(lib_symbols
	(symbol "antmicroBarrelPowerConnectors:BarrelJack_Pin1.3mm_694103107102"
			(pin_names
				(hide yes)
			)
			(exclude_from_sim no)
			(in_bom yes)
			(on_board yes)
			(property "Reference" "J"
				(at 15.24 -5.08 0)
				(effects
					(font
						(size 1.27 1.27)
						(thickness 0.15)
					)
					(justify left bottom)
				)
			)
			(property "Value" "BarrelJack_Pin1.3mm_694103107102"
				(at 15.24 -10.16 0)
				(effects
					(font
						(size 1.27 1.27)
						(thickness 0.15)
					)
					(justify left bottom)
					(hide yes)
				)
			)
			(property "Footprint" "antmicro-footprints:BarrelJack_Pin1.3mm_694103107102"
				(at 15.24 -12.7 0)
				(effects
					(font
						(size 1.27 1.27)
						(thickness 0.15)
					)
					(justify left bottom)
					(hide yes)
				)
			)
			(property "Datasheet" "https://www.we-online.de/katalog/datasheet/694103107102.pdf"
				(at 15.24 -15.24 0)
				(effects
					(font
						(size 1.27 1.27)
						(thickness 0.15)
					)
					(justify left bottom)
					(hide yes)
				)
			)
			(property "Description" "DC Power Connector, Jack, 5 A, 1.35 mm, PCB Mount, Surface Mount"
				(at 15.24 -27.94 0)
				(effects
					(font
						(size 1.27 1.27)
						(thickness 0.15)
					)
					(justify left bottom)
					(hide yes)
				)
			)
			(property "MPN" "694103107102"
				(at 15.24 -7.62 0)
				(effects
					(font
						(size 1.27 1.27)
						(thickness 0.15)
					)
					(justify left bottom)
				)
			)
			(property "Manufacturer" "Würth Elektronik"
				(at 15.24 -20.32 0)
				(effects
					(font
						(size 1.27 1.27)
						(thickness 0.15)
					)
					(justify left bottom)
					(hide yes)
				)
			)
			(property "Author" "Antmicro"
				(at 15.24 -22.86 0)
				(effects
					(font
						(size 1.27 1.27)
						(thickness 0.15)
					)
					(justify left bottom)
					(hide yes)
				)
			)
			(property "License" "Apache-2.0"
				(at 15.24 -25.4 0)
				(effects
					(font
						(size 1.27 1.27)
						(thickness 0.15)
					)
					(justify left bottom)
					(hide yes)
				)
			)
			(property "ki_keywords" "CONNECTOR"
				(at 0 0 0)
				(effects
					(font
						(size 1.27 1.27)
					)
					(hide yes)
				)
			)
			(symbol "BarrelJack_Pin1.3mm_694103107102_1_1"
				(rectangle
					(start -12.7 1.905)
					(end -2.54 -6.985)
					(stroke
						(width 0.254)
						(type default)
					)
					(fill
						(type background)
					)
				)
				(rectangle
					(start -8.255 0.635)
					(end -4.445 -0.635)
					(stroke
						(width 0.254)
						(type default)
					)
					(fill
						(type outline)
					)
				)
				(arc
					(start -8.255 -0.635)
					(mid -8.8873 0)
					(end -8.255 0.635)
					(stroke
						(width 0.254)
						(type default)
					)
					(fill
						(type outline)
					)
				)
				(polyline
					(pts
						(xy -6.35 -2.54) (xy -6.985 -2.54) (xy -6.35 -3.81) (xy -5.715 -2.54) (xy -6.35 -2.54)
					)
					(stroke
						(width 0.254)
						(type default)
					)
					(fill
						(type none)
					)
				)
				(rectangle
					(start -4.445 1.27)
					(end -3.81 -1.27)
					(stroke
						(width 0.254)
						(type default)
					)
					(fill
						(type none)
					)
				)
				(polyline
					(pts
						(xy -2.54 0) (xy -3.81 0)
					)
					(stroke
						(width 0.254)
						(type default)
					)
					(fill
						(type background)
					)
				)
				(polyline
					(pts
						(xy -2.54 -2.54) (xy -5.715 -2.54)
					)
					(stroke
						(width 0.254)
						(type default)
					)
					(fill
						(type background)
					)
				)
				(polyline
					(pts
						(xy -2.54 -5.08) (xy -7.62 -5.08) (xy -8.89 -3.81) (xy -10.16 -5.08)
					)
					(stroke
						(width 0.254)
						(type default)
					)
					(fill
						(type none)
					)
				)
				(pin passive line
					(at 0 0 180)
					(length 2.54)
					(name "1"
						(effects
							(font
								(size 1.27 1.27)
							)
						)
					)
					(number "1"
						(effects
							(font
								(size 1.27 1.27)
							)
						)
					)
				)
				(pin passive line
					(at 0 -2.54 180)
					(length 2.54)
					(name "3"
						(effects
							(font
								(size 1.27 1.27)
							)
						)
					)
					(number "3"
						(effects
							(font
								(size 1.27 1.27)
							)
						)
					)
				)
				(pin passive line
					(at 0 -5.08 180)
					(length 2.54)
					(name "2"
						(effects
							(font
								(size 1.27 1.27)
							)
						)
					)
					(number "2"
						(effects
							(font
								(size 1.27 1.27)
							)
						)
					)
				)
			)
		)
	(symbol "antmicroCapacitors0402:C_100n_0402"
			(pin_numbers
				(hide yes)
			)
			(pin_names
				(hide yes)
			)
			(exclude_from_sim no)
			(in_bom yes)
			(on_board yes)
			(property "Reference" "C"
				(at 20.32 -5.08 0)
				(effects
					(font
						(size 1.27 1.27)
						(thickness 0.15)
					)
					(justify left bottom)
				)
			)
			(property "Value" "C_100n_0402"
				(at 20.32 -10.16 0)
				(effects
					(font
						(size 1.27 1.27)
						(thickness 0.15)
					)
					(justify left bottom)
					(hide yes)
				)
			)
			(property "Footprint" "antmicro-footprints:C_0402_1005Metric"
				(at 20.32 -12.7 0)
				(effects
					(font
						(size 1.27 1.27)
						(thickness 0.15)
					)
					(justify left bottom)
					(hide yes)
				)
			)
			(property "Datasheet" "https://www.murata.com/products/productdetail?partno=GRM155R61H104KE14%23"
				(at 20.32 -15.24 0)
				(effects
					(font
						(size 1.27 1.27)
						(thickness 0.15)
					)
					(justify left bottom)
					(hide yes)
				)
			)
			(property "Description" "SMD Multilayer Ceramic Capacitor, 0.1 µF, 50 V, 0402 [1005 Metric], ± 10%, X5R, GRM Series"
				(at 20.32 -33.02 0)
				(effects
					(font
						(size 1.27 1.27)
					)
					(justify left bottom)
					(hide yes)
				)
			)
			(property "MPN" "GRM155R61H104KE14D"
				(at 20.32 -17.78 0)
				(effects
					(font
						(size 1.27 1.27)
						(thickness 0.15)
					)
					(justify left bottom)
					(hide yes)
				)
			)
			(property "Manufacturer" "Murata"
				(at 20.32 -20.32 0)
				(effects
					(font
						(size 1.27 1.27)
						(thickness 0.15)
					)
					(justify left bottom)
					(hide yes)
				)
			)
			(property "License" "Apache-2.0"
				(at 20.32 -22.86 0)
				(effects
					(font
						(size 1.27 1.27)
						(thickness 0.15)
					)
					(justify left bottom)
					(hide yes)
				)
			)
			(property "Author" "Antmicro"
				(at 20.32 -25.4 0)
				(effects
					(font
						(size 1.27 1.27)
						(thickness 0.15)
					)
					(justify left bottom)
					(hide yes)
				)
			)
			(property "Val" "100n"
				(at 20.32 -7.62 0)
				(effects
					(font
						(size 1.27 1.27)
						(thickness 0.15)
					)
					(justify left bottom)
				)
			)
			(property "Voltage" "50V"
				(at 20.32 -27.94 0)
				(effects
					(font
						(size 1.27 1.27)
					)
					(justify left bottom)
					(hide yes)
				)
			)
			(property "Dielectric" "X5R"
				(at 20.32 -30.48 0)
				(effects
					(font
						(size 1.27 1.27)
					)
					(justify left bottom)
					(hide yes)
				)
			)
			(property "ki_keywords" "0402, SMT, CAPACITOR, PASSIVE, CERAMIC, MLCC"
				(at 0 0 0)
				(effects
					(font
						(size 1.27 1.27)
					)
					(hide yes)
				)
			)
			(symbol "C_100n_0402_0_1"
				(polyline
					(pts
						(xy 2.032 -1.524) (xy 2.032 1.524)
					)
					(stroke
						(width 0.3048)
						(type default)
					)
					(fill
						(type none)
					)
				)
				(polyline
					(pts
						(xy 3.048 -1.524) (xy 3.048 1.524)
					)
					(stroke
						(width 0.3302)
						(type default)
					)
					(fill
						(type none)
					)
				)
			)
			(symbol "C_100n_0402_1_1"
				(pin passive line
					(at 0 0 0)
					(length 2.032)
					(name "~"
						(effects
							(font
								(size 1.27 1.27)
							)
						)
					)
					(number "1"
						(effects
							(font
								(size 1.27 1.27)
							)
						)
					)
				)
				(pin passive line
					(at 5.08 0 180)
					(length 2.032)
					(name "~"
						(effects
							(font
								(size 1.27 1.27)
							)
						)
					)
					(number "2"
						(effects
							(font
								(size 1.27 1.27)
							)
						)
					)
				)
			)
		)
	(symbol "antmicroCapacitors0402:C_10p_0402"
			(pin_numbers
				(hide yes)
			)
			(pin_names
				(hide yes)
			)
			(exclude_from_sim no)
			(in_bom yes)
			(on_board yes)
			(property "Reference" "C"
				(at 20.32 -5.08 0)
				(effects
					(font
						(size 1.27 1.27)
						(thickness 0.15)
					)
					(justify left bottom)
				)
			)
			(property "Value" "C_10p_0402"
				(at 20.32 -10.16 0)
				(effects
					(font
						(size 1.27 1.27)
						(thickness 0.15)
					)
					(justify left bottom)
					(hide yes)
				)
			)
			(property "Footprint" "antmicro-footprints:C_0402_1005Metric"
				(at 20.32 -12.7 0)
				(effects
					(font
						(size 1.27 1.27)
						(thickness 0.15)
					)
					(justify left bottom)
					(hide yes)
				)
			)
			(property "Datasheet" "https://www.murata.com/products/productdetail?partno=GCM1555C1H100GA16%23"
				(at 20.32 -15.24 0)
				(effects
					(font
						(size 1.27 1.27)
						(thickness 0.15)
					)
					(justify left bottom)
					(hide yes)
				)
			)
			(property "Description" "SMD Multilayer Ceramic Capacitor, 10 pF, 50 V, 0402 [1005 Metric], ± 2%, C0G / NP0, GCM"
				(at 20.32 -33.02 0)
				(effects
					(font
						(size 1.27 1.27)
					)
					(justify left bottom)
					(hide yes)
				)
			)
			(property "MPN" "GCM1555C1H100GA16D"
				(at 20.32 -17.78 0)
				(effects
					(font
						(size 1.27 1.27)
						(thickness 0.15)
					)
					(justify left bottom)
					(hide yes)
				)
			)
			(property "Manufacturer" "Murata"
				(at 20.32 -20.32 0)
				(effects
					(font
						(size 1.27 1.27)
						(thickness 0.15)
					)
					(justify left bottom)
					(hide yes)
				)
			)
			(property "License" "Apache-2.0"
				(at 20.32 -22.86 0)
				(effects
					(font
						(size 1.27 1.27)
						(thickness 0.15)
					)
					(justify left bottom)
					(hide yes)
				)
			)
			(property "Author" "Antmicro"
				(at 20.32 -25.4 0)
				(effects
					(font
						(size 1.27 1.27)
						(thickness 0.15)
					)
					(justify left bottom)
					(hide yes)
				)
			)
			(property "Val" "10p"
				(at 20.32 -7.62 0)
				(effects
					(font
						(size 1.27 1.27)
						(thickness 0.15)
					)
					(justify left bottom)
				)
			)
			(property "Voltage" "50V"
				(at 20.32 -27.94 0)
				(effects
					(font
						(size 1.27 1.27)
					)
					(justify left bottom)
					(hide yes)
				)
			)
			(property "Dielectric" "C0G"
				(at 20.32 -30.48 0)
				(effects
					(font
						(size 1.27 1.27)
					)
					(justify left bottom)
					(hide yes)
				)
			)
			(property "ki_keywords" "0402, SMT, CAPACITOR, PASSIVE"
				(at 0 0 0)
				(effects
					(font
						(size 1.27 1.27)
					)
					(hide yes)
				)
			)
			(symbol "C_10p_0402_0_1"
				(polyline
					(pts
						(xy 2.032 -1.524) (xy 2.032 1.524)
					)
					(stroke
						(width 0.3048)
						(type default)
					)
					(fill
						(type none)
					)
				)
				(polyline
					(pts
						(xy 3.048 -1.524) (xy 3.048 1.524)
					)
					(stroke
						(width 0.3302)
						(type default)
					)
					(fill
						(type none)
					)
				)
			)
			(symbol "C_10p_0402_1_1"
				(pin passive line
					(at 0 0 0)
					(length 2.032)
					(name "~"
						(effects
							(font
								(size 1.27 1.27)
							)
						)
					)
					(number "1"
						(effects
							(font
								(size 1.27 1.27)
							)
						)
					)
				)
				(pin passive line
					(at 5.08 0 180)
					(length 2.032)
					(name "~"
						(effects
							(font
								(size 1.27 1.27)
							)
						)
					)
					(number "2"
						(effects
							(font
								(size 1.27 1.27)
							)
						)
					)
				)
			)
		)
	(symbol "antmicroCapacitors0402:C_10p_25V_0402"
			(pin_numbers
				(hide yes)
			)
			(pin_names
				(hide yes)
			)
			(exclude_from_sim no)
			(in_bom yes)
			(on_board yes)
			(property "Reference" "C"
				(at 20.32 -5.08 0)
				(effects
					(font
						(size 1.27 1.27)
						(thickness 0.15)
					)
					(justify left bottom)
				)
			)
			(property "Value" "C_10p_25V_0402"
				(at 20.32 -10.16 0)
				(effects
					(font
						(size 1.27 1.27)
						(thickness 0.15)
					)
					(justify left bottom)
					(hide yes)
				)
			)
			(property "Footprint" "antmicro-footprints:C_0402_1005Metric"
				(at 20.32 -12.7 0)
				(effects
					(font
						(size 1.27 1.27)
						(thickness 0.15)
					)
					(justify left bottom)
					(hide yes)
				)
			)
			(property "Datasheet" "https://spicat.kyocera-avx.com/product/mlcc/chartview/04023A100FAT2A/"
				(at 20.32 -15.24 0)
				(effects
					(font
						(size 1.27 1.27)
						(thickness 0.15)
					)
					(justify left bottom)
					(hide yes)
				)
			)
			(property "Description" "Multilayer Ceramic Capacitors MLCC - SMD/SMT 25V 10pF C0G 0402 1%"
				(at 20.32 -33.02 0)
				(effects
					(font
						(size 1.27 1.27)
					)
					(justify left bottom)
					(hide yes)
				)
			)
			(property "MPN" "04023A100FAT2A"
				(at 20.32 -17.78 0)
				(effects
					(font
						(size 1.27 1.27)
						(thickness 0.15)
					)
					(justify left bottom)
					(hide yes)
				)
			)
			(property "Manufacturer" "KYOCERA AVX"
				(at 20.32 -20.32 0)
				(effects
					(font
						(size 1.27 1.27)
						(thickness 0.15)
					)
					(justify left bottom)
					(hide yes)
				)
			)
			(property "License" "Apache-2.0"
				(at 20.32 -22.86 0)
				(effects
					(font
						(size 1.27 1.27)
						(thickness 0.15)
					)
					(justify left bottom)
					(hide yes)
				)
			)
			(property "Author" "Antmicro"
				(at 20.32 -25.4 0)
				(effects
					(font
						(size 1.27 1.27)
						(thickness 0.15)
					)
					(justify left bottom)
					(hide yes)
				)
			)
			(property "Val" "10p"
				(at 20.32 -7.62 0)
				(effects
					(font
						(size 1.27 1.27)
						(thickness 0.15)
					)
					(justify left bottom)
				)
			)
			(property "Voltage" "25V"
				(at 20.32 -27.94 0)
				(effects
					(font
						(size 1.27 1.27)
					)
					(justify left bottom)
					(hide yes)
				)
			)
			(property "Dielectric" "C0G"
				(at 20.32 -30.48 0)
				(effects
					(font
						(size 1.27 1.27)
					)
					(justify left bottom)
					(hide yes)
				)
			)
			(property "ki_keywords" "0402, SMT, CAPACITOR, PASSIVE"
				(at 0 0 0)
				(effects
					(font
						(size 1.27 1.27)
					)
					(hide yes)
				)
			)
			(symbol "C_10p_25V_0402_0_1"
				(polyline
					(pts
						(xy 2.032 -1.524) (xy 2.032 1.524)
					)
					(stroke
						(width 0.3048)
						(type default)
					)
					(fill
						(type none)
					)
				)
				(polyline
					(pts
						(xy 3.048 -1.524) (xy 3.048 1.524)
					)
					(stroke
						(width 0.3302)
						(type default)
					)
					(fill
						(type none)
					)
				)
			)
			(symbol "C_10p_25V_0402_1_1"
				(pin passive line
					(at 0 0 0)
					(length 2.032)
					(name "~"
						(effects
							(font
								(size 1.27 1.27)
							)
						)
					)
					(number "1"
						(effects
							(font
								(size 1.27 1.27)
							)
						)
					)
				)
				(pin passive line
					(at 5.08 0 180)
					(length 2.032)
					(name "~"
						(effects
							(font
								(size 1.27 1.27)
							)
						)
					)
					(number "2"
						(effects
							(font
								(size 1.27 1.27)
							)
						)
					)
				)
			)
		)
	(symbol "antmicroCapacitors0402:C_10u_0402"
			(pin_numbers
				(hide yes)
			)
			(pin_names
				(hide yes)
			)
			(exclude_from_sim no)
			(in_bom yes)
			(on_board yes)
			(property "Reference" "C"
				(at 20.32 -5.08 0)
				(effects
					(font
						(size 1.27 1.27)
						(thickness 0.15)
					)
					(justify left bottom)
				)
			)
			(property "Value" "C_10u_0402"
				(at 20.32 -10.16 0)
				(effects
					(font
						(size 1.27 1.27)
						(thickness 0.15)
					)
					(justify left bottom)
					(hide yes)
				)
			)
			(property "Footprint" "antmicro-footprints:C_0402_1005Metric"
				(at 20.32 -12.7 0)
				(effects
					(font
						(size 1.27 1.27)
						(thickness 0.15)
					)
					(justify left bottom)
					(hide yes)
				)
			)
			(property "Datasheet" "https://www.yageo.com/en/Chart/Download/pdf/CC0402MRX5R5BB106"
				(at 20.32 -15.24 0)
				(effects
					(font
						(size 1.27 1.27)
						(thickness 0.15)
					)
					(justify left bottom)
					(hide yes)
				)
			)
			(property "Description" "SMD Multilayer Ceramic Capacitor, 10 µF, 6.3 V, 0402 [1005 Metric], ± 20%, X5R, CC Series"
				(at 20.32 -33.02 0)
				(effects
					(font
						(size 1.27 1.27)
					)
					(justify left bottom)
					(hide yes)
				)
			)
			(property "MPN" "CC0402MRX5R5BB106"
				(at 20.32 -17.78 0)
				(effects
					(font
						(size 1.27 1.27)
						(thickness 0.15)
					)
					(justify left bottom)
					(hide yes)
				)
			)
			(property "Manufacturer" "YAGEO"
				(at 20.32 -20.32 0)
				(effects
					(font
						(size 1.27 1.27)
						(thickness 0.15)
					)
					(justify left bottom)
					(hide yes)
				)
			)
			(property "License" "Apache-2.0"
				(at 20.32 -22.86 0)
				(effects
					(font
						(size 1.27 1.27)
						(thickness 0.15)
					)
					(justify left bottom)
					(hide yes)
				)
			)
			(property "Author" "Antmicro"
				(at 20.32 -25.4 0)
				(effects
					(font
						(size 1.27 1.27)
						(thickness 0.15)
					)
					(justify left bottom)
					(hide yes)
				)
			)
			(property "Val" "10u"
				(at 20.32 -7.62 0)
				(effects
					(font
						(size 1.27 1.27)
						(thickness 0.15)
					)
					(justify left bottom)
				)
			)
			(property "Voltage" ""
				(at 20.32 -27.94 0)
				(effects
					(font
						(size 1.27 1.27)
					)
					(justify left bottom)
					(hide yes)
				)
			)
			(property "Dielectric" ""
				(at 20.32 -30.48 0)
				(effects
					(font
						(size 1.27 1.27)
					)
					(justify left bottom)
					(hide yes)
				)
			)
			(property "ki_keywords" "0402, SMT, CAPACITOR, PASSIVE, MLCC, CERAMIC"
				(at 0 0 0)
				(effects
					(font
						(size 1.27 1.27)
					)
					(hide yes)
				)
			)
			(symbol "C_10u_0402_0_1"
				(polyline
					(pts
						(xy 2.032 -1.524) (xy 2.032 1.524)
					)
					(stroke
						(width 0.3048)
						(type default)
					)
					(fill
						(type none)
					)
				)
				(polyline
					(pts
						(xy 3.048 -1.524) (xy 3.048 1.524)
					)
					(stroke
						(width 0.3302)
						(type default)
					)
					(fill
						(type none)
					)
				)
			)
			(symbol "C_10u_0402_1_1"
				(pin passive line
					(at 0 0 0)
					(length 2.032)
					(name "~"
						(effects
							(font
								(size 1.27 1.27)
							)
						)
					)
					(number "1"
						(effects
							(font
								(size 1.27 1.27)
							)
						)
					)
				)
				(pin passive line
					(at 5.08 0 180)
					(length 2.032)
					(name "~"
						(effects
							(font
								(size 1.27 1.27)
							)
						)
					)
					(number "2"
						(effects
							(font
								(size 1.27 1.27)
							)
						)
					)
				)
			)
		)
	(symbol "antmicroCapacitors0402:C_1u_0402"
			(pin_numbers
				(hide yes)
			)
			(pin_names
				(hide yes)
			)
			(exclude_from_sim no)
			(in_bom yes)
			(on_board yes)
			(property "Reference" "C"
				(at 20.32 -5.08 0)
				(effects
					(font
						(size 1.27 1.27)
						(thickness 0.15)
					)
					(justify left bottom)
				)
			)
			(property "Value" "C_1u_0402"
				(at 20.32 -10.16 0)
				(effects
					(font
						(size 1.27 1.27)
						(thickness 0.15)
					)
					(justify left bottom)
					(hide yes)
				)
			)
			(property "Footprint" "antmicro-footprints:C_0402_1005Metric"
				(at 20.32 -12.7 0)
				(effects
					(font
						(size 1.27 1.27)
						(thickness 0.15)
					)
					(justify left bottom)
					(hide yes)
				)
			)
			(property "Datasheet" "https://product.tdk.com/en/search/capacitor/ceramic/mlcc/info?part_no=C1005X6S1A105K050BC"
				(at 20.32 -15.24 0)
				(effects
					(font
						(size 1.27 1.27)
						(thickness 0.15)
					)
					(justify left bottom)
					(hide yes)
				)
			)
			(property "Description" "SMD Multilayer Ceramic Capacitor, 1 µF, 10 V, 0402 [1005 Metric], ± 10%, X6S, C"
				(at 20.32 -33.02 0)
				(effects
					(font
						(size 1.27 1.27)
					)
					(justify left bottom)
					(hide yes)
				)
			)
			(property "MPN" "C1005X6S1A105K050BC"
				(at 20.32 -17.78 0)
				(effects
					(font
						(size 1.27 1.27)
						(thickness 0.15)
					)
					(justify left bottom)
					(hide yes)
				)
			)
			(property "Manufacturer" "TDK"
				(at 20.32 -20.32 0)
				(effects
					(font
						(size 1.27 1.27)
						(thickness 0.15)
					)
					(justify left bottom)
					(hide yes)
				)
			)
			(property "License" "Apache-2.0"
				(at 20.32 -22.86 0)
				(effects
					(font
						(size 1.27 1.27)
						(thickness 0.15)
					)
					(justify left bottom)
					(hide yes)
				)
			)
			(property "Author" "Antmicro"
				(at 20.32 -25.4 0)
				(effects
					(font
						(size 1.27 1.27)
						(thickness 0.15)
					)
					(justify left bottom)
					(hide yes)
				)
			)
			(property "Val" "1u"
				(at 20.32 -7.62 0)
				(effects
					(font
						(size 1.27 1.27)
						(thickness 0.15)
					)
					(justify left bottom)
				)
			)
			(property "Voltage" ""
				(at 20.32 -27.94 0)
				(effects
					(font
						(size 1.27 1.27)
					)
					(justify left bottom)
					(hide yes)
				)
			)
			(property "Dielectric" ""
				(at 20.32 -30.48 0)
				(effects
					(font
						(size 1.27 1.27)
					)
					(justify left bottom)
					(hide yes)
				)
			)
			(property "ki_keywords" "0402, SMT, CAPACITOR, PASSIVE, CERAMIC, MLCC"
				(at 0 0 0)
				(effects
					(font
						(size 1.27 1.27)
					)
					(hide yes)
				)
			)
			(symbol "C_1u_0402_0_1"
				(polyline
					(pts
						(xy 2.032 -1.524) (xy 2.032 1.524)
					)
					(stroke
						(width 0.3048)
						(type default)
					)
					(fill
						(type none)
					)
				)
				(polyline
					(pts
						(xy 3.048 -1.524) (xy 3.048 1.524)
					)
					(stroke
						(width 0.3302)
						(type default)
					)
					(fill
						(type none)
					)
				)
			)
			(symbol "C_1u_0402_1_1"
				(pin passive line
					(at 0 0 0)
					(length 2.032)
					(name "~"
						(effects
							(font
								(size 1.27 1.27)
							)
						)
					)
					(number "1"
						(effects
							(font
								(size 1.27 1.27)
							)
						)
					)
				)
				(pin passive line
					(at 5.08 0 180)
					(length 2.032)
					(name "~"
						(effects
							(font
								(size 1.27 1.27)
							)
						)
					)
					(number "2"
						(effects
							(font
								(size 1.27 1.27)
							)
						)
					)
				)
			)
		)
	(symbol "antmicroCapacitors0402:C_1u_25V_0402"
			(pin_numbers
				(hide yes)
			)
			(pin_names
				(hide yes)
			)
			(exclude_from_sim no)
			(in_bom yes)
			(on_board yes)
			(property "Reference" "C"
				(at 20.32 -5.08 0)
				(effects
					(font
						(size 1.27 1.27)
						(thickness 0.15)
					)
					(justify left bottom)
				)
			)
			(property "Value" "C_1u_25V_0402"
				(at 20.32 -10.16 0)
				(effects
					(font
						(size 1.27 1.27)
						(thickness 0.15)
					)
					(justify left bottom)
					(hide yes)
				)
			)
			(property "Footprint" "antmicro-footprints:C_0402_1005Metric"
				(at 20.32 -12.7 0)
				(effects
					(font
						(size 1.27 1.27)
						(thickness 0.15)
					)
					(justify left bottom)
					(hide yes)
				)
			)
			(property "Datasheet" "https://www.murata.com/products/productdetail?partno=GRM155R61E105KE11%23"
				(at 20.32 -15.24 0)
				(effects
					(font
						(size 1.27 1.27)
						(thickness 0.15)
					)
					(justify left bottom)
					(hide yes)
				)
			)
			(property "Description" "SMD Multilayer Ceramic Capacitor, 1 µF, 25 V, 0402 [1005 Metric], ± 10%, X5R, GRM Series"
				(at 20.32 -33.02 0)
				(effects
					(font
						(size 1.27 1.27)
					)
					(justify left bottom)
					(hide yes)
				)
			)
			(property "MPN" "GRM155R61E105KE11J"
				(at 20.32 -17.78 0)
				(effects
					(font
						(size 1.27 1.27)
						(thickness 0.15)
					)
					(justify left bottom)
					(hide yes)
				)
			)
			(property "Manufacturer" "Murata"
				(at 20.32 -20.32 0)
				(effects
					(font
						(size 1.27 1.27)
						(thickness 0.15)
					)
					(justify left bottom)
					(hide yes)
				)
			)
			(property "License" "Apache-2.0"
				(at 20.32 -22.86 0)
				(effects
					(font
						(size 1.27 1.27)
						(thickness 0.15)
					)
					(justify left bottom)
					(hide yes)
				)
			)
			(property "Author" "Antmicro"
				(at 20.32 -25.4 0)
				(effects
					(font
						(size 1.27 1.27)
						(thickness 0.15)
					)
					(justify left bottom)
					(hide yes)
				)
			)
			(property "Val" "1u"
				(at 20.32 -7.62 0)
				(effects
					(font
						(size 1.27 1.27)
						(thickness 0.15)
					)
					(justify left bottom)
				)
			)
			(property "Voltage" "25V"
				(at 20.32 -27.94 0)
				(effects
					(font
						(size 1.27 1.27)
					)
					(justify left bottom)
					(hide yes)
				)
			)
			(property "Dielectric" "X5R"
				(at 20.32 -30.48 0)
				(effects
					(font
						(size 1.27 1.27)
					)
					(justify left bottom)
					(hide yes)
				)
			)
			(property "ki_keywords" "0402, SMT, CAPACITOR, PASSIVE, CERAMIC"
				(at 0 0 0)
				(effects
					(font
						(size 1.27 1.27)
					)
					(hide yes)
				)
			)
			(symbol "C_1u_25V_0402_0_1"
				(polyline
					(pts
						(xy 2.032 -1.524) (xy 2.032 1.524)
					)
					(stroke
						(width 0.3048)
						(type default)
					)
					(fill
						(type none)
					)
				)
				(polyline
					(pts
						(xy 3.048 -1.524) (xy 3.048 1.524)
					)
					(stroke
						(width 0.3302)
						(type default)
					)
					(fill
						(type none)
					)
				)
			)
			(symbol "C_1u_25V_0402_1_1"
				(pin passive line
					(at 0 0 0)
					(length 2.032)
					(name "~"
						(effects
							(font
								(size 1.27 1.27)
							)
						)
					)
					(number "1"
						(effects
							(font
								(size 1.27 1.27)
							)
						)
					)
				)
				(pin passive line
					(at 5.08 0 180)
					(length 2.032)
					(name "~"
						(effects
							(font
								(size 1.27 1.27)
							)
						)
					)
					(number "2"
						(effects
							(font
								(size 1.27 1.27)
							)
						)
					)
				)
			)
		)
	(symbol "antmicroCapacitors0402:C_220n_0402"
			(pin_numbers
				(hide yes)
			)
			(pin_names
				(hide yes)
			)
			(exclude_from_sim no)
			(in_bom yes)
			(on_board yes)
			(property "Reference" "C"
				(at 20.32 -5.08 0)
				(effects
					(font
						(size 1.27 1.27)
						(thickness 0.15)
					)
					(justify left bottom)
				)
			)
			(property "Value" "C_220n_0402"
				(at 20.32 -10.16 0)
				(effects
					(font
						(size 1.27 1.27)
						(thickness 0.15)
					)
					(justify left bottom)
					(hide yes)
				)
			)
			(property "Footprint" "antmicro-footprints:C_0402_1005Metric"
				(at 20.32 -12.7 0)
				(effects
					(font
						(size 1.27 1.27)
						(thickness 0.15)
					)
					(justify left bottom)
					(hide yes)
				)
			)
			(property "Datasheet" "https://www.yageo.com/en/Chart/Download/pdf/CC0402KRX5R6BB224"
				(at 20.32 -15.24 0)
				(effects
					(font
						(size 1.27 1.27)
						(thickness 0.15)
					)
					(justify left bottom)
					(hide yes)
				)
			)
			(property "Description" "SMD Multilayer Ceramic Capacitor, 0.22 µF, 10 V, 0402 [1005 Metric], ± 10%, X5R, CC Series"
				(at 20.32 -33.02 0)
				(effects
					(font
						(size 1.27 1.27)
					)
					(justify left bottom)
					(hide yes)
				)
			)
			(property "MPN" "CC0402KRX5R6BB224"
				(at 20.32 -17.78 0)
				(effects
					(font
						(size 1.27 1.27)
						(thickness 0.15)
					)
					(justify left bottom)
					(hide yes)
				)
			)
			(property "Manufacturer" "YAGEO"
				(at 20.32 -20.32 0)
				(effects
					(font
						(size 1.27 1.27)
						(thickness 0.15)
					)
					(justify left bottom)
					(hide yes)
				)
			)
			(property "License" "Apache-2.0"
				(at 20.32 -22.86 0)
				(effects
					(font
						(size 1.27 1.27)
						(thickness 0.15)
					)
					(justify left bottom)
					(hide yes)
				)
			)
			(property "Author" "Antmicro"
				(at 20.32 -25.4 0)
				(effects
					(font
						(size 1.27 1.27)
						(thickness 0.15)
					)
					(justify left bottom)
					(hide yes)
				)
			)
			(property "Val" "220n"
				(at 20.32 -7.62 0)
				(effects
					(font
						(size 1.27 1.27)
						(thickness 0.15)
					)
					(justify left bottom)
				)
			)
			(property "Voltage" ""
				(at 20.32 -27.94 0)
				(effects
					(font
						(size 1.27 1.27)
					)
					(justify left bottom)
					(hide yes)
				)
			)
			(property "Dielectric" ""
				(at 20.32 -30.48 0)
				(effects
					(font
						(size 1.27 1.27)
					)
					(justify left bottom)
					(hide yes)
				)
			)
			(property "ki_keywords" "0402, SMT, CAPACITOR, PASSIVE, MLCC, CERAMIC"
				(at 0 0 0)
				(effects
					(font
						(size 1.27 1.27)
					)
					(hide yes)
				)
			)
			(symbol "C_220n_0402_0_1"
				(polyline
					(pts
						(xy 2.032 -1.524) (xy 2.032 1.524)
					)
					(stroke
						(width 0.3048)
						(type default)
					)
					(fill
						(type none)
					)
				)
				(polyline
					(pts
						(xy 3.048 -1.524) (xy 3.048 1.524)
					)
					(stroke
						(width 0.3302)
						(type default)
					)
					(fill
						(type none)
					)
				)
			)
			(symbol "C_220n_0402_1_1"
				(pin passive line
					(at 0 0 0)
					(length 2.032)
					(name "~"
						(effects
							(font
								(size 1.27 1.27)
							)
						)
					)
					(number "1"
						(effects
							(font
								(size 1.27 1.27)
							)
						)
					)
				)
				(pin passive line
					(at 5.08 0 180)
					(length 2.032)
					(name "~"
						(effects
							(font
								(size 1.27 1.27)
							)
						)
					)
					(number "2"
						(effects
							(font
								(size 1.27 1.27)
							)
						)
					)
				)
			)
		)
	(symbol "antmicroCapacitors0402:C_220n_16V_0402"
			(pin_numbers
				(hide yes)
			)
			(pin_names
				(hide yes)
			)
			(exclude_from_sim no)
			(in_bom yes)
			(on_board yes)
			(property "Reference" "C"
				(at 20.32 -5.08 0)
				(effects
					(font
						(size 1.27 1.27)
						(thickness 0.15)
					)
					(justify left bottom)
				)
			)
			(property "Value" "C_220n_16V_0402"
				(at 20.32 -10.16 0)
				(effects
					(font
						(size 1.27 1.27)
						(thickness 0.15)
					)
					(justify left bottom)
					(hide yes)
				)
			)
			(property "Footprint" "antmicro-footprints:C_0402_1005Metric"
				(at 20.32 -12.7 0)
				(effects
					(font
						(size 1.27 1.27)
						(thickness 0.15)
					)
					(justify left bottom)
					(hide yes)
				)
			)
			(property "Datasheet" "https://www.murata.com/products/productdetail?partno=GRM155R71C224KA12%23"
				(at 20.32 -15.24 0)
				(effects
					(font
						(size 1.27 1.27)
						(thickness 0.15)
					)
					(justify left bottom)
					(hide yes)
				)
			)
			(property "Description" "SMD Multilayer Ceramic Capacitor, 0.22 µF, 16 V, 0402 [1005 Metric], ± 10%, X7R, GRM Series"
				(at 20.32 -33.02 0)
				(effects
					(font
						(size 1.27 1.27)
					)
					(justify left bottom)
					(hide yes)
				)
			)
			(property "MPN" "GRM155R71C224KA12D"
				(at 20.32 -17.78 0)
				(effects
					(font
						(size 1.27 1.27)
						(thickness 0.15)
					)
					(justify left bottom)
					(hide yes)
				)
			)
			(property "Manufacturer" "Murata"
				(at 20.32 -20.32 0)
				(effects
					(font
						(size 1.27 1.27)
						(thickness 0.15)
					)
					(justify left bottom)
					(hide yes)
				)
			)
			(property "License" "Apache-2.0"
				(at 20.32 -22.86 0)
				(effects
					(font
						(size 1.27 1.27)
						(thickness 0.15)
					)
					(justify left bottom)
					(hide yes)
				)
			)
			(property "Author" "Antmicro"
				(at 20.32 -25.4 0)
				(effects
					(font
						(size 1.27 1.27)
						(thickness 0.15)
					)
					(justify left bottom)
					(hide yes)
				)
			)
			(property "Val" "220n"
				(at 20.32 -7.62 0)
				(effects
					(font
						(size 1.27 1.27)
						(thickness 0.15)
					)
					(justify left bottom)
				)
			)
			(property "Voltage" "16V"
				(at 20.32 -27.94 0)
				(effects
					(font
						(size 1.27 1.27)
					)
					(justify left bottom)
					(hide yes)
				)
			)
			(property "Dielectric" "X7R"
				(at 20.32 -30.48 0)
				(effects
					(font
						(size 1.27 1.27)
					)
					(justify left bottom)
					(hide yes)
				)
			)
			(property "ki_keywords" "0402, SMT, CAPACITOR, PASSIVE, CERAMIC"
				(at 0 0 0)
				(effects
					(font
						(size 1.27 1.27)
					)
					(hide yes)
				)
			)
			(symbol "C_220n_16V_0402_0_1"
				(polyline
					(pts
						(xy 2.032 -1.524) (xy 2.032 1.524)
					)
					(stroke
						(width 0.3048)
						(type default)
					)
					(fill
						(type none)
					)
				)
				(polyline
					(pts
						(xy 3.048 -1.524) (xy 3.048 1.524)
					)
					(stroke
						(width 0.3302)
						(type default)
					)
					(fill
						(type none)
					)
				)
			)
			(symbol "C_220n_16V_0402_1_1"
				(pin passive line
					(at 0 0 0)
					(length 2.032)
					(name "~"
						(effects
							(font
								(size 1.27 1.27)
							)
						)
					)
					(number "1"
						(effects
							(font
								(size 1.27 1.27)
							)
						)
					)
				)
				(pin passive line
					(at 5.08 0 180)
					(length 2.032)
					(name "~"
						(effects
							(font
								(size 1.27 1.27)
							)
						)
					)
					(number "2"
						(effects
							(font
								(size 1.27 1.27)
							)
						)
					)
				)
			)
		)
	(symbol "antmicroCapacitors0402:C_220p_0402"
			(pin_numbers
				(hide yes)
			)
			(pin_names
				(hide yes)
			)
			(exclude_from_sim no)
			(in_bom yes)
			(on_board yes)
			(property "Reference" "C"
				(at 20.32 -5.08 0)
				(effects
					(font
						(size 1.27 1.27)
						(thickness 0.15)
					)
					(justify left bottom)
				)
			)
			(property "Value" "C_220p_0402"
				(at 20.32 -10.16 0)
				(effects
					(font
						(size 1.27 1.27)
						(thickness 0.15)
					)
					(justify left bottom)
					(hide yes)
				)
			)
			(property "Footprint" "antmicro-footprints:C_0402_1005Metric"
				(at 20.32 -12.7 0)
				(effects
					(font
						(size 1.27 1.27)
						(thickness 0.15)
					)
					(justify left bottom)
					(hide yes)
				)
			)
			(property "Datasheet" "https://spicat.kyocera-avx.com/product/mlcc/chartview/04025C221JAT2A/"
				(at 20.32 -15.24 0)
				(effects
					(font
						(size 1.27 1.27)
						(thickness 0.15)
					)
					(justify left bottom)
					(hide yes)
				)
			)
			(property "Description" "SMD Multilayer Ceramic Capacitor, 220 pF, 50 V, 0402 [1005 Metric], ± 10%, X7R, MC"
				(at 20.32 -33.02 0)
				(effects
					(font
						(size 1.27 1.27)
					)
					(justify left bottom)
					(hide yes)
				)
			)
			(property "MPN" "04025C221JAT2A"
				(at 20.32 -17.78 0)
				(effects
					(font
						(size 1.27 1.27)
						(thickness 0.15)
					)
					(justify left bottom)
					(hide yes)
				)
			)
			(property "Manufacturer" "KYOCERA AVX"
				(at 20.32 -20.32 0)
				(effects
					(font
						(size 1.27 1.27)
						(thickness 0.15)
					)
					(justify left bottom)
					(hide yes)
				)
			)
			(property "License" "Apache-2.0"
				(at 20.32 -22.86 0)
				(effects
					(font
						(size 1.27 1.27)
						(thickness 0.15)
					)
					(justify left bottom)
					(hide yes)
				)
			)
			(property "Author" "Antmicro"
				(at 20.32 -25.4 0)
				(effects
					(font
						(size 1.27 1.27)
						(thickness 0.15)
					)
					(justify left bottom)
					(hide yes)
				)
			)
			(property "Val" "220p"
				(at 20.32 -7.62 0)
				(effects
					(font
						(size 1.27 1.27)
						(thickness 0.15)
					)
					(justify left bottom)
				)
			)
			(property "Voltage" ""
				(at 20.32 -27.94 0)
				(effects
					(font
						(size 1.27 1.27)
					)
					(justify left bottom)
					(hide yes)
				)
			)
			(property "Dielectric" ""
				(at 20.32 -30.48 0)
				(effects
					(font
						(size 1.27 1.27)
					)
					(justify left bottom)
					(hide yes)
				)
			)
			(property "ki_keywords" "0402, SMT, CAPACITOR, PASSIVE"
				(at 0 0 0)
				(effects
					(font
						(size 1.27 1.27)
					)
					(hide yes)
				)
			)
			(symbol "C_220p_0402_0_1"
				(polyline
					(pts
						(xy 2.032 -1.524) (xy 2.032 1.524)
					)
					(stroke
						(width 0.3048)
						(type default)
					)
					(fill
						(type none)
					)
				)
				(polyline
					(pts
						(xy 3.048 -1.524) (xy 3.048 1.524)
					)
					(stroke
						(width 0.3302)
						(type default)
					)
					(fill
						(type none)
					)
				)
			)
			(symbol "C_220p_0402_1_1"
				(pin passive line
					(at 0 0 0)
					(length 2.032)
					(name "~"
						(effects
							(font
								(size 1.27 1.27)
							)
						)
					)
					(number "1"
						(effects
							(font
								(size 1.27 1.27)
							)
						)
					)
				)
				(pin passive line
					(at 5.08 0 180)
					(length 2.032)
					(name "~"
						(effects
							(font
								(size 1.27 1.27)
							)
						)
					)
					(number "2"
						(effects
							(font
								(size 1.27 1.27)
							)
						)
					)
				)
			)
		)
	(symbol "antmicroCapacitors0402:C_2u2_0402"
			(pin_numbers
				(hide yes)
			)
			(pin_names
				(hide yes)
			)
			(exclude_from_sim no)
			(in_bom yes)
			(on_board yes)
			(property "Reference" "C"
				(at 20.32 -5.08 0)
				(effects
					(font
						(size 1.27 1.27)
						(thickness 0.15)
					)
					(justify left bottom)
				)
			)
			(property "Value" "C_2u2_0402"
				(at 20.32 -10.16 0)
				(effects
					(font
						(size 1.27 1.27)
						(thickness 0.15)
					)
					(justify left bottom)
					(hide yes)
				)
			)
			(property "Footprint" "antmicro-footprints:C_0402_1005Metric"
				(at 20.32 -12.7 0)
				(effects
					(font
						(size 1.27 1.27)
						(thickness 0.15)
					)
					(justify left bottom)
					(hide yes)
				)
			)
			(property "Datasheet" "https://product.tdk.com/en/search/capacitor/ceramic/mlcc/info?part_no=C1005X5R1A225K050BC"
				(at 20.32 -15.24 0)
				(effects
					(font
						(size 1.27 1.27)
						(thickness 0.15)
					)
					(justify left bottom)
					(hide yes)
				)
			)
			(property "Description" "SMD Multilayer Ceramic Capacitor, 2.2 µF, 10 V, 0402 [1005 Metric], ± 10%, X5R, C"
				(at 20.32 -33.02 0)
				(effects
					(font
						(size 1.27 1.27)
					)
					(justify left bottom)
					(hide yes)
				)
			)
			(property "MPN" "C1005X5R1A225K050BC"
				(at 20.32 -17.78 0)
				(effects
					(font
						(size 1.27 1.27)
						(thickness 0.15)
					)
					(justify left bottom)
					(hide yes)
				)
			)
			(property "Manufacturer" "TDK"
				(at 20.32 -20.32 0)
				(effects
					(font
						(size 1.27 1.27)
						(thickness 0.15)
					)
					(justify left bottom)
					(hide yes)
				)
			)
			(property "License" "Apache-2.0"
				(at 20.32 -22.86 0)
				(effects
					(font
						(size 1.27 1.27)
						(thickness 0.15)
					)
					(justify left bottom)
					(hide yes)
				)
			)
			(property "Author" "Antmicro"
				(at 20.32 -25.4 0)
				(effects
					(font
						(size 1.27 1.27)
						(thickness 0.15)
					)
					(justify left bottom)
					(hide yes)
				)
			)
			(property "Val" "2u2"
				(at 20.32 -7.62 0)
				(effects
					(font
						(size 1.27 1.27)
						(thickness 0.15)
					)
					(justify left bottom)
				)
			)
			(property "Voltage" ""
				(at 20.32 -27.94 0)
				(effects
					(font
						(size 1.27 1.27)
					)
					(justify left bottom)
					(hide yes)
				)
			)
			(property "Dielectric" ""
				(at 20.32 -30.48 0)
				(effects
					(font
						(size 1.27 1.27)
					)
					(justify left bottom)
					(hide yes)
				)
			)
			(property "ki_keywords" "0402, SMT, CAPACITOR, PASSIVE, CERAMIC, MLCC"
				(at 0 0 0)
				(effects
					(font
						(size 1.27 1.27)
					)
					(hide yes)
				)
			)
			(symbol "C_2u2_0402_0_1"
				(polyline
					(pts
						(xy 2.032 -1.524) (xy 2.032 1.524)
					)
					(stroke
						(width 0.3048)
						(type default)
					)
					(fill
						(type none)
					)
				)
				(polyline
					(pts
						(xy 3.048 -1.524) (xy 3.048 1.524)
					)
					(stroke
						(width 0.3302)
						(type default)
					)
					(fill
						(type none)
					)
				)
			)
			(symbol "C_2u2_0402_1_1"
				(pin passive line
					(at 0 0 0)
					(length 2.032)
					(name "~"
						(effects
							(font
								(size 1.27 1.27)
							)
						)
					)
					(number "1"
						(effects
							(font
								(size 1.27 1.27)
							)
						)
					)
				)
				(pin passive line
					(at 5.08 0 180)
					(length 2.032)
					(name "~"
						(effects
							(font
								(size 1.27 1.27)
							)
						)
					)
					(number "2"
						(effects
							(font
								(size 1.27 1.27)
							)
						)
					)
				)
			)
		)
	(symbol "antmicroCapacitors0402:C_33p_0402"
			(pin_numbers
				(hide yes)
			)
			(pin_names
				(hide yes)
			)
			(exclude_from_sim no)
			(in_bom yes)
			(on_board yes)
			(property "Reference" "C"
				(at 20.32 -5.08 0)
				(effects
					(font
						(size 1.27 1.27)
						(thickness 0.15)
					)
					(justify left bottom)
				)
			)
			(property "Value" "C_33p_0402"
				(at 20.32 -10.16 0)
				(effects
					(font
						(size 1.27 1.27)
						(thickness 0.15)
					)
					(justify left bottom)
					(hide yes)
				)
			)
			(property "Footprint" "antmicro-footprints:C_0402_1005Metric"
				(at 20.32 -12.7 0)
				(effects
					(font
						(size 1.27 1.27)
						(thickness 0.15)
					)
					(justify left bottom)
					(hide yes)
				)
			)
			(property "Datasheet" "https://spicat.kyocera-avx.com/product/mlcc/chartview/04025A330FAT2A/"
				(at 20.32 -15.24 0)
				(effects
					(font
						(size 1.27 1.27)
						(thickness 0.15)
					)
					(justify left bottom)
					(hide yes)
				)
			)
			(property "Description" "SMD Multilayer Ceramic Capacitor, 33 pF, 50 V, 0402 [1005 Metric], ± 5%, C0G / NP0, MC"
				(at 20.32 -33.02 0)
				(effects
					(font
						(size 1.27 1.27)
					)
					(justify left bottom)
					(hide yes)
				)
			)
			(property "MPN" "04025A330FAT2A"
				(at 20.32 -17.78 0)
				(effects
					(font
						(size 1.27 1.27)
						(thickness 0.15)
					)
					(justify left bottom)
					(hide yes)
				)
			)
			(property "Manufacturer" "KYOCERA AVX"
				(at 20.32 -20.32 0)
				(effects
					(font
						(size 1.27 1.27)
						(thickness 0.15)
					)
					(justify left bottom)
					(hide yes)
				)
			)
			(property "License" "Apache-2.0"
				(at 20.32 -22.86 0)
				(effects
					(font
						(size 1.27 1.27)
						(thickness 0.15)
					)
					(justify left bottom)
					(hide yes)
				)
			)
			(property "Author" "Antmicro"
				(at 20.32 -25.4 0)
				(effects
					(font
						(size 1.27 1.27)
						(thickness 0.15)
					)
					(justify left bottom)
					(hide yes)
				)
			)
			(property "Val" "33p"
				(at 20.32 -7.62 0)
				(effects
					(font
						(size 1.27 1.27)
						(thickness 0.15)
					)
					(justify left bottom)
				)
			)
			(property "Voltage" ""
				(at 20.32 -27.94 0)
				(effects
					(font
						(size 1.27 1.27)
					)
					(justify left bottom)
					(hide yes)
				)
			)
			(property "Dielectric" ""
				(at 20.32 -30.48 0)
				(effects
					(font
						(size 1.27 1.27)
					)
					(justify left bottom)
					(hide yes)
				)
			)
			(property "ki_keywords" "0402, SMT, CAPACITOR, PASSIVE"
				(at 0 0 0)
				(effects
					(font
						(size 1.27 1.27)
					)
					(hide yes)
				)
			)
			(symbol "C_33p_0402_0_1"
				(polyline
					(pts
						(xy 2.032 -1.524) (xy 2.032 1.524)
					)
					(stroke
						(width 0.3048)
						(type default)
					)
					(fill
						(type none)
					)
				)
				(polyline
					(pts
						(xy 3.048 -1.524) (xy 3.048 1.524)
					)
					(stroke
						(width 0.3302)
						(type default)
					)
					(fill
						(type none)
					)
				)
			)
			(symbol "C_33p_0402_1_1"
				(pin passive line
					(at 0 0 0)
					(length 2.032)
					(name "~"
						(effects
							(font
								(size 1.27 1.27)
							)
						)
					)
					(number "1"
						(effects
							(font
								(size 1.27 1.27)
							)
						)
					)
				)
				(pin passive line
					(at 5.08 0 180)
					(length 2.032)
					(name "~"
						(effects
							(font
								(size 1.27 1.27)
							)
						)
					)
					(number "2"
						(effects
							(font
								(size 1.27 1.27)
							)
						)
					)
				)
			)
		)
	(symbol "antmicroCapacitors0402:C_470p_0402"
			(pin_numbers
				(hide yes)
			)
			(pin_names
				(hide yes)
			)
			(exclude_from_sim no)
			(in_bom yes)
			(on_board yes)
			(property "Reference" "C"
				(at 20.32 -5.08 0)
				(effects
					(font
						(size 1.27 1.27)
						(thickness 0.15)
					)
					(justify left bottom)
				)
			)
			(property "Value" "C_470p_0402"
				(at 20.32 -10.16 0)
				(effects
					(font
						(size 1.27 1.27)
						(thickness 0.15)
					)
					(justify left bottom)
					(hide yes)
				)
			)
			(property "Footprint" "antmicro-footprints:C_0402_1005Metric"
				(at 20.32 -12.7 0)
				(effects
					(font
						(size 1.27 1.27)
						(thickness 0.15)
					)
					(justify left bottom)
					(hide yes)
				)
			)
			(property "Datasheet" "https://www.passivecomponent.com/wp-content/uploads/datasheet/WTC_MLCC_General_Purpose.pdf"
				(at 20.32 -15.24 0)
				(effects
					(font
						(size 1.27 1.27)
						(thickness 0.15)
					)
					(justify left bottom)
					(hide yes)
				)
			)
			(property "Description" "SMD Multilayer Ceramic Capacitor, General Purpose, 470 pF, 25 V, 0402 [1005 Metric], ± 10%, X7R"
				(at 20.32 -33.02 0)
				(effects
					(font
						(size 1.27 1.27)
					)
					(justify left bottom)
					(hide yes)
				)
			)
			(property "MPN" "0402B471K250CT"
				(at 20.32 -17.78 0)
				(effects
					(font
						(size 1.27 1.27)
						(thickness 0.15)
					)
					(justify left bottom)
					(hide yes)
				)
			)
			(property "Manufacturer" "Walsin"
				(at 20.32 -20.32 0)
				(effects
					(font
						(size 1.27 1.27)
						(thickness 0.15)
					)
					(justify left bottom)
					(hide yes)
				)
			)
			(property "License" "Apache-2.0"
				(at 20.32 -22.86 0)
				(effects
					(font
						(size 1.27 1.27)
						(thickness 0.15)
					)
					(justify left bottom)
					(hide yes)
				)
			)
			(property "Author" "Antmicro"
				(at 20.32 -25.4 0)
				(effects
					(font
						(size 1.27 1.27)
						(thickness 0.15)
					)
					(justify left bottom)
					(hide yes)
				)
			)
			(property "Val" "470p"
				(at 20.32 -7.62 0)
				(effects
					(font
						(size 1.27 1.27)
						(thickness 0.15)
					)
					(justify left bottom)
				)
			)
			(property "Voltage" "25V"
				(at 20.32 -27.94 0)
				(effects
					(font
						(size 1.27 1.27)
					)
					(justify left bottom)
					(hide yes)
				)
			)
			(property "Dielectric" "X7R"
				(at 20.32 -30.48 0)
				(effects
					(font
						(size 1.27 1.27)
					)
					(justify left bottom)
					(hide yes)
				)
			)
			(property "ki_keywords" "0402, SMT, CAPACITOR, PASSIVE, MLCC"
				(at 0 0 0)
				(effects
					(font
						(size 1.27 1.27)
					)
					(hide yes)
				)
			)
			(symbol "C_470p_0402_0_1"
				(polyline
					(pts
						(xy 2.032 -1.524) (xy 2.032 1.524)
					)
					(stroke
						(width 0.3048)
						(type default)
					)
					(fill
						(type none)
					)
				)
				(polyline
					(pts
						(xy 3.048 -1.524) (xy 3.048 1.524)
					)
					(stroke
						(width 0.3302)
						(type default)
					)
					(fill
						(type none)
					)
				)
			)
			(symbol "C_470p_0402_1_1"
				(pin passive line
					(at 0 0 0)
					(length 2.032)
					(name "~"
						(effects
							(font
								(size 1.27 1.27)
							)
						)
					)
					(number "1"
						(effects
							(font
								(size 1.27 1.27)
							)
						)
					)
				)
				(pin passive line
					(at 5.08 0 180)
					(length 2.032)
					(name "~"
						(effects
							(font
								(size 1.27 1.27)
							)
						)
					)
					(number "2"
						(effects
							(font
								(size 1.27 1.27)
							)
						)
					)
				)
			)
		)
	(symbol "antmicroCapacitors0402:C_4u7_25V_0402"
			(pin_numbers
				(hide yes)
			)
			(pin_names
				(hide yes)
			)
			(exclude_from_sim no)
			(in_bom yes)
			(on_board yes)
			(property "Reference" "C"
				(at 20.32 -5.08 0)
				(effects
					(font
						(size 1.27 1.27)
						(thickness 0.15)
					)
					(justify left bottom)
				)
			)
			(property "Value" "C_4u7_25V_0402"
				(at 20.32 -10.16 0)
				(effects
					(font
						(size 1.27 1.27)
						(thickness 0.15)
					)
					(justify left bottom)
					(hide yes)
				)
			)
			(property "Footprint" "antmicro-footprints:C_0402_1005Metric"
				(at 20.32 -12.7 0)
				(effects
					(font
						(size 1.27 1.27)
						(thickness 0.15)
					)
					(justify left bottom)
					(hide yes)
				)
			)
			(property "Datasheet" "https://www.murata.com/products/productdetail?partno=GRM155C61E475ME15%23"
				(at 20.32 -15.24 0)
				(effects
					(font
						(size 1.27 1.27)
						(thickness 0.15)
					)
					(justify left bottom)
					(hide yes)
				)
			)
			(property "Description" "SMD Multilayer Ceramic Capacitor"
				(at 20.32 -33.02 0)
				(effects
					(font
						(size 1.27 1.27)
					)
					(justify left bottom)
					(hide yes)
				)
			)
			(property "MPN" "GRM155C61E475ME15J"
				(at 20.32 -17.78 0)
				(effects
					(font
						(size 1.27 1.27)
						(thickness 0.15)
					)
					(justify left bottom)
					(hide yes)
				)
			)
			(property "Manufacturer" "Murata"
				(at 20.32 -20.32 0)
				(effects
					(font
						(size 1.27 1.27)
						(thickness 0.15)
					)
					(justify left bottom)
					(hide yes)
				)
			)
			(property "License" "Apache-2.0"
				(at 20.32 -22.86 0)
				(effects
					(font
						(size 1.27 1.27)
						(thickness 0.15)
					)
					(justify left bottom)
					(hide yes)
				)
			)
			(property "Author" "Antmicro"
				(at 20.32 -25.4 0)
				(effects
					(font
						(size 1.27 1.27)
						(thickness 0.15)
					)
					(justify left bottom)
					(hide yes)
				)
			)
			(property "Val" "4u7"
				(at 20.32 -7.62 0)
				(effects
					(font
						(size 1.27 1.27)
						(thickness 0.15)
					)
					(justify left bottom)
				)
			)
			(property "Voltage" "25V"
				(at 20.32 -27.94 0)
				(effects
					(font
						(size 1.27 1.27)
					)
					(justify left bottom)
					(hide yes)
				)
			)
			(property "Dielectric" "X5S"
				(at 20.32 -30.48 0)
				(effects
					(font
						(size 1.27 1.27)
					)
					(justify left bottom)
					(hide yes)
				)
			)
			(property "ki_keywords" "0402, SMT, CAPACITOR, PASSIVE, CERAMIC"
				(at 0 0 0)
				(effects
					(font
						(size 1.27 1.27)
					)
					(hide yes)
				)
			)
			(symbol "C_4u7_25V_0402_0_1"
				(polyline
					(pts
						(xy 2.032 -1.524) (xy 2.032 1.524)
					)
					(stroke
						(width 0.3048)
						(type default)
					)
					(fill
						(type none)
					)
				)
				(polyline
					(pts
						(xy 3.048 -1.524) (xy 3.048 1.524)
					)
					(stroke
						(width 0.3302)
						(type default)
					)
					(fill
						(type none)
					)
				)
			)
			(symbol "C_4u7_25V_0402_1_1"
				(pin passive line
					(at 0 0 0)
					(length 2.032)
					(name "~"
						(effects
							(font
								(size 1.27 1.27)
							)
						)
					)
					(number "1"
						(effects
							(font
								(size 1.27 1.27)
							)
						)
					)
				)
				(pin passive line
					(at 5.08 0 180)
					(length 2.032)
					(name "~"
						(effects
							(font
								(size 1.27 1.27)
							)
						)
					)
					(number "2"
						(effects
							(font
								(size 1.27 1.27)
							)
						)
					)
				)
			)
		)
	(symbol "antmicroCapacitors0402:C_5p6_0402"
			(pin_numbers
				(hide yes)
			)
			(pin_names
				(hide yes)
			)
			(exclude_from_sim no)
			(in_bom yes)
			(on_board yes)
			(property "Reference" "C"
				(at 20.32 -5.08 0)
				(effects
					(font
						(size 1.27 1.27)
						(thickness 0.15)
					)
					(justify left bottom)
				)
			)
			(property "Value" "C_5p6_0402"
				(at 20.32 -10.16 0)
				(effects
					(font
						(size 1.27 1.27)
						(thickness 0.15)
					)
					(justify left bottom)
					(hide yes)
				)
			)
			(property "Footprint" "antmicro-footprints:C_0402_1005Metric"
				(at 20.32 -12.7 0)
				(effects
					(font
						(size 1.27 1.27)
						(thickness 0.15)
					)
					(justify left bottom)
					(hide yes)
				)
			)
			(property "Datasheet" "https://www.mouser.com/datasheet/3/76/2/GCM1555C1H5R6BA16_01A.pdf"
				(at 20.32 -15.24 0)
				(effects
					(font
						(size 1.27 1.27)
						(thickness 0.15)
					)
					(justify left bottom)
					(hide yes)
				)
			)
			(property "Description" "Multilayer Ceramic Capacitors MLCC - SMD/SMT 5.6 pF 50 VDC 0.1 pF 0402 C0G (NP0) AEC-Q200"
				(at 20.32 -33.02 0)
				(effects
					(font
						(size 1.27 1.27)
					)
					(justify left bottom)
					(hide yes)
				)
			)
			(property "MPN" "GCM1555C1H5R6BA16D"
				(at 20.32 -17.78 0)
				(effects
					(font
						(size 1.27 1.27)
						(thickness 0.15)
					)
					(justify left bottom)
					(hide yes)
				)
			)
			(property "Manufacturer" "Murata"
				(at 20.32 -20.32 0)
				(effects
					(font
						(size 1.27 1.27)
						(thickness 0.15)
					)
					(justify left bottom)
					(hide yes)
				)
			)
			(property "License" "Apache-2.0"
				(at 20.32 -22.86 0)
				(effects
					(font
						(size 1.27 1.27)
						(thickness 0.15)
					)
					(justify left bottom)
					(hide yes)
				)
			)
			(property "Author" "Antmicro"
				(at 20.32 -25.4 0)
				(effects
					(font
						(size 1.27 1.27)
						(thickness 0.15)
					)
					(justify left bottom)
					(hide yes)
				)
			)
			(property "Val" "5p6"
				(at 20.32 -7.62 0)
				(effects
					(font
						(size 1.27 1.27)
						(thickness 0.15)
					)
					(justify left bottom)
				)
			)
			(property "Voltage" "50V"
				(at 20.32 -27.94 0)
				(effects
					(font
						(size 1.27 1.27)
					)
					(justify left bottom)
					(hide yes)
				)
			)
			(property "Dielectric" "C0G"
				(at 20.32 -30.48 0)
				(effects
					(font
						(size 1.27 1.27)
					)
					(justify left bottom)
					(hide yes)
				)
			)
			(property "ki_keywords" "0402, SMT, CAPACITOR, PASSIVE, CERAMIC, MLCC"
				(at 0 0 0)
				(effects
					(font
						(size 1.27 1.27)
					)
					(hide yes)
				)
			)
			(symbol "C_5p6_0402_0_1"
				(polyline
					(pts
						(xy 2.032 -1.524) (xy 2.032 1.524)
					)
					(stroke
						(width 0.3048)
						(type default)
					)
					(fill
						(type none)
					)
				)
				(polyline
					(pts
						(xy 3.048 -1.524) (xy 3.048 1.524)
					)
					(stroke
						(width 0.3302)
						(type default)
					)
					(fill
						(type none)
					)
				)
			)
			(symbol "C_5p6_0402_1_1"
				(pin passive line
					(at 0 0 0)
					(length 2.032)
					(name "~"
						(effects
							(font
								(size 1.27 1.27)
							)
						)
					)
					(number "1"
						(effects
							(font
								(size 1.27 1.27)
							)
						)
					)
				)
				(pin passive line
					(at 5.08 0 180)
					(length 2.032)
					(name "~"
						(effects
							(font
								(size 1.27 1.27)
							)
						)
					)
					(number "2"
						(effects
							(font
								(size 1.27 1.27)
							)
						)
					)
				)
			)
		)
	(symbol "antmicroCapacitors0603:C_10u_10V_X7R_0603"
			(pin_numbers
				(hide yes)
			)
			(pin_names
				(hide yes)
			)
			(exclude_from_sim no)
			(in_bom yes)
			(on_board yes)
			(property "Reference" "C"
				(at 15.24 -5.08 0)
				(effects
					(font
						(size 1.27 1.27)
						(thickness 0.15)
					)
					(justify left bottom)
				)
			)
			(property "Value" "C_10u_10V_X7R_0603"
				(at 15.24 -10.16 0)
				(effects
					(font
						(size 1.27 1.27)
						(thickness 0.15)
					)
					(justify left bottom)
					(hide yes)
				)
			)
			(property "Footprint" "antmicro-footprints:C_0603_1608Metric"
				(at 15.24 -12.7 0)
				(effects
					(font
						(size 1.27 1.27)
						(thickness 0.15)
					)
					(justify left bottom)
					(hide yes)
				)
			)
			(property "Datasheet" "https://www.murata.com/products/productdetail?partno=GRM188Z71A106KA73%23"
				(at 15.24 -15.24 0)
				(effects
					(font
						(size 1.27 1.27)
						(thickness 0.15)
					)
					(justify left bottom)
					(hide yes)
				)
			)
			(property "Description" "SMD Multilayer Ceramic Capacitor,  10µF, 10V, 0603, ±10%, X7R"
				(at 15.24 -33.02 0)
				(effects
					(font
						(size 1.27 1.27)
					)
					(justify left bottom)
					(hide yes)
				)
			)
			(property "MPN" "GRM188Z71A106KA73D"
				(at 15.24 -17.78 0)
				(effects
					(font
						(size 1.27 1.27)
						(thickness 0.15)
					)
					(justify left bottom)
					(hide yes)
				)
			)
			(property "Val" "10u"
				(at 15.24 -7.62 0)
				(effects
					(font
						(size 1.27 1.27)
						(thickness 0.15)
					)
					(justify left bottom)
				)
			)
			(property "Voltage" "10V"
				(at 15.24 -20.32 0)
				(effects
					(font
						(size 1.27 1.27)
						(thickness 0.15)
					)
					(justify left bottom)
					(hide yes)
				)
			)
			(property "Dielectric" "X7R"
				(at 15.24 -22.86 0)
				(effects
					(font
						(size 1.27 1.27)
						(thickness 0.15)
					)
					(justify left bottom)
					(hide yes)
				)
			)
			(property "Manufacturer" "Murata"
				(at 15.24 -25.4 0)
				(effects
					(font
						(size 1.27 1.27)
						(thickness 0.15)
					)
					(justify left bottom)
					(hide yes)
				)
			)
			(property "License" "Apache-2.0"
				(at 15.24 -27.94 0)
				(effects
					(font
						(size 1.27 1.27)
						(thickness 0.15)
					)
					(justify left bottom)
					(hide yes)
				)
			)
			(property "Author" "Antmicro"
				(at 15.24 -30.48 0)
				(effects
					(font
						(size 1.27 1.27)
						(thickness 0.15)
					)
					(justify left bottom)
					(hide yes)
				)
			)
			(property "ki_keywords" "SMT, CAPACITOR, PASSIVE"
				(at 0 0 0)
				(effects
					(font
						(size 1.27 1.27)
					)
					(hide yes)
				)
			)
			(symbol "C_10u_10V_X7R_0603_0_1"
				(polyline
					(pts
						(xy 2.032 -1.524) (xy 2.032 1.524)
					)
					(stroke
						(width 0.3048)
						(type default)
					)
					(fill
						(type none)
					)
				)
				(polyline
					(pts
						(xy 3.048 -1.524) (xy 3.048 1.524)
					)
					(stroke
						(width 0.3302)
						(type default)
					)
					(fill
						(type none)
					)
				)
			)
			(symbol "C_10u_10V_X7R_0603_1_1"
				(pin passive line
					(at 0 0 0)
					(length 2.032)
					(name "~"
						(effects
							(font
								(size 1.27 1.27)
							)
						)
					)
					(number "1"
						(effects
							(font
								(size 1.27 1.27)
							)
						)
					)
				)
				(pin passive line
					(at 5.08 0 180)
					(length 2.032)
					(name "~"
						(effects
							(font
								(size 1.27 1.27)
							)
						)
					)
					(number "2"
						(effects
							(font
								(size 1.27 1.27)
							)
						)
					)
				)
			)
		)
	(symbol "antmicroCapacitors0603:C_22u_0603"
			(pin_numbers
				(hide yes)
			)
			(pin_names
				(hide yes)
			)
			(exclude_from_sim no)
			(in_bom yes)
			(on_board yes)
			(property "Reference" "C"
				(at 20.32 -5.08 0)
				(effects
					(font
						(size 1.27 1.27)
						(thickness 0.15)
					)
					(justify left bottom)
				)
			)
			(property "Value" "C_22u_0603"
				(at 20.32 -10.16 0)
				(effects
					(font
						(size 1.27 1.27)
						(thickness 0.15)
					)
					(justify left bottom)
					(hide yes)
				)
			)
			(property "Footprint" "antmicro-footprints:C_0603_1608Metric"
				(at 20.32 -12.7 0)
				(effects
					(font
						(size 1.27 1.27)
						(thickness 0.15)
					)
					(justify left bottom)
					(hide yes)
				)
			)
			(property "Datasheet" "https://www.murata.com/products/productdetail?partno=GRM188R60J226MEA0%23"
				(at 20.32 -15.24 0)
				(effects
					(font
						(size 1.27 1.27)
						(thickness 0.15)
					)
					(justify left bottom)
					(hide yes)
				)
			)
			(property "Description" "SMD Multilayer Ceramic Capacitor, 22 µF, 6.3 V, 0603 [1608 Metric], ± 20%, X5R, GRM Series"
				(at 20.32 -33.02 0)
				(effects
					(font
						(size 1.27 1.27)
					)
					(justify left bottom)
					(hide yes)
				)
			)
			(property "MPN" "GRM188R60J226MEA0D"
				(at 20.32 -17.78 0)
				(effects
					(font
						(size 1.27 1.27)
						(thickness 0.15)
					)
					(justify left bottom)
					(hide yes)
				)
			)
			(property "Manufacturer" "Murata"
				(at 20.32 -20.32 0)
				(effects
					(font
						(size 1.27 1.27)
						(thickness 0.15)
					)
					(justify left bottom)
					(hide yes)
				)
			)
			(property "License" "Apache-2.0"
				(at 20.32 -22.86 0)
				(effects
					(font
						(size 1.27 1.27)
						(thickness 0.15)
					)
					(justify left bottom)
					(hide yes)
				)
			)
			(property "Author" "Antmicro"
				(at 20.32 -25.4 0)
				(effects
					(font
						(size 1.27 1.27)
						(thickness 0.15)
					)
					(justify left bottom)
					(hide yes)
				)
			)
			(property "Val" "22u"
				(at 20.32 -7.62 0)
				(effects
					(font
						(size 1.27 1.27)
						(thickness 0.15)
					)
					(justify left bottom)
				)
			)
			(property "Voltage" ""
				(at 20.32 -27.94 0)
				(effects
					(font
						(size 1.27 1.27)
					)
					(justify left bottom)
					(hide yes)
				)
			)
			(property "Dielectric" ""
				(at 20.32 -30.48 0)
				(effects
					(font
						(size 1.27 1.27)
					)
					(justify left bottom)
					(hide yes)
				)
			)
			(property "ki_keywords" "0603, SMT, CAPACITOR, PASSIVE, CERAMIC, MLCC"
				(at 0 0 0)
				(effects
					(font
						(size 1.27 1.27)
					)
					(hide yes)
				)
			)
			(symbol "C_22u_0603_0_1"
				(polyline
					(pts
						(xy 2.032 -1.524) (xy 2.032 1.524)
					)
					(stroke
						(width 0.3048)
						(type default)
					)
					(fill
						(type none)
					)
				)
				(polyline
					(pts
						(xy 3.048 -1.524) (xy 3.048 1.524)
					)
					(stroke
						(width 0.3302)
						(type default)
					)
					(fill
						(type none)
					)
				)
			)
			(symbol "C_22u_0603_1_1"
				(pin passive line
					(at 0 0 0)
					(length 2.032)
					(name "~"
						(effects
							(font
								(size 1.27 1.27)
							)
						)
					)
					(number "1"
						(effects
							(font
								(size 1.27 1.27)
							)
						)
					)
				)
				(pin passive line
					(at 5.08 0 180)
					(length 2.032)
					(name "~"
						(effects
							(font
								(size 1.27 1.27)
							)
						)
					)
					(number "2"
						(effects
							(font
								(size 1.27 1.27)
							)
						)
					)
				)
			)
		)
	(symbol "antmicroCapacitors0603:C_22u_16V_0603"
			(pin_numbers
				(hide yes)
			)
			(pin_names
				(hide yes)
			)
			(exclude_from_sim no)
			(in_bom yes)
			(on_board yes)
			(property "Reference" "C"
				(at 20.32 -5.08 0)
				(effects
					(font
						(size 1.27 1.27)
						(thickness 0.15)
					)
					(justify left bottom)
				)
			)
			(property "Value" "C_22u_16V_0603"
				(at 20.32 -10.16 0)
				(effects
					(font
						(size 1.27 1.27)
						(thickness 0.15)
					)
					(justify left bottom)
					(hide yes)
				)
			)
			(property "Footprint" "antmicro-footprints:C_0603_1608Metric_EIA"
				(at 20.32 -12.7 0)
				(effects
					(font
						(size 1.27 1.27)
						(thickness 0.15)
					)
					(justify left bottom)
					(hide yes)
				)
			)
			(property "Datasheet" "https://product.samsungsem.com/mlcc/CL10A226MO7JZN.do"
				(at 20.32 -15.24 0)
				(effects
					(font
						(size 1.27 1.27)
						(thickness 0.15)
					)
					(justify left bottom)
					(hide yes)
				)
			)
			(property "Description" "SMD Multilayer Ceramic Capacitor"
				(at 20.32 -33.02 0)
				(effects
					(font
						(size 1.27 1.27)
					)
					(justify left bottom)
					(hide yes)
				)
			)
			(property "MPN" "CL10A226MO7JZNC"
				(at 20.32 -17.78 0)
				(effects
					(font
						(size 1.27 1.27)
						(thickness 0.15)
					)
					(justify left bottom)
					(hide yes)
				)
			)
			(property "Manufacturer" "Samsung Electro-Mechanics"
				(at 20.32 -20.32 0)
				(effects
					(font
						(size 1.27 1.27)
						(thickness 0.15)
					)
					(justify left bottom)
					(hide yes)
				)
			)
			(property "License" "Apache-2.0"
				(at 20.32 -22.86 0)
				(effects
					(font
						(size 1.27 1.27)
						(thickness 0.15)
					)
					(justify left bottom)
					(hide yes)
				)
			)
			(property "Author" "Antmicro"
				(at 20.32 -25.4 0)
				(effects
					(font
						(size 1.27 1.27)
						(thickness 0.15)
					)
					(justify left bottom)
					(hide yes)
				)
			)
			(property "Val" "22u"
				(at 20.32 -7.62 0)
				(effects
					(font
						(size 1.27 1.27)
						(thickness 0.15)
					)
					(justify left bottom)
				)
			)
			(property "Voltage" "16V"
				(at 20.32 -27.94 0)
				(effects
					(font
						(size 1.27 1.27)
					)
					(justify left bottom)
					(hide yes)
				)
			)
			(property "Dielectric" ""
				(at 20.32 -30.48 0)
				(effects
					(font
						(size 1.27 1.27)
					)
					(justify left bottom)
					(hide yes)
				)
			)
			(property "ki_keywords" "0603, SMT, CAPACITOR, PASSIVE, CERAMIC"
				(at 0 0 0)
				(effects
					(font
						(size 1.27 1.27)
					)
					(hide yes)
				)
			)
			(symbol "C_22u_16V_0603_0_1"
				(polyline
					(pts
						(xy 2.032 -1.524) (xy 2.032 1.524)
					)
					(stroke
						(width 0.3048)
						(type default)
					)
					(fill
						(type none)
					)
				)
				(polyline
					(pts
						(xy 3.048 -1.524) (xy 3.048 1.524)
					)
					(stroke
						(width 0.3302)
						(type default)
					)
					(fill
						(type none)
					)
				)
			)
			(symbol "C_22u_16V_0603_1_1"
				(pin passive line
					(at 0 0 0)
					(length 2.032)
					(name "~"
						(effects
							(font
								(size 1.27 1.27)
							)
						)
					)
					(number "1"
						(effects
							(font
								(size 1.27 1.27)
							)
						)
					)
				)
				(pin passive line
					(at 5.08 0 180)
					(length 2.032)
					(name "~"
						(effects
							(font
								(size 1.27 1.27)
							)
						)
					)
					(number "2"
						(effects
							(font
								(size 1.27 1.27)
							)
						)
					)
				)
			)
		)
	(symbol "antmicroCapacitors0603:C_47u_0603"
			(pin_numbers
				(hide yes)
			)
			(pin_names
				(hide yes)
			)
			(exclude_from_sim no)
			(in_bom yes)
			(on_board yes)
			(property "Reference" "C"
				(at 20.32 -5.08 0)
				(effects
					(font
						(size 1.27 1.27)
						(thickness 0.15)
					)
					(justify left bottom)
				)
			)
			(property "Value" "C_47u_0603"
				(at 20.32 -10.16 0)
				(effects
					(font
						(size 1.27 1.27)
						(thickness 0.15)
					)
					(justify left bottom)
					(hide yes)
				)
			)
			(property "Footprint" "antmicro-footprints:C_0603_1608Metric"
				(at 20.32 -12.7 0)
				(effects
					(font
						(size 1.27 1.27)
						(thickness 0.15)
					)
					(justify left bottom)
					(hide yes)
				)
			)
			(property "Datasheet" "https://www.murata.com/products/productdetail?partno=GRM188R60J476ME15%23"
				(at 20.32 -15.24 0)
				(effects
					(font
						(size 1.27 1.27)
						(thickness 0.15)
					)
					(justify left bottom)
					(hide yes)
				)
			)
			(property "Description" "SMD Multilayer Ceramic Capacitor, 47 µF, 6.3 V, 0603 [1608 Metric], ± 20%, X5R, GRM Series"
				(at 20.32 -33.02 0)
				(effects
					(font
						(size 1.27 1.27)
					)
					(justify left bottom)
					(hide yes)
				)
			)
			(property "MPN" "GRM188R60J476ME15D"
				(at 20.32 -17.78 0)
				(effects
					(font
						(size 1.27 1.27)
						(thickness 0.15)
					)
					(justify left bottom)
					(hide yes)
				)
			)
			(property "Manufacturer" "Murata"
				(at 20.32 -20.32 0)
				(effects
					(font
						(size 1.27 1.27)
						(thickness 0.15)
					)
					(justify left bottom)
					(hide yes)
				)
			)
			(property "License" "Apache-2.0"
				(at 20.32 -22.86 0)
				(effects
					(font
						(size 1.27 1.27)
						(thickness 0.15)
					)
					(justify left bottom)
					(hide yes)
				)
			)
			(property "Author" "Antmicro"
				(at 20.32 -25.4 0)
				(effects
					(font
						(size 1.27 1.27)
						(thickness 0.15)
					)
					(justify left bottom)
					(hide yes)
				)
			)
			(property "Val" "47u"
				(at 20.32 -7.62 0)
				(effects
					(font
						(size 1.27 1.27)
						(thickness 0.15)
					)
					(justify left bottom)
				)
			)
			(property "Voltage" ""
				(at 20.32 -27.94 0)
				(effects
					(font
						(size 1.27 1.27)
					)
					(justify left bottom)
					(hide yes)
				)
			)
			(property "Dielectric" ""
				(at 20.32 -30.48 0)
				(effects
					(font
						(size 1.27 1.27)
					)
					(justify left bottom)
					(hide yes)
				)
			)
			(property "ki_keywords" "0603, SMT, CAPACITOR, PASSIVE, CERAMIC, MLCC"
				(at 0 0 0)
				(effects
					(font
						(size 1.27 1.27)
					)
					(hide yes)
				)
			)
			(symbol "C_47u_0603_0_1"
				(polyline
					(pts
						(xy 2.032 -1.524) (xy 2.032 1.524)
					)
					(stroke
						(width 0.3048)
						(type default)
					)
					(fill
						(type none)
					)
				)
				(polyline
					(pts
						(xy 3.048 -1.524) (xy 3.048 1.524)
					)
					(stroke
						(width 0.3302)
						(type default)
					)
					(fill
						(type none)
					)
				)
			)
			(symbol "C_47u_0603_1_1"
				(pin passive line
					(at 0 0 0)
					(length 2.032)
					(name "~"
						(effects
							(font
								(size 1.27 1.27)
							)
						)
					)
					(number "1"
						(effects
							(font
								(size 1.27 1.27)
							)
						)
					)
				)
				(pin passive line
					(at 5.08 0 180)
					(length 2.032)
					(name "~"
						(effects
							(font
								(size 1.27 1.27)
							)
						)
					)
					(number "2"
						(effects
							(font
								(size 1.27 1.27)
							)
						)
					)
				)
			)
		)
	(symbol "antmicroCapacitorsmisc:C_100u_0805"
			(pin_numbers
				(hide yes)
			)
			(pin_names
				(hide yes)
			)
			(exclude_from_sim no)
			(in_bom yes)
			(on_board yes)
			(property "Reference" "C"
				(at 20.32 -5.08 0)
				(effects
					(font
						(size 1.27 1.27)
						(thickness 0.15)
					)
					(justify left bottom)
				)
			)
			(property "Value" "C_100u_0805"
				(at 20.32 -10.16 0)
				(effects
					(font
						(size 1.27 1.27)
						(thickness 0.15)
					)
					(justify left bottom)
					(hide yes)
				)
			)
			(property "Footprint" "antmicro-footprints:C_0805_2012Metric"
				(at 20.32 -12.7 0)
				(effects
					(font
						(size 1.27 1.27)
						(thickness 0.15)
					)
					(justify left bottom)
					(hide yes)
				)
			)
			(property "Datasheet" "https://www.murata.com/products/productdetail?partno=GRM21BR60J107ME15%23"
				(at 20.32 -15.24 0)
				(effects
					(font
						(size 1.27 1.27)
						(thickness 0.15)
					)
					(justify left bottom)
					(hide yes)
				)
			)
			(property "Description" "SMD Multilayer Ceramic Capacitor, 100 µF, 6.3 V, 0805 [2012 Metric], ± 20%, X5R, GRM Series"
				(at 20.32 -33.02 0)
				(effects
					(font
						(size 1.27 1.27)
					)
					(justify left bottom)
					(hide yes)
				)
			)
			(property "MPN" "GRM21BR60J107ME15L"
				(at 20.32 -17.78 0)
				(effects
					(font
						(size 1.27 1.27)
						(thickness 0.15)
					)
					(justify left bottom)
					(hide yes)
				)
			)
			(property "Manufacturer" "Murata"
				(at 20.32 -20.32 0)
				(effects
					(font
						(size 1.27 1.27)
						(thickness 0.15)
					)
					(justify left bottom)
					(hide yes)
				)
			)
			(property "License" "Apache-2.0"
				(at 20.32 -22.86 0)
				(effects
					(font
						(size 1.27 1.27)
						(thickness 0.15)
					)
					(justify left bottom)
					(hide yes)
				)
			)
			(property "Author" "Antmicro"
				(at 20.32 -25.4 0)
				(effects
					(font
						(size 1.27 1.27)
						(thickness 0.15)
					)
					(justify left bottom)
					(hide yes)
				)
			)
			(property "Val" "100u"
				(at 20.32 -7.62 0)
				(effects
					(font
						(size 1.27 1.27)
						(thickness 0.15)
					)
					(justify left bottom)
				)
			)
			(property "Voltage" ""
				(at 20.32 -27.94 0)
				(effects
					(font
						(size 1.27 1.27)
					)
					(justify left bottom)
					(hide yes)
				)
			)
			(property "Dielectric" ""
				(at 20.32 -30.48 0)
				(effects
					(font
						(size 1.27 1.27)
					)
					(justify left bottom)
					(hide yes)
				)
			)
			(property "Public" "False"
				(at 20.32 -33.02 0)
				(effects
					(font
						(size 1.27 1.27)
					)
					(justify left bottom)
					(hide yes)
				)
			)
			(property "ki_keywords" "0805, SMT, CAPACITOR, PASSIVE"
				(at 0 0 0)
				(effects
					(font
						(size 1.27 1.27)
					)
					(hide yes)
				)
			)
			(symbol "C_100u_0805_0_1"
				(polyline
					(pts
						(xy 2.032 -1.524) (xy 2.032 1.524)
					)
					(stroke
						(width 0.3048)
						(type default)
					)
					(fill
						(type none)
					)
				)
				(polyline
					(pts
						(xy 3.048 -1.524) (xy 3.048 1.524)
					)
					(stroke
						(width 0.3302)
						(type default)
					)
					(fill
						(type none)
					)
				)
			)
			(symbol "C_100u_0805_1_1"
				(pin passive line
					(at 0 0 0)
					(length 2.032)
					(name "~"
						(effects
							(font
								(size 1.27 1.27)
							)
						)
					)
					(number "1"
						(effects
							(font
								(size 1.27 1.27)
							)
						)
					)
				)
				(pin passive line
					(at 5.08 0 180)
					(length 2.032)
					(name "~"
						(effects
							(font
								(size 1.27 1.27)
							)
						)
					)
					(number "2"
						(effects
							(font
								(size 1.27 1.27)
							)
						)
					)
				)
			)
		)
	(symbol "antmicroCapacitorsmisc:C_220u_1206_6V3"
			(pin_numbers
				(hide yes)
			)
			(pin_names
				(hide yes)
			)
			(exclude_from_sim no)
			(in_bom yes)
			(on_board yes)
			(property "Reference" "C"
				(at 20.32 -5.08 0)
				(effects
					(font
						(size 1.27 1.27)
						(thickness 0.15)
					)
					(justify left bottom)
				)
			)
			(property "Value" "C_220u_1206_6V3"
				(at 20.32 -10.16 0)
				(effects
					(font
						(size 1.27 1.27)
						(thickness 0.15)
					)
					(justify left bottom)
					(hide yes)
				)
			)
			(property "Footprint" "antmicro-footprints:C_1206_3216Metric"
				(at 20.32 -12.7 0)
				(effects
					(font
						(size 1.27 1.27)
						(thickness 0.15)
					)
					(justify left bottom)
					(hide yes)
				)
			)
			(property "Datasheet" "https://www.murata.com/products/productdetail?partno=GRM31CR60J227ME11%23"
				(at 20.32 -15.24 0)
				(effects
					(font
						(size 1.27 1.27)
						(thickness 0.15)
					)
					(justify left bottom)
					(hide yes)
				)
			)
			(property "Description" "SMD Multilayer Ceramic Capacitor, 220 µF, 6.3 V, 1206 [3216 Metric], ± 20%, X5R, GRM Series"
				(at 20.32 -33.02 0)
				(effects
					(font
						(size 1.27 1.27)
					)
					(justify left bottom)
					(hide yes)
				)
			)
			(property "MPN" "GRM31CR60J227ME11L"
				(at 20.32 -17.78 0)
				(effects
					(font
						(size 1.27 1.27)
						(thickness 0.15)
					)
					(justify left bottom)
					(hide yes)
				)
			)
			(property "Manufacturer" "Murata"
				(at 20.32 -20.32 0)
				(effects
					(font
						(size 1.27 1.27)
						(thickness 0.15)
					)
					(justify left bottom)
					(hide yes)
				)
			)
			(property "License" "Apache-2.0"
				(at 20.32 -22.86 0)
				(effects
					(font
						(size 1.27 1.27)
						(thickness 0.15)
					)
					(justify left bottom)
					(hide yes)
				)
			)
			(property "Author" "Antmicro"
				(at 20.32 -25.4 0)
				(effects
					(font
						(size 1.27 1.27)
						(thickness 0.15)
					)
					(justify left bottom)
					(hide yes)
				)
			)
			(property "Val" "220u"
				(at 20.32 -7.62 0)
				(effects
					(font
						(size 1.27 1.27)
						(thickness 0.15)
					)
					(justify left bottom)
				)
			)
			(property "Voltage" ""
				(at 20.32 -27.94 0)
				(effects
					(font
						(size 1.27 1.27)
					)
					(justify left bottom)
					(hide yes)
				)
			)
			(property "Dielectric" ""
				(at 20.32 -30.48 0)
				(effects
					(font
						(size 1.27 1.27)
					)
					(justify left bottom)
					(hide yes)
				)
			)
			(property "Public" "False"
				(at 20.32 -33.02 0)
				(effects
					(font
						(size 1.27 1.27)
					)
					(justify left bottom)
					(hide yes)
				)
			)
			(property "ki_keywords" "1206, SMT, CAPACITOR, PASSIVE, CERAMIC, MLCC"
				(at 0 0 0)
				(effects
					(font
						(size 1.27 1.27)
					)
					(hide yes)
				)
			)
			(symbol "C_220u_1206_6V3_0_1"
				(polyline
					(pts
						(xy 2.032 -1.524) (xy 2.032 1.524)
					)
					(stroke
						(width 0.3048)
						(type default)
					)
					(fill
						(type none)
					)
				)
				(polyline
					(pts
						(xy 3.048 -1.524) (xy 3.048 1.524)
					)
					(stroke
						(width 0.3302)
						(type default)
					)
					(fill
						(type none)
					)
				)
			)
			(symbol "C_220u_1206_6V3_1_1"
				(pin passive line
					(at 0 0 0)
					(length 2.032)
					(name "~"
						(effects
							(font
								(size 1.27 1.27)
							)
						)
					)
					(number "1"
						(effects
							(font
								(size 1.27 1.27)
							)
						)
					)
				)
				(pin passive line
					(at 5.08 0 180)
					(length 2.032)
					(name "~"
						(effects
							(font
								(size 1.27 1.27)
							)
						)
					)
					(number "2"
						(effects
							(font
								(size 1.27 1.27)
							)
						)
					)
				)
			)
		)
	(symbol "antmicroCapacitorsmisc:C_22u_100V_2220"
			(pin_numbers
				(hide yes)
			)
			(pin_names
				(hide yes)
			)
			(exclude_from_sim no)
			(in_bom yes)
			(on_board yes)
			(property "Reference" "C"
				(at 20.32 -5.08 0)
				(effects
					(font
						(size 1.27 1.27)
						(thickness 0.15)
					)
					(justify left bottom)
				)
			)
			(property "Value" "C_22u_100V_2220"
				(at 20.32 -10.16 0)
				(effects
					(font
						(size 1.27 1.27)
						(thickness 0.15)
					)
					(justify left bottom)
					(hide yes)
				)
			)
			(property "Footprint" "antmicro-footprints:C_2220_5650Metric"
				(at 20.32 -12.7 0)
				(effects
					(font
						(size 1.27 1.27)
						(thickness 0.15)
					)
					(justify left bottom)
					(hide yes)
				)
			)
			(property "Datasheet" "https://product.tdk.com/en/search/capacitor/ceramic/mlcc/info?part_no=C5750X7S2A226M280KB"
				(at 20.32 -15.24 0)
				(effects
					(font
						(size 1.27 1.27)
						(thickness 0.15)
					)
					(justify left bottom)
					(hide yes)
				)
			)
			(property "Description" "SMT Multilayer Ceramic Capacitor, 22 µF, 100 V, 2220 [5750 Metric], ± 20%, X7S, C"
				(at 20.32 -33.02 0)
				(effects
					(font
						(size 1.27 1.27)
					)
					(justify left bottom)
					(hide yes)
				)
			)
			(property "MPN" "C5750X7S2A226M280KB"
				(at 20.32 -17.78 0)
				(effects
					(font
						(size 1.27 1.27)
						(thickness 0.15)
					)
					(justify left bottom)
					(hide yes)
				)
			)
			(property "Manufacturer" "TDK"
				(at 20.32 -20.32 0)
				(effects
					(font
						(size 1.27 1.27)
						(thickness 0.15)
					)
					(justify left bottom)
					(hide yes)
				)
			)
			(property "License" "Apache-2.0"
				(at 20.32 -22.86 0)
				(effects
					(font
						(size 1.27 1.27)
						(thickness 0.15)
					)
					(justify left bottom)
					(hide yes)
				)
			)
			(property "Author" "Antmicro"
				(at 20.32 -25.4 0)
				(effects
					(font
						(size 1.27 1.27)
						(thickness 0.15)
					)
					(justify left bottom)
					(hide yes)
				)
			)
			(property "Val" "22u"
				(at 20.32 -7.62 0)
				(effects
					(font
						(size 1.27 1.27)
						(thickness 0.15)
					)
					(justify left bottom)
				)
			)
			(property "Voltage" "100V"
				(at 20.32 -27.94 0)
				(effects
					(font
						(size 1.27 1.27)
					)
					(justify left bottom)
				)
			)
			(property "Dielectric" "X7S"
				(at 20.32 -30.48 0)
				(effects
					(font
						(size 1.27 1.27)
					)
					(justify left bottom)
					(hide yes)
				)
			)
			(property "Public" "False"
				(at 20.32 -33.02 0)
				(effects
					(font
						(size 1.27 1.27)
					)
					(justify left bottom)
					(hide yes)
				)
			)
			(property "ki_keywords" "SMT, CAPACITOR, PASSIVE"
				(at 0 0 0)
				(effects
					(font
						(size 1.27 1.27)
					)
					(hide yes)
				)
			)
			(symbol "C_22u_100V_2220_0_1"
				(polyline
					(pts
						(xy 2.032 -1.524) (xy 2.032 1.524)
					)
					(stroke
						(width 0.3048)
						(type default)
					)
					(fill
						(type none)
					)
				)
				(polyline
					(pts
						(xy 3.048 -1.524) (xy 3.048 1.524)
					)
					(stroke
						(width 0.3302)
						(type default)
					)
					(fill
						(type none)
					)
				)
			)
			(symbol "C_22u_100V_2220_1_1"
				(pin passive line
					(at 0 0 0)
					(length 2.032)
					(name "~"
						(effects
							(font
								(size 1.27 1.27)
							)
						)
					)
					(number "1"
						(effects
							(font
								(size 1.27 1.27)
							)
						)
					)
				)
				(pin passive line
					(at 5.08 0 180)
					(length 2.032)
					(name "~"
						(effects
							(font
								(size 1.27 1.27)
							)
						)
					)
					(number "2"
						(effects
							(font
								(size 1.27 1.27)
							)
						)
					)
				)
			)
		)
	(symbol "antmicroCapacitorsmisc:C_22u_25V_0805"
			(pin_numbers
				(hide yes)
			)
			(pin_names
				(hide yes)
			)
			(exclude_from_sim no)
			(in_bom yes)
			(on_board yes)
			(property "Reference" "C"
				(at 20.32 -5.08 0)
				(effects
					(font
						(size 1.27 1.27)
						(thickness 0.15)
					)
					(justify left bottom)
				)
			)
			(property "Value" "C_22u_25V_0805"
				(at 20.32 -10.16 0)
				(effects
					(font
						(size 1.27 1.27)
						(thickness 0.15)
					)
					(justify left bottom)
					(hide yes)
				)
			)
			(property "Footprint" "antmicro-footprints:C_0805_2012Metric"
				(at 20.32 -12.7 0)
				(effects
					(font
						(size 1.27 1.27)
						(thickness 0.15)
					)
					(justify left bottom)
					(hide yes)
				)
			)
			(property "Datasheet" "https://product.samsungsem.com/mlcc/CL21A226MAYNNN.do"
				(at 20.32 -15.24 0)
				(effects
					(font
						(size 1.27 1.27)
						(thickness 0.15)
					)
					(justify left bottom)
					(hide yes)
				)
			)
			(property "Description" "SMT Multilayer Ceramic Capacitor, 22uF, +/-20%, 25V, X5R, 0805 [2012 Metric]"
				(at 20.32 -33.02 0)
				(effects
					(font
						(size 1.27 1.27)
					)
					(justify left bottom)
					(hide yes)
				)
			)
			(property "MPN" "CL21A226MAYNNNE"
				(at 20.32 -17.78 0)
				(effects
					(font
						(size 1.27 1.27)
						(thickness 0.15)
					)
					(justify left bottom)
					(hide yes)
				)
			)
			(property "Manufacturer" "Samsung Electro-Mechanics"
				(at 20.32 -20.32 0)
				(effects
					(font
						(size 1.27 1.27)
						(thickness 0.15)
					)
					(justify left bottom)
					(hide yes)
				)
			)
			(property "License" "Apache-2.0"
				(at 20.32 -22.86 0)
				(effects
					(font
						(size 1.27 1.27)
						(thickness 0.15)
					)
					(justify left bottom)
					(hide yes)
				)
			)
			(property "Author" "Antmicro"
				(at 20.32 -25.4 0)
				(effects
					(font
						(size 1.27 1.27)
						(thickness 0.15)
					)
					(justify left bottom)
					(hide yes)
				)
			)
			(property "Val" "22u"
				(at 20.32 -7.62 0)
				(effects
					(font
						(size 1.27 1.27)
						(thickness 0.15)
					)
					(justify left bottom)
				)
			)
			(property "Voltage" "25V"
				(at 20.32 -27.94 0)
				(effects
					(font
						(size 1.27 1.27)
					)
					(justify left bottom)
				)
			)
			(property "Dielectric" "X5R"
				(at 20.32 -30.48 0)
				(effects
					(font
						(size 1.27 1.27)
					)
					(justify left bottom)
					(hide yes)
				)
			)
			(property "Public" "False"
				(at 20.32 -33.02 0)
				(effects
					(font
						(size 1.27 1.27)
					)
					(justify left bottom)
					(hide yes)
				)
			)
			(property "ki_keywords" "0805, SMT, CAPACITOR, PASSIVE"
				(at 0 0 0)
				(effects
					(font
						(size 1.27 1.27)
					)
					(hide yes)
				)
			)
			(symbol "C_22u_25V_0805_0_1"
				(polyline
					(pts
						(xy 2.032 -1.524) (xy 2.032 1.524)
					)
					(stroke
						(width 0.3048)
						(type default)
					)
					(fill
						(type none)
					)
				)
				(polyline
					(pts
						(xy 3.048 -1.524) (xy 3.048 1.524)
					)
					(stroke
						(width 0.3302)
						(type default)
					)
					(fill
						(type none)
					)
				)
			)
			(symbol "C_22u_25V_0805_1_1"
				(pin passive line
					(at 0 0 0)
					(length 2.032)
					(name "~"
						(effects
							(font
								(size 1.27 1.27)
							)
						)
					)
					(number "1"
						(effects
							(font
								(size 1.27 1.27)
							)
						)
					)
				)
				(pin passive line
					(at 5.08 0 180)
					(length 2.032)
					(name "~"
						(effects
							(font
								(size 1.27 1.27)
							)
						)
					)
					(number "2"
						(effects
							(font
								(size 1.27 1.27)
							)
						)
					)
				)
			)
		)
	(symbol "antmicroCapacitorspol:C_Pol_100u_6V_KEMET-T490-A"
			(pin_numbers
				(hide yes)
			)
			(pin_names
				(hide yes)
			)
			(exclude_from_sim no)
			(in_bom yes)
			(on_board yes)
			(property "Reference" "C"
				(at 13.97 0 0)
				(effects
					(font
						(size 1.27 1.27)
						(thickness 0.15)
					)
					(justify left bottom)
				)
			)
			(property "Value" "C_Pol_100u_6V_KEMET-T490-A"
				(at 13.97 -2.54 0)
				(effects
					(font
						(size 1.27 1.27)
						(thickness 0.15)
					)
					(justify left bottom)
					(hide yes)
				)
			)
			(property "Footprint" "antmicro-footprints:C_Pol_EIA-A"
				(at 13.97 -7.62 0)
				(effects
					(font
						(size 1.27 1.27)
						(thickness 0.15)
					)
					(justify left bottom)
					(hide yes)
				)
			)
			(property "Datasheet" "https://www.kemet.com/en/us/capacitors/product/T490A107M006ATE800.html"
				(at 13.97 -10.16 0)
				(effects
					(font
						(size 1.27 1.27)
						(thickness 0.15)
					)
					(justify left bottom)
					(hide yes)
				)
			)
			(property "Description" "Surface Mount Tantalum Capacitor,  Solid SMD 6V 100uF 1206 20% ESR=800mOhms"
				(at 13.97 -25.4 0)
				(effects
					(font
						(size 1.27 1.27)
					)
					(justify left bottom)
					(hide yes)
				)
			)
			(property "Val" "100u"
				(at 13.97 -5.08 0)
				(effects
					(font
						(size 1.27 1.27)
						(thickness 0.15)
					)
					(justify left bottom)
				)
			)
			(property "MPN" "T490A107M006ATE800"
				(at 13.97 -12.7 0)
				(effects
					(font
						(size 1.27 1.27)
						(thickness 0.15)
					)
					(justify left bottom)
					(hide yes)
				)
			)
			(property "Manufacturer" "KEMET"
				(at 13.97 -15.24 0)
				(effects
					(font
						(size 1.27 1.27)
						(thickness 0.15)
					)
					(justify left bottom)
					(hide yes)
				)
			)
			(property "License" "Apache-2.0"
				(at 13.97 -17.78 0)
				(effects
					(font
						(size 1.27 1.27)
						(thickness 0.15)
					)
					(justify left bottom)
					(hide yes)
				)
			)
			(property "Author" "Antmicro"
				(at 13.97 -20.32 0)
				(effects
					(font
						(size 1.27 1.27)
						(thickness 0.15)
					)
					(justify left bottom)
					(hide yes)
				)
			)
			(property "Voltage" "6V"
				(at 13.97 -22.86 0)
				(effects
					(font
						(size 1.27 1.27)
					)
					(justify left bottom)
					(hide yes)
				)
			)
			(property "Dielectric" "template_dielectric"
				(at 13.97 -25.4 0)
				(effects
					(font
						(size 1.27 1.27)
					)
					(justify left bottom)
					(hide yes)
				)
			)
			(property "ki_keywords" "SMT, CAPACITOR, PASSIVE, POLARIZED, TANTALUM"
				(at 0 0 0)
				(effects
					(font
						(size 1.27 1.27)
					)
					(hide yes)
				)
			)
			(symbol "C_Pol_100u_6V_KEMET-T490-A_0_1"
				(polyline
					(pts
						(xy 0.9652 1.27) (xy 0.9652 1.778)
					)
					(stroke
						(width 0)
						(type default)
					)
					(fill
						(type none)
					)
				)
				(polyline
					(pts
						(xy 1.2192 1.524) (xy 0.7112 1.524)
					)
					(stroke
						(width 0)
						(type default)
					)
					(fill
						(type none)
					)
				)
				(rectangle
					(start 1.905 -1.524)
					(end 2.286 1.524)
					(stroke
						(width 0)
						(type default)
					)
					(fill
						(type none)
					)
				)
				(rectangle
					(start 2.921 -1.524)
					(end 3.302 1.524)
					(stroke
						(width 0)
						(type default)
					)
					(fill
						(type outline)
					)
				)
			)
			(symbol "C_Pol_100u_6V_KEMET-T490-A_1_1"
				(pin passive line
					(at 0 0 0)
					(length 1.8542)
					(name "~"
						(effects
							(font
								(size 1.27 1.27)
							)
						)
					)
					(number "1"
						(effects
							(font
								(size 1.27 1.27)
							)
						)
					)
				)
				(pin passive line
					(at 5.08 0 180)
					(length 1.8542)
					(name "~"
						(effects
							(font
								(size 1.27 1.27)
							)
						)
					)
					(number "2"
						(effects
							(font
								(size 1.27 1.27)
							)
						)
					)
				)
			)
		)
	(symbol "antmicroCapacitorspol:C_Pol_330u_6.3V_KEMET-T520-B"
			(pin_numbers
				(hide yes)
			)
			(pin_names
				(hide yes)
			)
			(exclude_from_sim no)
			(in_bom yes)
			(on_board yes)
			(property "Reference" "C"
				(at 13.97 0 0)
				(effects
					(font
						(size 1.27 1.27)
						(thickness 0.15)
					)
					(justify left bottom)
				)
			)
			(property "Value" "C_Pol_330u_6.3V_KEMET-T520-B"
				(at 13.97 -2.54 0)
				(effects
					(font
						(size 1.27 1.27)
						(thickness 0.15)
					)
					(justify left bottom)
					(hide yes)
				)
			)
			(property "Footprint" "antmicro-footprints:C_Pol_EIA-B"
				(at 13.97 -7.62 0)
				(effects
					(font
						(size 1.27 1.27)
						(thickness 0.15)
					)
					(justify left bottom)
					(hide yes)
				)
			)
			(property "Datasheet" "https://www.kemet.com/en/us/capacitors/product/T520B337M006ATE040.html"
				(at 13.97 -10.16 0)
				(effects
					(font
						(size 1.27 1.27)
						(thickness 0.15)
					)
					(justify left bottom)
					(hide yes)
				)
			)
			(property "Description" "Tantalum Polymer Capacitor, KO-CAP®, 330 µF, ± 20%, 6.3 V, B, 0.04 ohm, 1411 [3528 Metric]"
				(at 13.97 -25.4 0)
				(effects
					(font
						(size 1.27 1.27)
					)
					(justify left bottom)
					(hide yes)
				)
			)
			(property "Val" "330u"
				(at 13.97 -5.08 0)
				(effects
					(font
						(size 1.27 1.27)
						(thickness 0.15)
					)
					(justify left bottom)
				)
			)
			(property "MPN" "T520B337M006ATE040"
				(at 13.97 -12.7 0)
				(effects
					(font
						(size 1.27 1.27)
						(thickness 0.15)
					)
					(justify left bottom)
					(hide yes)
				)
			)
			(property "Manufacturer" "KEMET"
				(at 13.97 -15.24 0)
				(effects
					(font
						(size 1.27 1.27)
						(thickness 0.15)
					)
					(justify left bottom)
					(hide yes)
				)
			)
			(property "License" "Apache-2.0"
				(at 13.97 -17.78 0)
				(effects
					(font
						(size 1.27 1.27)
						(thickness 0.15)
					)
					(justify left bottom)
					(hide yes)
				)
			)
			(property "Author" "Antmicro"
				(at 13.97 -20.32 0)
				(effects
					(font
						(size 1.27 1.27)
						(thickness 0.15)
					)
					(justify left bottom)
					(hide yes)
				)
			)
			(property "Voltage" "6.3V"
				(at 13.97 -22.86 0)
				(effects
					(font
						(size 1.27 1.27)
					)
					(justify left bottom)
					(hide yes)
				)
			)
			(property "Dielectric" "template_dielectric"
				(at 13.97 -25.4 0)
				(effects
					(font
						(size 1.27 1.27)
					)
					(justify left bottom)
					(hide yes)
				)
			)
			(property "ki_keywords" "SMT, CAPACITOR, PASSIVE, POLARIZED, TANTALUM"
				(at 0 0 0)
				(effects
					(font
						(size 1.27 1.27)
					)
					(hide yes)
				)
			)
			(symbol "C_Pol_330u_6.3V_KEMET-T520-B_0_1"
				(polyline
					(pts
						(xy 0.9652 1.27) (xy 0.9652 1.778)
					)
					(stroke
						(width 0)
						(type default)
					)
					(fill
						(type none)
					)
				)
				(polyline
					(pts
						(xy 1.2192 1.524) (xy 0.7112 1.524)
					)
					(stroke
						(width 0)
						(type default)
					)
					(fill
						(type none)
					)
				)
				(rectangle
					(start 1.905 -1.524)
					(end 2.286 1.524)
					(stroke
						(width 0)
						(type default)
					)
					(fill
						(type none)
					)
				)
				(rectangle
					(start 2.921 -1.524)
					(end 3.302 1.524)
					(stroke
						(width 0)
						(type default)
					)
					(fill
						(type outline)
					)
				)
			)
			(symbol "C_Pol_330u_6.3V_KEMET-T520-B_1_1"
				(pin passive line
					(at 0 0 0)
					(length 1.8542)
					(name "~"
						(effects
							(font
								(size 1.27 1.27)
							)
						)
					)
					(number "1"
						(effects
							(font
								(size 1.27 1.27)
							)
						)
					)
				)
				(pin passive line
					(at 5.08 0 180)
					(length 1.8542)
					(name "~"
						(effects
							(font
								(size 1.27 1.27)
							)
						)
					)
					(number "2"
						(effects
							(font
								(size 1.27 1.27)
							)
						)
					)
				)
			)
		)
	(symbol "antmicroClockTimingClockGeneratorsPLLsFrequencySynthesizers:SI52112-B6-GT"
			(exclude_from_sim no)
			(in_bom yes)
			(on_board yes)
			(property "Reference" "U"
				(at 38.1 -2.54 0)
				(effects
					(font
						(size 1.27 1.27)
						(thickness 0.15)
					)
					(justify left bottom)
				)
			)
			(property "Value" "SI52112-B6-GT"
				(at 38.1 -5.08 0)
				(effects
					(font
						(size 1.27 1.27)
						(thickness 0.15)
					)
					(justify left bottom)
					(hide yes)
				)
			)
			(property "Footprint" "antmicro-footprints:TSSOP-8_3x4.4mm_P0.65mm"
				(at 38.1 -7.62 0)
				(effects
					(font
						(size 1.27 1.27)
						(thickness 0.15)
					)
					(justify left bottom)
					(hide yes)
				)
			)
			(property "Datasheet" "https://www.skyworksinc.com/-/media/Skyworks/SL/documents/public/data-sheets/Si52112-B5-B6.pdf"
				(at 38.1 -10.16 0)
				(effects
					(font
						(size 1.27 1.27)
						(thickness 0.15)
					)
					(justify left bottom)
					(hide yes)
				)
			)
			(property "Description" "Clock Generator, 100MHz, 2.97V to 3.63V, 2 Outputs, TSSOP-8"
				(at 38.1 -22.86 0)
				(effects
					(font
						(size 1.27 1.27)
					)
					(justify left bottom)
					(hide yes)
				)
			)
			(property "MPN" "SI52112-B6-GT"
				(at 38.1 -12.7 0)
				(effects
					(font
						(size 1.27 1.27)
						(thickness 0.15)
					)
					(justify left bottom)
				)
			)
			(property "Manufacturer" "Skyworks Solutions"
				(at 38.1 -15.24 0)
				(effects
					(font
						(size 1.27 1.27)
						(thickness 0.15)
					)
					(justify left bottom)
					(hide yes)
				)
			)
			(property "Author" "Antmicro"
				(at 38.1 -17.78 0)
				(effects
					(font
						(size 1.27 1.27)
						(thickness 0.15)
					)
					(justify left bottom)
					(hide yes)
				)
			)
			(property "License" "Apache-2.0"
				(at 38.1 -20.32 0)
				(effects
					(font
						(size 1.27 1.27)
						(thickness 0.15)
					)
					(justify left bottom)
					(hide yes)
				)
			)
			(property "ki_keywords" "IC"
				(at 0 0 0)
				(effects
					(font
						(size 1.27 1.27)
					)
					(hide yes)
				)
			)
			(symbol "SI52112-B6-GT_0_1"
				(rectangle
					(start 2.54 2.54)
					(end 21.59 -10.16)
					(stroke
						(width 0.254)
						(type default)
					)
					(fill
						(type background)
					)
				)
			)
			(symbol "SI52112-B6-GT_1_1"
				(pin power_in line
					(at 0 0 0)
					(length 2.54)
					(name "VDD"
						(effects
							(font
								(size 1.27 1.27)
							)
						)
					)
					(number "1"
						(effects
							(font
								(size 1.27 1.27)
							)
						)
					)
				)
				(pin output line
					(at 0 -2.54 0)
					(length 2.54)
					(name "XOUT"
						(effects
							(font
								(size 1.27 1.27)
							)
						)
					)
					(number "2"
						(effects
							(font
								(size 1.27 1.27)
							)
						)
					)
				)
				(pin input line
					(at 0 -5.08 0)
					(length 2.54)
					(name "XIN/CLKIN"
						(effects
							(font
								(size 1.27 1.27)
							)
						)
					)
					(number "3"
						(effects
							(font
								(size 1.27 1.27)
							)
						)
					)
				)
				(pin power_in line
					(at 0 -7.62 0)
					(length 2.54)
					(name "GND"
						(effects
							(font
								(size 1.27 1.27)
							)
						)
					)
					(number "4"
						(effects
							(font
								(size 1.27 1.27)
							)
						)
					)
				)
				(pin output line
					(at 24.13 0 180)
					(length 2.54)
					(name "DIFF1"
						(effects
							(font
								(size 1.27 1.27)
							)
						)
					)
					(number "5"
						(effects
							(font
								(size 1.27 1.27)
							)
						)
					)
				)
				(pin output line
					(at 24.13 -2.54 180)
					(length 2.54)
					(name "~{DIFF1}"
						(effects
							(font
								(size 1.27 1.27)
							)
						)
					)
					(number "6"
						(effects
							(font
								(size 1.27 1.27)
							)
						)
					)
				)
				(pin output line
					(at 24.13 -5.08 180)
					(length 2.54)
					(name "DIFF2"
						(effects
							(font
								(size 1.27 1.27)
							)
						)
					)
					(number "7"
						(effects
							(font
								(size 1.27 1.27)
							)
						)
					)
				)
				(pin output line
					(at 24.13 -7.62 180)
					(length 2.54)
					(name "~{DIFF2}"
						(effects
							(font
								(size 1.27 1.27)
							)
						)
					)
					(number "8"
						(effects
							(font
								(size 1.27 1.27)
							)
						)
					)
				)
			)
		)
	(symbol "antmicroDCDCConverters:MP2386GG"
			(exclude_from_sim no)
			(in_bom yes)
			(on_board yes)
			(property "Reference" "U"
				(at 33.02 -5.08 0)
				(effects
					(font
						(size 1.27 1.27)
						(thickness 0.15)
					)
					(justify left bottom)
				)
			)
			(property "Value" "MP2386GG"
				(at 33.02 -7.62 0)
				(effects
					(font
						(size 1.27 1.27)
						(thickness 0.15)
					)
					(justify left bottom)
					(hide yes)
				)
			)
			(property "Footprint" "antmicro-footprints:QFN-11_2x2mm_P0.5mm"
				(at 33.02 -10.16 0)
				(effects
					(font
						(size 1.27 1.27)
						(thickness 0.15)
					)
					(justify left bottom)
					(hide yes)
				)
			)
			(property "Datasheet" "https://www.monolithicpower.com/en/documentview/productdocument/index/version/2/document_type/Datasheet/lang/en/sku/MP2386GG-Z/document_id/4066/"
				(at 33.02 -12.7 0)
				(effects
					(font
						(size 1.27 1.27)
						(thickness 0.15)
					)
					(justify left bottom)
					(hide yes)
				)
			)
			(property "Description" "DC/DC converter"
				(at 33.02 -25.4 0)
				(effects
					(font
						(size 1.27 1.27)
					)
					(justify left bottom)
					(hide yes)
				)
			)
			(property "Manufacturer" "Monolithic Power Systems"
				(at 33.02 -15.24 0)
				(effects
					(font
						(size 1.27 1.27)
						(thickness 0.15)
					)
					(justify left bottom)
					(hide yes)
				)
			)
			(property "MPN" "MP2386GG-P"
				(at 33.02 -17.78 0)
				(effects
					(font
						(size 1.27 1.27)
						(thickness 0.15)
					)
					(justify left bottom)
				)
			)
			(property "Author" "Antmicro"
				(at 33.02 -20.32 0)
				(effects
					(font
						(size 1.27 1.27)
						(thickness 0.15)
					)
					(justify left bottom)
					(hide yes)
				)
			)
			(property "License" "Apache-2.0"
				(at 33.02 -22.86 0)
				(effects
					(font
						(size 1.27 1.27)
						(thickness 0.15)
					)
					(justify left bottom)
					(hide yes)
				)
			)
			(property "ki_keywords" "IC"
				(at 0 0 0)
				(effects
					(font
						(size 1.27 1.27)
					)
					(hide yes)
				)
			)
			(symbol "MP2386GG_1_1"
				(rectangle
					(start 2.54 2.54)
					(end 15.24 -20.32)
					(stroke
						(width 0.254)
						(type default)
					)
					(fill
						(type background)
					)
				)
				(pin power_in line
					(at 0 0 0)
					(length 2.54)
					(name "VIN"
						(effects
							(font
								(size 1.27 1.27)
							)
						)
					)
					(number "1"
						(effects
							(font
								(size 1.27 1.27)
							)
						)
					)
				)
				(pin input line
					(at 0 -5.08 0)
					(length 2.54)
					(name "EN"
						(effects
							(font
								(size 1.27 1.27)
							)
						)
					)
					(number "11"
						(effects
							(font
								(size 1.27 1.27)
							)
						)
					)
				)
				(pin power_out line
					(at 0 -7.62 0)
					(length 2.54)
					(name "VCC"
						(effects
							(font
								(size 1.27 1.27)
							)
						)
					)
					(number "8"
						(effects
							(font
								(size 1.27 1.27)
							)
						)
					)
				)
				(pin power_in line
					(at 0 -15.24 0)
					(length 2.54)
					(name "AGND"
						(effects
							(font
								(size 1.27 1.27)
							)
						)
					)
					(number "9"
						(effects
							(font
								(size 1.27 1.27)
							)
						)
					)
				)
				(pin power_in line
					(at 0 -17.78 0)
					(length 2.54)
					(name "PGND"
						(effects
							(font
								(size 1.27 1.27)
							)
						)
					)
					(number "2"
						(effects
							(font
								(size 1.27 1.27)
							)
						)
					)
				)
				(pin passive line
					(at 0 -17.78 0)
					(length 2.54)
					(hide yes)
					(name "PGND"
						(effects
							(font
								(size 1.27 1.27)
							)
						)
					)
					(number "3"
						(effects
							(font
								(size 1.27 1.27)
							)
						)
					)
				)
				(pin passive line
					(at 0 -17.78 0)
					(length 2.54)
					(hide yes)
					(name "PGND"
						(effects
							(font
								(size 1.27 1.27)
							)
						)
					)
					(number "4"
						(effects
							(font
								(size 1.27 1.27)
							)
						)
					)
				)
				(pin input line
					(at 17.78 0 180)
					(length 2.54)
					(name "BST"
						(effects
							(font
								(size 1.27 1.27)
							)
						)
					)
					(number "7"
						(effects
							(font
								(size 1.27 1.27)
							)
						)
					)
				)
				(pin power_out line
					(at 17.78 -2.54 180)
					(length 2.54)
					(name "SW"
						(effects
							(font
								(size 1.27 1.27)
							)
						)
					)
					(number "6"
						(effects
							(font
								(size 1.27 1.27)
							)
						)
					)
				)
				(pin input line
					(at 17.78 -10.16 180)
					(length 2.54)
					(name "FB"
						(effects
							(font
								(size 1.27 1.27)
							)
						)
					)
					(number "10"
						(effects
							(font
								(size 1.27 1.27)
							)
						)
					)
				)
				(pin open_collector line
					(at 17.78 -15.24 180)
					(length 2.54)
					(name "PG"
						(effects
							(font
								(size 1.27 1.27)
							)
						)
					)
					(number "5"
						(effects
							(font
								(size 1.27 1.27)
							)
						)
					)
				)
			)
		)
	(symbol "antmicroDCDCConverters:SIC437AED-T1-GE3"
			(exclude_from_sim no)
			(in_bom yes)
			(on_board yes)
			(property "Reference" "U"
				(at 33.02 -2.54 0)
				(effects
					(font
						(size 1.27 1.27)
						(thickness 0.15)
					)
					(justify left bottom)
				)
			)
			(property "Value" "SIC437AED-T1-GE3"
				(at 33.02 -7.62 0)
				(effects
					(font
						(size 1.27 1.27)
						(thickness 0.15)
					)
					(justify left bottom)
					(hide yes)
				)
			)
			(property "Footprint" "antmicro-footprints:MLP44-24L_4x4x0.75mm"
				(at 33.02 -10.16 0)
				(effects
					(font
						(size 1.27 1.27)
						(thickness 0.15)
					)
					(justify left bottom)
					(hide yes)
				)
			)
			(property "Datasheet" "https://www.vishay.com/docs/75921/sic437.pdf"
				(at 33.02 -12.7 0)
				(effects
					(font
						(size 1.27 1.27)
						(thickness 0.15)
					)
					(justify left bottom)
					(hide yes)
				)
			)
			(property "Description" "DC/DC Buck Step Down Regulator Adjustable, 4.5-28V In, 0.6V to 20V/12A Out, 1MHz, PowerPAK MLP44-24"
				(at 33.02 -22.86 0)
				(effects
					(font
						(size 1.27 1.27)
					)
					(justify left bottom)
					(hide yes)
				)
			)
			(property "Manufacturer" "Vishay"
				(at 33.02 -15.24 0)
				(effects
					(font
						(size 1.27 1.27)
						(thickness 0.15)
					)
					(justify left bottom)
					(hide yes)
				)
			)
			(property "MPN" "SIC437AED-T1-GE3"
				(at 33.02 -5.08 0)
				(effects
					(font
						(size 1.27 1.27)
						(thickness 0.15)
					)
					(justify left bottom)
				)
			)
			(property "Author" "Antmicro"
				(at 33.02 -17.78 0)
				(effects
					(font
						(size 1.27 1.27)
						(thickness 0.15)
					)
					(justify left bottom)
					(hide yes)
				)
			)
			(property "License" "Apache-2.0"
				(at 33.02 -20.32 0)
				(effects
					(font
						(size 1.27 1.27)
						(thickness 0.15)
					)
					(justify left bottom)
					(hide yes)
				)
			)
			(property "ki_keywords" "SMT, PMIC, IC, DC-DC, CONVERTER, SWITCHING, VOLTAGE"
				(at 0 0 0)
				(effects
					(font
						(size 1.27 1.27)
					)
					(hide yes)
				)
			)
			(symbol "SIC437AED-T1-GE3_1_1"
				(rectangle
					(start 2.54 2.54)
					(end 19.05 -22.86)
					(stroke
						(width 0.254)
						(type default)
					)
					(fill
						(type background)
					)
				)
				(pin power_in line
					(at 0 0 0)
					(length 2.54)
					(name "V_{IN}"
						(effects
							(font
								(size 1.27 1.27)
							)
						)
					)
					(number "1"
						(effects
							(font
								(size 1.27 1.27)
							)
						)
					)
				)
				(pin passive line
					(at 0 0 0)
					(length 2.54)
					(hide yes)
					(name "V_{IN}"
						(effects
							(font
								(size 1.27 1.27)
							)
						)
					)
					(number "2"
						(effects
							(font
								(size 1.27 1.27)
							)
						)
					)
				)
				(pin passive line
					(at 0 0 0)
					(length 2.54)
					(hide yes)
					(name "V_{IN}"
						(effects
							(font
								(size 1.27 1.27)
							)
						)
					)
					(number "22"
						(effects
							(font
								(size 1.27 1.27)
							)
						)
					)
				)
				(pin passive line
					(at 0 0 0)
					(length 2.54)
					(hide yes)
					(name "V_{IN}"
						(effects
							(font
								(size 1.27 1.27)
							)
						)
					)
					(number "26"
						(effects
							(font
								(size 1.27 1.27)
							)
						)
					)
				)
				(pin input line
					(at 0 -7.62 0)
					(length 2.54)
					(name "EN"
						(effects
							(font
								(size 1.27 1.27)
							)
						)
					)
					(number "19"
						(effects
							(font
								(size 1.27 1.27)
							)
						)
					)
				)
				(pin input line
					(at 0 -10.16 0)
					(length 2.54)
					(name "MODE1"
						(effects
							(font
								(size 1.27 1.27)
							)
						)
					)
					(number "21"
						(effects
							(font
								(size 1.27 1.27)
							)
						)
					)
				)
				(pin input line
					(at 0 -12.7 0)
					(length 2.54)
					(name "MODE2"
						(effects
							(font
								(size 1.27 1.27)
							)
						)
					)
					(number "20"
						(effects
							(font
								(size 1.27 1.27)
							)
						)
					)
				)
				(pin passive line
					(at 0 -15.24 0)
					(length 2.54)
					(name "V_{DD}"
						(effects
							(font
								(size 1.27 1.27)
							)
						)
					)
					(number "15"
						(effects
							(font
								(size 1.27 1.27)
							)
						)
					)
				)
				(pin passive line
					(at 0 -17.78 0)
					(length 2.54)
					(name "V_{DRV}"
						(effects
							(font
								(size 1.27 1.27)
							)
						)
					)
					(number "12"
						(effects
							(font
								(size 1.27 1.27)
							)
						)
					)
				)
				(pin output line
					(at 0 -20.32 0)
					(length 2.54)
					(name "P_{GOOD}"
						(effects
							(font
								(size 1.27 1.27)
							)
						)
					)
					(number "14"
						(effects
							(font
								(size 1.27 1.27)
							)
						)
					)
				)
				(pin passive line
					(at 21.59 0 180)
					(length 2.54)
					(name "BOOT"
						(effects
							(font
								(size 1.27 1.27)
							)
						)
					)
					(number "23"
						(effects
							(font
								(size 1.27 1.27)
							)
						)
					)
				)
				(pin passive line
					(at 21.59 -2.54 180)
					(length 2.54)
					(name "PHASE"
						(effects
							(font
								(size 1.27 1.27)
							)
						)
					)
					(number "24"
						(effects
							(font
								(size 1.27 1.27)
							)
						)
					)
				)
				(pin passive line
					(at 21.59 -5.08 180)
					(length 2.54)
					(name "SW"
						(effects
							(font
								(size 1.27 1.27)
							)
						)
					)
					(number "5"
						(effects
							(font
								(size 1.27 1.27)
							)
						)
					)
				)
				(pin passive line
					(at 21.59 -5.08 180)
					(length 2.54)
					(hide yes)
					(name "SW"
						(effects
							(font
								(size 1.27 1.27)
							)
						)
					)
					(number "6"
						(effects
							(font
								(size 1.27 1.27)
							)
						)
					)
				)
				(pin passive line
					(at 21.59 -5.08 180)
					(length 2.54)
					(hide yes)
					(name "SW"
						(effects
							(font
								(size 1.27 1.27)
							)
						)
					)
					(number "7"
						(effects
							(font
								(size 1.27 1.27)
							)
						)
					)
				)
				(pin passive line
					(at 21.59 -5.08 180)
					(length 2.54)
					(hide yes)
					(name "SW"
						(effects
							(font
								(size 1.27 1.27)
							)
						)
					)
					(number "8"
						(effects
							(font
								(size 1.27 1.27)
							)
						)
					)
				)
				(pin passive line
					(at 21.59 -5.08 180)
					(length 2.54)
					(hide yes)
					(name "SW"
						(effects
							(font
								(size 1.27 1.27)
							)
						)
					)
					(number "9"
						(effects
							(font
								(size 1.27 1.27)
							)
						)
					)
				)
				(pin passive line
					(at 21.59 -7.62 180)
					(length 2.54)
					(name "GL"
						(effects
							(font
								(size 1.27 1.27)
							)
						)
					)
					(number "10"
						(effects
							(font
								(size 1.27 1.27)
							)
						)
					)
				)
				(pin passive line
					(at 21.59 -7.62 180)
					(length 2.54)
					(hide yes)
					(name "GL"
						(effects
							(font
								(size 1.27 1.27)
							)
						)
					)
					(number "11"
						(effects
							(font
								(size 1.27 1.27)
							)
						)
					)
				)
				(pin passive line
					(at 21.59 -7.62 180)
					(length 2.54)
					(hide yes)
					(name "GL"
						(effects
							(font
								(size 1.27 1.27)
							)
						)
					)
					(number "28"
						(effects
							(font
								(size 1.27 1.27)
							)
						)
					)
				)
				(pin passive line
					(at 21.59 -10.16 180)
					(length 2.54)
					(name "V_{OUT}"
						(effects
							(font
								(size 1.27 1.27)
							)
						)
					)
					(number "18"
						(effects
							(font
								(size 1.27 1.27)
							)
						)
					)
				)
				(pin passive line
					(at 21.59 -12.7 180)
					(length 2.54)
					(name "FB"
						(effects
							(font
								(size 1.27 1.27)
							)
						)
					)
					(number "17"
						(effects
							(font
								(size 1.27 1.27)
							)
						)
					)
				)
				(pin power_in line
					(at 21.59 -17.78 180)
					(length 2.54)
					(name "A_{GND}"
						(effects
							(font
								(size 1.27 1.27)
							)
						)
					)
					(number "16"
						(effects
							(font
								(size 1.27 1.27)
							)
						)
					)
				)
				(pin passive line
					(at 21.59 -17.78 180)
					(length 2.54)
					(hide yes)
					(name "A_{GND}"
						(effects
							(font
								(size 1.27 1.27)
							)
						)
					)
					(number "25"
						(effects
							(font
								(size 1.27 1.27)
							)
						)
					)
				)
				(pin power_in line
					(at 21.59 -20.32 180)
					(length 2.54)
					(name "P_{GND}"
						(effects
							(font
								(size 1.27 1.27)
							)
						)
					)
					(number "13"
						(effects
							(font
								(size 1.27 1.27)
							)
						)
					)
				)
				(pin passive line
					(at 21.59 -20.32 180)
					(length 2.54)
					(hide yes)
					(name "P_{GND}"
						(effects
							(font
								(size 1.27 1.27)
							)
						)
					)
					(number "27"
						(effects
							(font
								(size 1.27 1.27)
							)
						)
					)
				)
				(pin passive line
					(at 21.59 -20.32 180)
					(length 2.54)
					(hide yes)
					(name "P_{GND}"
						(effects
							(font
								(size 1.27 1.27)
							)
						)
					)
					(number "3"
						(effects
							(font
								(size 1.27 1.27)
							)
						)
					)
				)
				(pin passive line
					(at 21.59 -20.32 180)
					(length 2.54)
					(hide yes)
					(name "P_{GND}"
						(effects
							(font
								(size 1.27 1.27)
							)
						)
					)
					(number "4"
						(effects
							(font
								(size 1.27 1.27)
							)
						)
					)
				)
			)
		)
	(symbol "antmicroDCDCConverters:TPS566231P"
			(exclude_from_sim no)
			(in_bom yes)
			(on_board yes)
			(property "Reference" "U"
				(at 33.02 -2.54 0)
				(effects
					(font
						(size 1.27 1.27)
						(thickness 0.15)
					)
					(justify left bottom)
				)
			)
			(property "Value" "TPS566231P"
				(at 33.02 -5.08 0)
				(effects
					(font
						(size 1.27 1.27)
						(thickness 0.15)
					)
					(justify left bottom)
					(hide yes)
				)
			)
			(property "Footprint" "antmicro-footprints:VQFN-HR-9_2x1.5mm"
				(at 33.02 -7.62 0)
				(effects
					(font
						(size 1.27 1.27)
						(thickness 0.15)
					)
					(justify left bottom)
					(hide yes)
				)
			)
			(property "Datasheet" "https://www.ti.com/lit/ds/symlink/tps566231.pdf"
				(at 33.02 -10.16 0)
				(effects
					(font
						(size 1.27 1.27)
						(thickness 0.15)
					)
					(justify left bottom)
					(hide yes)
				)
			)
			(property "Description" "Switching Voltage Regulators 3-V to 18-V, 6-A synchronous buck converter"
				(at 33.02 -22.86 0)
				(effects
					(font
						(size 1.27 1.27)
					)
					(justify left bottom)
					(hide yes)
				)
			)
			(property "Manufacturer" "Texas Instruments"
				(at 33.02 -12.7 0)
				(effects
					(font
						(size 1.27 1.27)
						(thickness 0.15)
					)
					(justify left bottom)
					(hide yes)
				)
			)
			(property "MPN" "TPS566231PRQFR"
				(at 33.02 -15.24 0)
				(effects
					(font
						(size 1.27 1.27)
						(thickness 0.15)
					)
					(justify left bottom)
				)
			)
			(property "Author" "Antmicro"
				(at 33.02 -17.78 0)
				(effects
					(font
						(size 1.27 1.27)
						(thickness 0.15)
					)
					(justify left bottom)
					(hide yes)
				)
			)
			(property "License" "Apache-2.0"
				(at 33.02 -20.32 0)
				(effects
					(font
						(size 1.27 1.27)
						(thickness 0.15)
					)
					(justify left bottom)
					(hide yes)
				)
			)
			(property "ki_keywords" "SMT, PMIC, IC, SWITCHING, VOLTAGE, REGULATOR, DC-DC"
				(at 0 0 0)
				(effects
					(font
						(size 1.27 1.27)
					)
					(hide yes)
				)
			)
			(symbol "TPS566231P_1_1"
				(rectangle
					(start 2.54 2.54)
					(end 15.24 -17.78)
					(stroke
						(width 0.254)
						(type default)
					)
					(fill
						(type background)
					)
				)
				(pin power_in line
					(at 0 0 0)
					(length 2.54)
					(name "V_{IN}"
						(effects
							(font
								(size 1.27 1.27)
							)
						)
					)
					(number "5"
						(effects
							(font
								(size 1.27 1.27)
							)
						)
					)
				)
				(pin passive line
					(at 0 0 0)
					(length 2.54)
					(hide yes)
					(name "V_{IN}"
						(effects
							(font
								(size 1.27 1.27)
							)
						)
					)
					(number "6"
						(effects
							(font
								(size 1.27 1.27)
							)
						)
					)
				)
				(pin passive line
					(at 0 -2.54 0)
					(length 2.54)
					(name "V_{CC}"
						(effects
							(font
								(size 1.27 1.27)
							)
						)
					)
					(number "1"
						(effects
							(font
								(size 1.27 1.27)
							)
						)
					)
				)
				(pin input line
					(at 0 -10.16 0)
					(length 2.54)
					(name "EN"
						(effects
							(font
								(size 1.27 1.27)
							)
						)
					)
					(number "3"
						(effects
							(font
								(size 1.27 1.27)
							)
						)
					)
				)
				(pin passive line
					(at 0 -15.24 0)
					(length 2.54)
					(name "PG"
						(effects
							(font
								(size 1.27 1.27)
							)
						)
					)
					(number "9"
						(effects
							(font
								(size 1.27 1.27)
							)
						)
					)
				)
				(pin power_out line
					(at 17.78 0 180)
					(length 2.54)
					(name "SW"
						(effects
							(font
								(size 1.27 1.27)
							)
						)
					)
					(number "8"
						(effects
							(font
								(size 1.27 1.27)
							)
						)
					)
				)
				(pin passive line
					(at 17.78 -5.08 180)
					(length 2.54)
					(name "BST"
						(effects
							(font
								(size 1.27 1.27)
							)
						)
					)
					(number "7"
						(effects
							(font
								(size 1.27 1.27)
							)
						)
					)
				)
				(pin input line
					(at 17.78 -10.16 180)
					(length 2.54)
					(name "FB"
						(effects
							(font
								(size 1.27 1.27)
							)
						)
					)
					(number "2"
						(effects
							(font
								(size 1.27 1.27)
							)
						)
					)
				)
				(pin power_in line
					(at 17.78 -15.24 180)
					(length 2.54)
					(name "PGND"
						(effects
							(font
								(size 1.27 1.27)
							)
						)
					)
					(number "4"
						(effects
							(font
								(size 1.27 1.27)
							)
						)
					)
				)
			)
		)
	(symbol "antmicroDiodesRectifiersSingle:RB521S30T1G"
			(pin_numbers
				(hide yes)
			)
			(pin_names
				(hide yes)
			)
			(exclude_from_sim no)
			(in_bom yes)
			(on_board yes)
			(property "Reference" "D"
				(at 22.86 -5.08 0)
				(effects
					(font
						(size 1.27 1.27)
						(thickness 0.15)
					)
					(justify left bottom)
				)
			)
			(property "Value" "RB521S30T1G"
				(at 22.86 -15.24 0)
				(effects
					(font
						(size 1.27 1.27)
						(thickness 0.15)
					)
					(justify left bottom)
					(hide yes)
				)
			)
			(property "Footprint" "antmicro-footprints:SOD-523"
				(at 22.86 -10.16 0)
				(effects
					(font
						(size 1.27 1.27)
						(thickness 0.15)
					)
					(justify left bottom)
					(hide yes)
				)
			)
			(property "Datasheet" "https://www.onsemi.com/pdf/datasheet/rb521s30t1-d.pdf"
				(at 22.86 -12.7 0)
				(effects
					(font
						(size 1.27 1.27)
						(thickness 0.15)
					)
					(justify left bottom)
					(hide yes)
				)
			)
			(property "Description" "Small Signal Schottky Diode, Single, 30 V, 200 mA, 500 mV, 1 A, 125 °C"
				(at 22.86 -25.4 0)
				(effects
					(font
						(size 1.27 1.27)
					)
					(justify left bottom)
					(hide yes)
				)
			)
			(property "MPN" "RB521S30T1G"
				(at 22.86 -7.62 0)
				(effects
					(font
						(size 1.27 1.27)
						(thickness 0.15)
					)
					(justify left bottom)
				)
			)
			(property "Manufacturer" "ON Semiconductor"
				(at 22.86 -17.78 0)
				(effects
					(font
						(size 1.27 1.27)
						(thickness 0.15)
					)
					(justify left bottom)
					(hide yes)
				)
			)
			(property "Author" "Antmicro"
				(at 22.86 -20.32 0)
				(effects
					(font
						(size 1.27 1.27)
						(thickness 0.15)
					)
					(justify left bottom)
					(hide yes)
				)
			)
			(property "License" "Apache-2.0"
				(at 22.86 -22.86 0)
				(effects
					(font
						(size 1.27 1.27)
						(thickness 0.15)
					)
					(justify left bottom)
					(hide yes)
				)
			)
			(property "ki_keywords" "SMT, SEMICONDUCTOR, DIODE, SCHOTTKY"
				(at 0 0 0)
				(effects
					(font
						(size 1.27 1.27)
					)
					(hide yes)
				)
			)
			(symbol "RB521S30T1G_0_1"
				(polyline
					(pts
						(xy 1.905 0) (xy 0.635 0)
					)
					(stroke
						(width 0)
						(type default)
					)
					(fill
						(type none)
					)
				)
				(polyline
					(pts
						(xy 4.445 0) (xy 3.175 0)
					)
					(stroke
						(width 0)
						(type default)
					)
					(fill
						(type none)
					)
				)
			)
			(symbol "RB521S30T1G_1_1"
				(polyline
					(pts
						(xy 1.778 1.016) (xy 1.778 -1.016)
					)
					(stroke
						(width 0.254)
						(type default)
					)
					(fill
						(type none)
					)
				)
				(polyline
					(pts
						(xy 1.778 1.016) (xy 1.397 1.016) (xy 1.397 0.762)
					)
					(stroke
						(width 0.254)
						(type default)
					)
					(fill
						(type none)
					)
				)
				(polyline
					(pts
						(xy 1.778 -1.016) (xy 2.159 -1.016) (xy 2.159 -0.762)
					)
					(stroke
						(width 0.254)
						(type default)
					)
					(fill
						(type none)
					)
				)
				(polyline
					(pts
						(xy 3.302 1.016) (xy 3.302 -1.016) (xy 1.778 0) (xy 3.302 1.016)
					)
					(stroke
						(width 0.254)
						(type default)
					)
					(fill
						(type outline)
					)
				)
				(pin passive line
					(at 0 0 0)
					(length 0.635)
					(name "C"
						(effects
							(font
								(size 1.27 1.27)
							)
						)
					)
					(number "1"
						(effects
							(font
								(size 1.27 1.27)
							)
						)
					)
				)
				(pin passive line
					(at 5.08 0 180)
					(length 0.635)
					(name "A"
						(effects
							(font
								(size 1.27 1.27)
							)
						)
					)
					(number "2"
						(effects
							(font
								(size 1.27 1.27)
							)
						)
					)
				)
			)
		)
	(symbol "antmicroDiodesZenerSingle:MM3Z3V3C"
			(pin_numbers
				(hide yes)
			)
			(pin_names
				(hide yes)
			)
			(exclude_from_sim no)
			(in_bom yes)
			(on_board yes)
			(property "Reference" "D"
				(at 22.86 -5.08 0)
				(effects
					(font
						(size 1.27 1.27)
						(thickness 0.15)
					)
					(justify left bottom)
				)
			)
			(property "Value" "MM3Z3V3C"
				(at 22.86 -15.24 0)
				(effects
					(font
						(size 1.27 1.27)
						(thickness 0.15)
					)
					(justify left bottom)
					(hide yes)
				)
			)
			(property "Footprint" "antmicro-footprints:D_SOD-323F"
				(at 22.86 -10.16 0)
				(effects
					(font
						(size 1.27 1.27)
						(thickness 0.15)
					)
					(justify left bottom)
					(hide yes)
				)
			)
			(property "Datasheet" "https://www.onsemi.com/download/data-sheet/pdf/mm3z9v1c-d.pdf"
				(at 22.86 -12.7 0)
				(effects
					(font
						(size 1.27 1.27)
						(thickness 0.15)
					)
					(justify left bottom)
					(hide yes)
				)
			)
			(property "Description" "Zener Single Diode, 3.3 V, 200 mW, SOD-323F, 2 Pins, 150 °C, Surface Mount"
				(at 22.86 -25.4 0)
				(effects
					(font
						(size 1.27 1.27)
					)
					(justify left bottom)
					(hide yes)
				)
			)
			(property "MPN" "MM3Z3V3C"
				(at 22.86 -7.62 0)
				(effects
					(font
						(size 1.27 1.27)
						(thickness 0.15)
					)
					(justify left bottom)
				)
			)
			(property "Manufacturer" "ON Semiconductor"
				(at 22.86 -17.78 0)
				(effects
					(font
						(size 1.27 1.27)
						(thickness 0.15)
					)
					(justify left bottom)
					(hide yes)
				)
			)
			(property "Author" "Antmicro"
				(at 22.86 -20.32 0)
				(effects
					(font
						(size 1.27 1.27)
						(thickness 0.15)
					)
					(justify left bottom)
					(hide yes)
				)
			)
			(property "License" "Apache-2.0"
				(at 22.86 -22.86 0)
				(effects
					(font
						(size 1.27 1.27)
						(thickness 0.15)
					)
					(justify left bottom)
					(hide yes)
				)
			)
			(property "ki_keywords" "SMT, DIODE, SEMICONDUCTOR, ZENER"
				(at 0 0 0)
				(effects
					(font
						(size 1.27 1.27)
					)
					(hide yes)
				)
			)
			(symbol "MM3Z3V3C_0_1"
				(polyline
					(pts
						(xy 1.905 0) (xy 0.635 0)
					)
					(stroke
						(width 0)
						(type default)
					)
					(fill
						(type none)
					)
				)
				(polyline
					(pts
						(xy 4.445 0) (xy 3.175 0)
					)
					(stroke
						(width 0)
						(type default)
					)
					(fill
						(type none)
					)
				)
			)
			(symbol "MM3Z3V3C_1_1"
				(polyline
					(pts
						(xy 1.778 -1.016) (xy 1.778 1.016)
					)
					(stroke
						(width 0.254)
						(type default)
					)
					(fill
						(type none)
					)
				)
				(polyline
					(pts
						(xy 2.159 1.016) (xy 1.778 1.016)
					)
					(stroke
						(width 0.254)
						(type default)
					)
					(fill
						(type none)
					)
				)
				(polyline
					(pts
						(xy 3.302 -1.016) (xy 3.302 1.016) (xy 1.778 0) (xy 3.302 -1.016)
					)
					(stroke
						(width 0.254)
						(type default)
					)
					(fill
						(type outline)
					)
				)
				(pin passive line
					(at 0 0 0)
					(length 0.635)
					(name "C"
						(effects
							(font
								(size 1.27 1.27)
							)
						)
					)
					(number "1"
						(effects
							(font
								(size 1.27 1.27)
							)
						)
					)
				)
				(pin passive line
					(at 5.08 0 180)
					(length 0.635)
					(name "A"
						(effects
							(font
								(size 1.27 1.27)
							)
						)
					)
					(number "2"
						(effects
							(font
								(size 1.27 1.27)
							)
						)
					)
				)
			)
		)
	(symbol "antmicroFerriteBeadsandChips:FB_30Z_8.5A_Murata-BLM21SN_0805"
			(pin_numbers
				(hide yes)
			)
			(pin_names
				(hide yes)
			)
			(exclude_from_sim no)
			(in_bom yes)
			(on_board yes)
			(property "Reference" "FB"
				(at 13.97 0 0)
				(effects
					(font
						(size 1.27 1.27)
						(thickness 0.15)
					)
					(justify left bottom)
				)
			)
			(property "Value" "FB_30Z_8.5A_Murata-BLM21SN_0805"
				(at 13.97 -2.54 0)
				(effects
					(font
						(size 1.27 1.27)
						(thickness 0.15)
					)
					(justify left bottom)
					(hide yes)
				)
			)
			(property "Footprint" "antmicro-footprints:FB_0805_2012Metric"
				(at 13.97 -7.62 0)
				(effects
					(font
						(size 1.27 1.27)
						(thickness 0.15)
					)
					(justify left bottom)
					(hide yes)
				)
			)
			(property "Datasheet" "https://www.murata.com/en-sg/products/productdata/8796738977822/ENFA0005.pdf?1519270210000"
				(at 13.97 -10.16 0)
				(effects
					(font
						(size 1.27 1.27)
						(thickness 0.15)
					)
					(justify left bottom)
					(hide yes)
				)
			)
			(property "Description" "Ferrite Bead, 0805 [2012 Metric], 30 ohm, 8.5 A, BLM21SN, 0.004 ohm, ± 10ohm, DC power line"
				(at 13.97 -22.86 0)
				(effects
					(font
						(size 1.27 1.27)
					)
					(justify left bottom)
					(hide yes)
				)
			)
			(property "Val" "30Z/8.5A"
				(at 13.97 -5.08 0)
				(effects
					(font
						(size 1.27 1.27)
					)
					(justify left bottom)
				)
			)
			(property "MPN" "BLM21SN300SZ1D"
				(at 13.97 -12.7 0)
				(effects
					(font
						(size 1.27 1.27)
						(thickness 0.15)
					)
					(justify left bottom)
					(hide yes)
				)
			)
			(property "Manufacturer" "Murata"
				(at 13.97 -15.24 0)
				(effects
					(font
						(size 1.27 1.27)
						(thickness 0.15)
					)
					(justify left bottom)
					(hide yes)
				)
			)
			(property "Current" ""
				(at 20.32 -22.86 0)
				(effects
					(font
						(size 1.27 1.27)
						(thickness 0.15)
					)
					(justify left bottom)
					(hide yes)
				)
			)
			(property "Author" "Antmicro"
				(at 13.97 -17.78 0)
				(effects
					(font
						(size 1.27 1.27)
						(thickness 0.15)
					)
					(justify left bottom)
					(hide yes)
				)
			)
			(property "License" "Apache-2.0"
				(at 13.97 -20.32 0)
				(effects
					(font
						(size 1.27 1.27)
						(thickness 0.15)
					)
					(justify left bottom)
					(hide yes)
				)
			)
			(property "ki_keywords" "0805, SMT, FERRITE BEAD, PASSIVE"
				(at 0 0 0)
				(effects
					(font
						(size 1.27 1.27)
					)
					(hide yes)
				)
			)
			(symbol "FB_30Z_8.5A_Murata-BLM21SN_0805_0_1"
				(polyline
					(pts
						(xy 1.651 0) (xy 1.2446 0)
					)
					(stroke
						(width 0)
						(type default)
					)
					(fill
						(type none)
					)
				)
				(polyline
					(pts
						(xy 2.2606 -1.8288) (xy 1.0414 -1.1176) (xy 2.7432 1.8288) (xy 3.9624 1.1176) (xy 2.2606 -1.8288)
					)
					(stroke
						(width 0)
						(type default)
					)
					(fill
						(type none)
					)
				)
				(polyline
					(pts
						(xy 3.81 0) (xy 3.3274 0)
					)
					(stroke
						(width 0)
						(type default)
					)
					(fill
						(type none)
					)
				)
			)
			(symbol "FB_30Z_8.5A_Murata-BLM21SN_0805_1_1"
				(pin passive line
					(at 0 0 0)
					(length 1.27)
					(name "~"
						(effects
							(font
								(size 1.27 1.27)
							)
						)
					)
					(number "1"
						(effects
							(font
								(size 1.27 1.27)
							)
						)
					)
				)
				(pin passive line
					(at 5.08 0 180)
					(length 1.27)
					(name "~"
						(effects
							(font
								(size 1.27 1.27)
							)
						)
					)
					(number "2"
						(effects
							(font
								(size 1.27 1.27)
							)
						)
					)
				)
			)
		)
	(symbol "antmicroFerriteBeadsandChips:FB_330Z_1.5A_Murata-BLM21PG_0805"
			(pin_numbers
				(hide yes)
			)
			(pin_names
				(hide yes)
			)
			(exclude_from_sim no)
			(in_bom yes)
			(on_board yes)
			(property "Reference" "FB"
				(at 13.97 0 0)
				(effects
					(font
						(size 1.27 1.27)
						(thickness 0.15)
					)
					(justify left bottom)
				)
			)
			(property "Value" "FB_330Z_1.5A_Murata-BLM21PG_0805"
				(at 13.97 -2.54 0)
				(effects
					(font
						(size 1.27 1.27)
						(thickness 0.15)
					)
					(justify left bottom)
					(hide yes)
				)
			)
			(property "Footprint" "antmicro-footprints:FB_0805_2012Metric"
				(at 13.97 -7.62 0)
				(effects
					(font
						(size 1.27 1.27)
						(thickness 0.15)
					)
					(justify left bottom)
					(hide yes)
				)
			)
			(property "Datasheet" "https://www.murata.com/products/productdata/8796738977822/ENFA0005.pdf?1653276712000"
				(at 13.97 -10.16 0)
				(effects
					(font
						(size 1.27 1.27)
						(thickness 0.15)
					)
					(justify left bottom)
					(hide yes)
				)
			)
			(property "Description" "Ferrite Bead, 0805 [2012 Metric], 330 ohm, 1.5 A, BLM21P, 0.07 ohm, ± 25%, DC power line"
				(at 13.97 -22.86 0)
				(effects
					(font
						(size 1.27 1.27)
					)
					(justify left bottom)
					(hide yes)
				)
			)
			(property "Val" "330Z/1.5A"
				(at 13.97 -5.08 0)
				(effects
					(font
						(size 1.27 1.27)
					)
					(justify left bottom)
				)
			)
			(property "MPN" "BLM21PG331SN1D"
				(at 13.97 -12.7 0)
				(effects
					(font
						(size 1.27 1.27)
						(thickness 0.15)
					)
					(justify left bottom)
					(hide yes)
				)
			)
			(property "Manufacturer" "Murata"
				(at 13.97 -15.24 0)
				(effects
					(font
						(size 1.27 1.27)
						(thickness 0.15)
					)
					(justify left bottom)
					(hide yes)
				)
			)
			(property "Current" ""
				(at 20.32 -22.86 0)
				(effects
					(font
						(size 1.27 1.27)
						(thickness 0.15)
					)
					(justify left bottom)
					(hide yes)
				)
			)
			(property "Author" "Antmicro"
				(at 13.97 -17.78 0)
				(effects
					(font
						(size 1.27 1.27)
						(thickness 0.15)
					)
					(justify left bottom)
					(hide yes)
				)
			)
			(property "License" "Apache-2.0"
				(at 13.97 -20.32 0)
				(effects
					(font
						(size 1.27 1.27)
						(thickness 0.15)
					)
					(justify left bottom)
					(hide yes)
				)
			)
			(property "ki_keywords" "0805, SMT, FERRITE BEAD, PASSIVE"
				(at 0 0 0)
				(effects
					(font
						(size 1.27 1.27)
					)
					(hide yes)
				)
			)
			(symbol "FB_330Z_1.5A_Murata-BLM21PG_0805_0_1"
				(polyline
					(pts
						(xy 1.651 0) (xy 1.2446 0)
					)
					(stroke
						(width 0)
						(type default)
					)
					(fill
						(type none)
					)
				)
				(polyline
					(pts
						(xy 2.2606 -1.8288) (xy 1.0414 -1.1176) (xy 2.7432 1.8288) (xy 3.9624 1.1176) (xy 2.2606 -1.8288)
					)
					(stroke
						(width 0)
						(type default)
					)
					(fill
						(type none)
					)
				)
				(polyline
					(pts
						(xy 3.81 0) (xy 3.3274 0)
					)
					(stroke
						(width 0)
						(type default)
					)
					(fill
						(type none)
					)
				)
			)
			(symbol "FB_330Z_1.5A_Murata-BLM21PG_0805_1_1"
				(pin passive line
					(at 0 0 0)
					(length 1.27)
					(name "~"
						(effects
							(font
								(size 1.27 1.27)
							)
						)
					)
					(number "1"
						(effects
							(font
								(size 1.27 1.27)
							)
						)
					)
				)
				(pin passive line
					(at 5.08 0 180)
					(length 1.27)
					(name "~"
						(effects
							(font
								(size 1.27 1.27)
							)
						)
					)
					(number "2"
						(effects
							(font
								(size 1.27 1.27)
							)
						)
					)
				)
			)
		)
	(symbol "antmicroFerriteBeadsandChips:FB_33Z_3A_Murata-BLM18PG_0603"
			(pin_numbers
				(hide yes)
			)
			(pin_names
				(hide yes)
			)
			(exclude_from_sim no)
			(in_bom yes)
			(on_board yes)
			(property "Reference" "FB"
				(at 13.97 0 0)
				(effects
					(font
						(size 1.27 1.27)
						(thickness 0.15)
					)
					(justify left bottom)
				)
			)
			(property "Value" "FB_33Z_3A_Murata-BLM18PG_0603"
				(at 13.97 -2.54 0)
				(effects
					(font
						(size 1.27 1.27)
						(thickness 0.15)
					)
					(justify left bottom)
					(hide yes)
				)
			)
			(property "Footprint" "antmicro-footprints:FB_0603_1608Metric"
				(at 13.97 -7.62 0)
				(effects
					(font
						(size 1.27 1.27)
						(thickness 0.15)
					)
					(justify left bottom)
					(hide yes)
				)
			)
			(property "Datasheet" "https://www.murata.com/products/productdata/8796737273886/QNFA9101.pdf?1649080818000"
				(at 13.97 -10.16 0)
				(effects
					(font
						(size 1.27 1.27)
						(thickness 0.15)
					)
					(justify left bottom)
					(hide yes)
				)
			)
			(property "Description" "Ferrite Bead, 0603 [1608 Metric], 33 ohm, 3 A, BLM18PG, 0.025 ohm, ± 25%, DC power line"
				(at 13.97 -22.86 0)
				(effects
					(font
						(size 1.27 1.27)
					)
					(justify left bottom)
					(hide yes)
				)
			)
			(property "Val" "33Z/3A"
				(at 13.97 -5.08 0)
				(effects
					(font
						(size 1.27 1.27)
					)
					(justify left bottom)
				)
			)
			(property "MPN" "BLM18PG330SH1D"
				(at 13.97 -12.7 0)
				(effects
					(font
						(size 1.27 1.27)
						(thickness 0.15)
					)
					(justify left bottom)
					(hide yes)
				)
			)
			(property "Manufacturer" "Murata"
				(at 13.97 -15.24 0)
				(effects
					(font
						(size 1.27 1.27)
						(thickness 0.15)
					)
					(justify left bottom)
					(hide yes)
				)
			)
			(property "Current" ""
				(at 20.32 -22.86 0)
				(effects
					(font
						(size 1.27 1.27)
						(thickness 0.15)
					)
					(justify left bottom)
					(hide yes)
				)
			)
			(property "Author" "Antmicro"
				(at 13.97 -17.78 0)
				(effects
					(font
						(size 1.27 1.27)
						(thickness 0.15)
					)
					(justify left bottom)
					(hide yes)
				)
			)
			(property "License" "Apache-2.0"
				(at 13.97 -20.32 0)
				(effects
					(font
						(size 1.27 1.27)
						(thickness 0.15)
					)
					(justify left bottom)
					(hide yes)
				)
			)
			(property "ki_keywords" "0603, SMT, FERRITE BEAD, PASSIVE"
				(at 0 0 0)
				(effects
					(font
						(size 1.27 1.27)
					)
					(hide yes)
				)
			)
			(symbol "FB_33Z_3A_Murata-BLM18PG_0603_0_1"
				(polyline
					(pts
						(xy 1.651 0) (xy 1.2446 0)
					)
					(stroke
						(width 0)
						(type default)
					)
					(fill
						(type none)
					)
				)
				(polyline
					(pts
						(xy 2.2606 -1.8288) (xy 1.0414 -1.1176) (xy 2.7432 1.8288) (xy 3.9624 1.1176) (xy 2.2606 -1.8288)
					)
					(stroke
						(width 0)
						(type default)
					)
					(fill
						(type none)
					)
				)
				(polyline
					(pts
						(xy 3.81 0) (xy 3.3274 0)
					)
					(stroke
						(width 0)
						(type default)
					)
					(fill
						(type none)
					)
				)
			)
			(symbol "FB_33Z_3A_Murata-BLM18PG_0603_1_1"
				(pin passive line
					(at 0 0 0)
					(length 1.27)
					(name "~"
						(effects
							(font
								(size 1.27 1.27)
							)
						)
					)
					(number "1"
						(effects
							(font
								(size 1.27 1.27)
							)
						)
					)
				)
				(pin passive line
					(at 5.08 0 180)
					(length 1.27)
					(name "~"
						(effects
							(font
								(size 1.27 1.27)
							)
						)
					)
					(number "2"
						(effects
							(font
								(size 1.27 1.27)
							)
						)
					)
				)
			)
		)
	(symbol "antmicroFerriteBeadsandChips:FB_470Z_1A_Murata-BLM18PG_0603"
			(pin_numbers
				(hide yes)
			)
			(pin_names
				(hide yes)
			)
			(exclude_from_sim no)
			(in_bom yes)
			(on_board yes)
			(property "Reference" "FB"
				(at 13.97 0 0)
				(effects
					(font
						(size 1.27 1.27)
						(thickness 0.15)
					)
					(justify left bottom)
				)
			)
			(property "Value" "FB_470Z_1A_Murata-BLM18PG_0603"
				(at 13.97 -2.54 0)
				(effects
					(font
						(size 1.27 1.27)
						(thickness 0.15)
					)
					(justify left bottom)
					(hide yes)
				)
			)
			(property "Footprint" "antmicro-footprints:FB_0603_1608Metric"
				(at 13.97 -7.62 0)
				(effects
					(font
						(size 1.27 1.27)
						(thickness 0.15)
					)
					(justify left bottom)
					(hide yes)
				)
			)
			(property "Datasheet" "https://www.murata.com/en-us/products/productdata/8796738650142/ENFA0003.pdf"
				(at 13.97 -10.16 0)
				(effects
					(font
						(size 1.27 1.27)
						(thickness 0.15)
					)
					(justify left bottom)
					(hide yes)
				)
			)
			(property "Description" "Ferrite Bead, 0603 [1608 Metric], 470 ohm, 1 A, BLM18P, 0.2 ohm, ± 25%, DC power line"
				(at 13.97 -22.86 0)
				(effects
					(font
						(size 1.27 1.27)
					)
					(justify left bottom)
					(hide yes)
				)
			)
			(property "Val" "470Z/1A"
				(at 13.97 -5.08 0)
				(effects
					(font
						(size 1.27 1.27)
					)
					(justify left bottom)
				)
			)
			(property "MPN" "BLM18PG471SN1D"
				(at 13.97 -12.7 0)
				(effects
					(font
						(size 1.27 1.27)
						(thickness 0.15)
					)
					(justify left bottom)
					(hide yes)
				)
			)
			(property "Manufacturer" "Murata"
				(at 13.97 -15.24 0)
				(effects
					(font
						(size 1.27 1.27)
						(thickness 0.15)
					)
					(justify left bottom)
					(hide yes)
				)
			)
			(property "Current" ""
				(at 20.32 -22.86 0)
				(effects
					(font
						(size 1.27 1.27)
						(thickness 0.15)
					)
					(justify left bottom)
					(hide yes)
				)
			)
			(property "Author" "Antmicro"
				(at 13.97 -17.78 0)
				(effects
					(font
						(size 1.27 1.27)
						(thickness 0.15)
					)
					(justify left bottom)
					(hide yes)
				)
			)
			(property "License" "Apache-2.0"
				(at 13.97 -20.32 0)
				(effects
					(font
						(size 1.27 1.27)
						(thickness 0.15)
					)
					(justify left bottom)
					(hide yes)
				)
			)
			(property "ki_keywords" "0603, SMT, FERRITE BEAD, PASSIVE"
				(at 0 0 0)
				(effects
					(font
						(size 1.27 1.27)
					)
					(hide yes)
				)
			)
			(symbol "FB_470Z_1A_Murata-BLM18PG_0603_0_1"
				(polyline
					(pts
						(xy 1.651 0) (xy 1.2446 0)
					)
					(stroke
						(width 0)
						(type default)
					)
					(fill
						(type none)
					)
				)
				(polyline
					(pts
						(xy 2.2606 -1.8288) (xy 1.0414 -1.1176) (xy 2.7432 1.8288) (xy 3.9624 1.1176) (xy 2.2606 -1.8288)
					)
					(stroke
						(width 0)
						(type default)
					)
					(fill
						(type none)
					)
				)
				(polyline
					(pts
						(xy 3.81 0) (xy 3.3274 0)
					)
					(stroke
						(width 0)
						(type default)
					)
					(fill
						(type none)
					)
				)
			)
			(symbol "FB_470Z_1A_Murata-BLM18PG_0603_1_1"
				(pin passive line
					(at 0 0 0)
					(length 1.27)
					(name "~"
						(effects
							(font
								(size 1.27 1.27)
							)
						)
					)
					(number "1"
						(effects
							(font
								(size 1.27 1.27)
							)
						)
					)
				)
				(pin passive line
					(at 5.08 0 180)
					(length 1.27)
					(name "~"
						(effects
							(font
								(size 1.27 1.27)
							)
						)
					)
					(number "2"
						(effects
							(font
								(size 1.27 1.27)
							)
						)
					)
				)
			)
		)
	(symbol "antmicroFiducialMarks:Fiducial_1mm_Mask2mm"
			(exclude_from_sim no)
			(in_bom no)
			(on_board yes)
			(property "Reference" "FD"
				(at 8.89 0 0)
				(effects
					(font
						(size 1.27 1.27)
						(thickness 0.15)
					)
					(justify left bottom)
				)
			)
			(property "Value" "Fiducial_1mm_Mask2mm"
				(at 8.89 -2.54 0)
				(effects
					(font
						(size 1.27 1.27)
						(thickness 0.15)
					)
					(justify left bottom)
				)
			)
			(property "Footprint" "antmicro-footprints:Fiducial_1mm_Mask2mm"
				(at 8.89 -5.08 0)
				(effects
					(font
						(size 1.27 1.27)
						(thickness 0.15)
					)
					(justify left bottom)
					(hide yes)
				)
			)
			(property "Datasheet" ""
				(at 9.22 -10.49 0)
				(effects
					(font
						(size 1.27 1.27)
						(thickness 0.15)
					)
					(justify left bottom)
					(hide yes)
				)
			)
			(property "Description" "Fiducial mask"
				(at 9.22 -13.03 0)
				(effects
					(font
						(size 1.27 1.27)
					)
					(justify left bottom)
					(hide yes)
				)
			)
			(property "Author" "Antmicro"
				(at 8.89 -7.62 0)
				(effects
					(font
						(size 1.27 1.27)
						(thickness 0.15)
					)
					(justify left bottom)
					(hide yes)
				)
			)
			(property "License" "Apache-2.0"
				(at 8.89 -10.16 0)
				(effects
					(font
						(size 1.27 1.27)
						(thickness 0.15)
					)
					(justify left bottom)
					(hide yes)
				)
			)
			(symbol "Fiducial_1mm_Mask2mm_1_1"
				(circle
					(center 0 0)
					(radius 2.2361)
					(stroke
						(width 0.254)
						(type default)
					)
					(fill
						(type background)
					)
				)
			)
		)
	(symbol "antmicroFixedInductors:L_1u_1.8A_0603"
			(pin_numbers
				(hide yes)
			)
			(pin_names
				(hide yes)
			)
			(exclude_from_sim no)
			(in_bom yes)
			(on_board yes)
			(property "Reference" "L"
				(at 13.97 0 0)
				(effects
					(font
						(size 1.27 1.27)
						(thickness 0.15)
					)
					(justify left bottom)
				)
			)
			(property "Value" "L_1u_1.8A_0603"
				(at 13.97 -2.54 0)
				(effects
					(font
						(size 1.27 1.27)
						(thickness 0.15)
					)
					(justify left bottom)
					(hide yes)
				)
			)
			(property "Footprint" "antmicro-footprints:L_0603_1608Metric"
				(at 13.97 -7.62 0)
				(effects
					(font
						(size 1.27 1.27)
						(thickness 0.15)
					)
					(justify left bottom)
					(hide yes)
				)
			)
			(property "Datasheet" "https://search.murata.co.jp/Ceramy/image/img/P02/JETE243A-0041.pdf"
				(at 13.97 -10.16 0)
				(effects
					(font
						(size 1.27 1.27)
						(thickness 0.15)
					)
					(justify left bottom)
					(hide yes)
				)
			)
			(property "Description" "Power Inductor (SMT), 1 µH, 1.8 A, Shielded, 1.9 A, DFE Series, 0603 [1608 Metric]"
				(at 13.97 -30.48 0)
				(effects
					(font
						(size 1.27 1.27)
					)
					(justify left bottom)
					(hide yes)
				)
			)
			(property "Val" "1u/1.8A"
				(at 13.97 -5.08 0)
				(effects
					(font
						(size 1.27 1.27)
						(thickness 0.15)
					)
					(justify left bottom)
				)
			)
			(property "Manufacturer" "Murata"
				(at 13.97 -12.7 0)
				(effects
					(font
						(size 1.27 1.27)
						(thickness 0.15)
					)
					(justify left bottom)
					(hide yes)
				)
			)
			(property "MPN" "DFE18SBN1R0ME0L"
				(at 13.97 -15.24 0)
				(effects
					(font
						(size 1.27 1.27)
						(thickness 0.15)
					)
					(justify left bottom)
					(hide yes)
				)
			)
			(property "ISat" "1.9A"
				(at 13.97 -17.78 0)
				(effects
					(font
						(size 1.27 1.27)
					)
					(justify left bottom)
					(hide yes)
				)
			)
			(property "IMax" "1.8A"
				(at 13.97 -20.32 0)
				(effects
					(font
						(size 1.27 1.27)
						(thickness 0.15)
					)
					(justify left bottom)
					(hide yes)
				)
			)
			(property "Size" "1.6x0.8"
				(at 13.97 -22.86 0)
				(effects
					(font
						(size 1.27 1.27)
						(thickness 0.15)
					)
					(justify left bottom)
					(hide yes)
				)
			)
			(property "Author" "Antmicro"
				(at 13.97 -25.4 0)
				(effects
					(font
						(size 1.27 1.27)
						(thickness 0.15)
					)
					(justify left bottom)
					(hide yes)
				)
			)
			(property "License" "Apache-2.0"
				(at 13.97 -27.94 0)
				(effects
					(font
						(size 1.27 1.27)
						(thickness 0.15)
					)
					(justify left bottom)
					(hide yes)
				)
			)
			(property "ki_keywords" "INDUCTOR, PASSIVE"
				(at 0 0 0)
				(effects
					(font
						(size 1.27 1.27)
					)
					(hide yes)
				)
			)
			(symbol "L_1u_1.8A_0603_0_1"
				(arc
					(start 0.508 0)
					(mid 1.016 0.5058)
					(end 1.524 0)
					(stroke
						(width 0)
						(type default)
					)
					(fill
						(type none)
					)
				)
				(arc
					(start 1.524 0)
					(mid 2.032 0.5058)
					(end 2.54 0)
					(stroke
						(width 0)
						(type default)
					)
					(fill
						(type none)
					)
				)
				(arc
					(start 2.54 0)
					(mid 3.048 0.5058)
					(end 3.556 0)
					(stroke
						(width 0)
						(type default)
					)
					(fill
						(type none)
					)
				)
				(arc
					(start 3.556 0)
					(mid 4.064 0.5058)
					(end 4.572 0)
					(stroke
						(width 0)
						(type default)
					)
					(fill
						(type none)
					)
				)
			)
			(symbol "L_1u_1.8A_0603_1_1"
				(pin passive line
					(at 0 0 0)
					(length 0.508)
					(name "~"
						(effects
							(font
								(size 1.27 1.27)
							)
						)
					)
					(number "1"
						(effects
							(font
								(size 1.27 1.27)
							)
						)
					)
				)
				(pin passive line
					(at 5.08 0 180)
					(length 0.508)
					(name "~"
						(effects
							(font
								(size 1.27 1.27)
							)
						)
					)
					(number "2"
						(effects
							(font
								(size 1.27 1.27)
							)
						)
					)
				)
			)
		)
	(symbol "antmicroFixedInductors:L_1u_10A_Bourns-SRP4021HMT"
			(pin_numbers
				(hide yes)
			)
			(pin_names
				(hide yes)
			)
			(exclude_from_sim no)
			(in_bom yes)
			(on_board yes)
			(property "Reference" "L"
				(at 15.24 -5.08 0)
				(effects
					(font
						(size 1.27 1.27)
						(thickness 0.15)
					)
					(justify left bottom)
				)
			)
			(property "Value" "L_1u_10A_Bourns-SRP4021HMT"
				(at 15.24 -10.16 0)
				(effects
					(font
						(size 1.27 1.27)
						(thickness 0.15)
					)
					(justify left bottom)
					(hide yes)
				)
			)
			(property "Footprint" "antmicro-footprints:L_Bourns-SRP4021HMT"
				(at 15.24 -12.7 0)
				(effects
					(font
						(size 1.27 1.27)
						(thickness 0.15)
					)
					(justify left bottom)
					(hide yes)
				)
			)
			(property "Datasheet" "https://www.mouser.com/datasheet/2/54/Bourns_04_01_2025_SRP4021HMT_Datasheet-3580094.pdf"
				(at 15.24 -15.24 0)
				(effects
					(font
						(size 1.27 1.27)
						(thickness 0.15)
					)
					(justify left bottom)
					(hide yes)
				)
			)
			(property "Description" "Power Inductors - SMD Ind,4.1x4.2x1.9mm,1uH+/-20%,10A, Shielded"
				(at 15.24 -38.1 0)
				(effects
					(font
						(size 1.27 1.27)
						(thickness 0.15)
					)
					(justify left bottom)
					(hide yes)
				)
			)
			(property "Val" "1u/10A"
				(at 15.24 -7.62 0)
				(effects
					(font
						(size 1.27 1.27)
						(thickness 0.15)
					)
					(justify left bottom)
				)
			)
			(property "Manufacturer" "Bourns"
				(at 15.24 -20.32 0)
				(effects
					(font
						(size 1.27 1.27)
						(thickness 0.15)
					)
					(justify left bottom)
					(hide yes)
				)
			)
			(property "MPN" "SRP4021HMT-1R0M"
				(at 15.24 -22.86 0)
				(effects
					(font
						(size 1.27 1.27)
						(thickness 0.15)
					)
					(justify left bottom)
					(hide yes)
				)
			)
			(property "ISat" ""
				(at 13.97 -16.51 0)
				(effects
					(font
						(size 1.27 1.27)
					)
					(justify left)
					(hide yes)
				)
			)
			(property "Isat" "8A"
				(at 15.24 -25.4 0)
				(effects
					(font
						(size 1.27 1.27)
						(thickness 0.15)
					)
					(justify left bottom)
					(hide yes)
				)
			)
			(property "IMax" ""
				(at 13.97 -20.32 0)
				(effects
					(font
						(size 1.27 1.27)
						(thickness 0.15)
					)
					(justify left bottom)
					(hide yes)
				)
			)
			(property "Imax" "10A"
				(at 15.24 -27.94 0)
				(effects
					(font
						(size 1.27 1.27)
						(thickness 0.15)
					)
					(justify left bottom)
					(hide yes)
				)
			)
			(property "Size" "4.2x4.1"
				(at 15.24 -30.48 0)
				(effects
					(font
						(size 1.27 1.27)
						(thickness 0.15)
					)
					(justify left bottom)
					(hide yes)
				)
			)
			(property "Author" "Antmicro"
				(at 15.24 -33.02 0)
				(effects
					(font
						(size 1.27 1.27)
						(thickness 0.15)
					)
					(justify left bottom)
					(hide yes)
				)
			)
			(property "License" "Apache-2.0"
				(at 15.24 -35.56 0)
				(effects
					(font
						(size 1.27 1.27)
						(thickness 0.15)
					)
					(justify left bottom)
					(hide yes)
				)
			)
			(property "ki_keywords" "SMT, INDUCTOR, PASSIVE"
				(at 0 0 0)
				(effects
					(font
						(size 1.27 1.27)
					)
					(hide yes)
				)
			)
			(symbol "L_1u_10A_Bourns-SRP4021HMT_0_1"
				(arc
					(start 0.508 0)
					(mid 1.016 0.5058)
					(end 1.524 0)
					(stroke
						(width 0)
						(type default)
					)
					(fill
						(type none)
					)
				)
				(arc
					(start 1.524 0)
					(mid 2.032 0.5058)
					(end 2.54 0)
					(stroke
						(width 0)
						(type default)
					)
					(fill
						(type none)
					)
				)
				(arc
					(start 2.54 0)
					(mid 3.048 0.5058)
					(end 3.556 0)
					(stroke
						(width 0)
						(type default)
					)
					(fill
						(type none)
					)
				)
				(arc
					(start 3.556 0)
					(mid 4.064 0.5058)
					(end 4.572 0)
					(stroke
						(width 0)
						(type default)
					)
					(fill
						(type none)
					)
				)
			)
			(symbol "L_1u_10A_Bourns-SRP4021HMT_1_1"
				(pin passive line
					(at 0 0 0)
					(length 0.508)
					(name "~"
						(effects
							(font
								(size 1.27 1.27)
							)
						)
					)
					(number "1"
						(effects
							(font
								(size 1.27 1.27)
							)
						)
					)
				)
				(pin passive line
					(at 5.08 0 180)
					(length 0.508)
					(name "~"
						(effects
							(font
								(size 1.27 1.27)
							)
						)
					)
					(number "2"
						(effects
							(font
								(size 1.27 1.27)
							)
						)
					)
				)
			)
		)
	(symbol "antmicroFixedInductors:L_2n4_0.85A_0402"
			(pin_numbers
				(hide yes)
			)
			(pin_names
				(hide yes)
			)
			(exclude_from_sim no)
			(in_bom yes)
			(on_board yes)
			(property "Reference" "L"
				(at 13.97 0 0)
				(effects
					(font
						(size 1.27 1.27)
						(thickness 0.15)
					)
					(justify left bottom)
				)
			)
			(property "Value" "L_2n4_0.85A_0402"
				(at 13.97 -2.54 0)
				(effects
					(font
						(size 1.27 1.27)
						(thickness 0.15)
					)
					(justify left bottom)
					(hide yes)
				)
			)
			(property "Footprint" "antmicro-footprints:L_0402_1005Metric"
				(at 13.97 -7.62 0)
				(effects
					(font
						(size 1.27 1.27)
						(thickness 0.15)
					)
					(justify left bottom)
					(hide yes)
				)
			)
			(property "Datasheet" "https://www.murata.com/products/productdetail?partno=LQW15AN2N4B00%23"
				(at 13.97 -10.16 0)
				(effects
					(font
						(size 1.27 1.27)
						(thickness 0.15)
					)
					(justify left bottom)
					(hide yes)
				)
			)
			(property "Description" "Wirewound Inductor, 2.4 nH, 0.05 ohm, 15 GHz, 850 mA, 0402 [1005 Metric], LQW15AN"
				(at 13.97 -30.48 0)
				(effects
					(font
						(size 1.27 1.27)
					)
					(justify left bottom)
					(hide yes)
				)
			)
			(property "Val" "2n4/0.85A"
				(at 13.97 -5.08 0)
				(effects
					(font
						(size 1.27 1.27)
						(thickness 0.15)
					)
					(justify left bottom)
				)
			)
			(property "Manufacturer" "Murata"
				(at 13.97 -12.7 0)
				(effects
					(font
						(size 1.27 1.27)
						(thickness 0.15)
					)
					(justify left bottom)
					(hide yes)
				)
			)
			(property "MPN" "LQW15AN2N4B00D"
				(at 13.97 -15.24 0)
				(effects
					(font
						(size 1.27 1.27)
						(thickness 0.15)
					)
					(justify left bottom)
					(hide yes)
				)
			)
			(property "ISat" "0.85 A"
				(at 13.97 -16.51 0)
				(effects
					(font
						(size 1.27 1.27)
					)
					(justify left)
					(hide yes)
				)
			)
			(property "IMax" "0.85 A"
				(at 13.97 -20.32 0)
				(effects
					(font
						(size 1.27 1.27)
						(thickness 0.15)
					)
					(justify left bottom)
					(hide yes)
				)
			)
			(property "Size" "1.0x0.5"
				(at 13.97 -22.86 0)
				(effects
					(font
						(size 1.27 1.27)
						(thickness 0.15)
					)
					(justify left bottom)
					(hide yes)
				)
			)
			(property "Author" "Antmicro"
				(at 13.97 -25.4 0)
				(effects
					(font
						(size 1.27 1.27)
						(thickness 0.15)
					)
					(justify left bottom)
					(hide yes)
				)
			)
			(property "License" "Apache-2.0"
				(at 13.97 -27.94 0)
				(effects
					(font
						(size 1.27 1.27)
						(thickness 0.15)
					)
					(justify left bottom)
					(hide yes)
				)
			)
			(property "ki_keywords" "INDUCTOR, PASSIVE"
				(at 0 0 0)
				(effects
					(font
						(size 1.27 1.27)
					)
					(hide yes)
				)
			)
			(symbol "L_2n4_0.85A_0402_0_1"
				(arc
					(start 0.508 0)
					(mid 1.016 0.5058)
					(end 1.524 0)
					(stroke
						(width 0)
						(type default)
					)
					(fill
						(type none)
					)
				)
				(arc
					(start 1.524 0)
					(mid 2.032 0.5058)
					(end 2.54 0)
					(stroke
						(width 0)
						(type default)
					)
					(fill
						(type none)
					)
				)
				(arc
					(start 2.54 0)
					(mid 3.048 0.5058)
					(end 3.556 0)
					(stroke
						(width 0)
						(type default)
					)
					(fill
						(type none)
					)
				)
				(arc
					(start 3.556 0)
					(mid 4.064 0.5058)
					(end 4.572 0)
					(stroke
						(width 0)
						(type default)
					)
					(fill
						(type none)
					)
				)
			)
			(symbol "L_2n4_0.85A_0402_1_1"
				(pin passive line
					(at 0 0 0)
					(length 0.508)
					(name "~"
						(effects
							(font
								(size 1.27 1.27)
							)
						)
					)
					(number "1"
						(effects
							(font
								(size 1.27 1.27)
							)
						)
					)
				)
				(pin passive line
					(at 5.08 0 180)
					(length 0.508)
					(name "~"
						(effects
							(font
								(size 1.27 1.27)
							)
						)
					)
					(number "2"
						(effects
							(font
								(size 1.27 1.27)
							)
						)
					)
				)
			)
		)
	(symbol "antmicroFixedInductors:L_2u2_5.8A_WE-PMFI-35329222"
			(pin_numbers
				(hide yes)
			)
			(pin_names
				(hide yes)
			)
			(exclude_from_sim no)
			(in_bom yes)
			(on_board yes)
			(property "Reference" "L"
				(at 13.97 0 0)
				(effects
					(font
						(size 1.27 1.27)
						(thickness 0.15)
					)
					(justify left bottom)
				)
			)
			(property "Value" "L_2u2_5.8A_WE-PMFI-35329222"
				(at 13.97 -2.54 0)
				(effects
					(font
						(size 1.27 1.27)
						(thickness 0.15)
					)
					(justify left bottom)
					(hide yes)
				)
			)
			(property "Footprint" "antmicro-footprints:L_WE-PMFI-353220"
				(at 13.97 -7.62 0)
				(effects
					(font
						(size 1.27 1.27)
						(thickness 0.15)
					)
					(justify left bottom)
					(hide yes)
				)
			)
			(property "Datasheet" "https://www.we-online.com/components/products/datasheet/74479335329222.pdf"
				(at 13.97 -10.16 0)
				(effects
					(font
						(size 1.27 1.27)
						(thickness 0.15)
					)
					(justify left bottom)
					(hide yes)
				)
			)
			(property "Description" "Power Inductors - SMD WE-PMFI 2.2 uH 5.8 A 40 mOhms AEC-Q200"
				(at 13.97 -30.48 0)
				(effects
					(font
						(size 1.27 1.27)
					)
					(justify left bottom)
					(hide yes)
				)
			)
			(property "Val" "2u2/5.8A"
				(at 13.97 -5.08 0)
				(effects
					(font
						(size 1.27 1.27)
						(thickness 0.15)
					)
					(justify left bottom)
				)
			)
			(property "Manufacturer" "Würth Elektronik"
				(at 13.97 -12.7 0)
				(effects
					(font
						(size 1.27 1.27)
						(thickness 0.15)
					)
					(justify left bottom)
					(hide yes)
				)
			)
			(property "MPN" "74479335329222"
				(at 13.97 -15.24 0)
				(effects
					(font
						(size 1.27 1.27)
						(thickness 0.15)
					)
					(justify left bottom)
					(hide yes)
				)
			)
			(property "ISat" "7.8A"
				(at 13.97 -17.78 0)
				(effects
					(font
						(size 1.27 1.27)
					)
					(justify left bottom)
					(hide yes)
				)
			)
			(property "IMax" "5.8A"
				(at 13.97 -20.32 0)
				(effects
					(font
						(size 1.27 1.27)
						(thickness 0.15)
					)
					(justify left bottom)
					(hide yes)
				)
			)
			(property "Size" "3.5x3.2x2.0"
				(at 13.97 -22.86 0)
				(effects
					(font
						(size 1.27 1.27)
						(thickness 0.15)
					)
					(justify left bottom)
					(hide yes)
				)
			)
			(property "Author" "Antmicro"
				(at 13.97 -25.4 0)
				(effects
					(font
						(size 1.27 1.27)
						(thickness 0.15)
					)
					(justify left bottom)
					(hide yes)
				)
			)
			(property "License" "Apache-2.0"
				(at 13.97 -27.94 0)
				(effects
					(font
						(size 1.27 1.27)
						(thickness 0.15)
					)
					(justify left bottom)
					(hide yes)
				)
			)
			(property "ki_keywords" "SMT, INDUCTOR, PASSIVE"
				(at 0 0 0)
				(effects
					(font
						(size 1.27 1.27)
					)
					(hide yes)
				)
			)
			(symbol "L_2u2_5.8A_WE-PMFI-35329222_0_1"
				(arc
					(start 0.508 0)
					(mid 1.016 0.5058)
					(end 1.524 0)
					(stroke
						(width 0)
						(type default)
					)
					(fill
						(type none)
					)
				)
				(arc
					(start 1.524 0)
					(mid 2.032 0.5058)
					(end 2.54 0)
					(stroke
						(width 0)
						(type default)
					)
					(fill
						(type none)
					)
				)
				(arc
					(start 2.54 0)
					(mid 3.048 0.5058)
					(end 3.556 0)
					(stroke
						(width 0)
						(type default)
					)
					(fill
						(type none)
					)
				)
				(arc
					(start 3.556 0)
					(mid 4.064 0.5058)
					(end 4.572 0)
					(stroke
						(width 0)
						(type default)
					)
					(fill
						(type none)
					)
				)
			)
			(symbol "L_2u2_5.8A_WE-PMFI-35329222_1_1"
				(pin passive line
					(at 0 0 0)
					(length 0.508)
					(name "~"
						(effects
							(font
								(size 1.27 1.27)
							)
						)
					)
					(number "1"
						(effects
							(font
								(size 1.27 1.27)
							)
						)
					)
				)
				(pin passive line
					(at 5.08 0 180)
					(length 0.508)
					(name "~"
						(effects
							(font
								(size 1.27 1.27)
							)
						)
					)
					(number "2"
						(effects
							(font
								(size 1.27 1.27)
							)
						)
					)
				)
			)
		)
	(symbol "antmicroFixedInductors:L_2u2_9.7A_Coilcraft-XAL5030"
			(pin_numbers
				(hide yes)
			)
			(pin_names
				(hide yes)
			)
			(exclude_from_sim no)
			(in_bom yes)
			(on_board yes)
			(property "Reference" "L"
				(at 13.97 0 0)
				(effects
					(font
						(size 1.27 1.27)
						(thickness 0.15)
					)
					(justify left bottom)
				)
			)
			(property "Value" "L_2u2_9.7A_Coilcraft-XAL5030"
				(at 13.97 -2.54 0)
				(effects
					(font
						(size 1.27 1.27)
						(thickness 0.15)
					)
					(justify left bottom)
					(hide yes)
				)
			)
			(property "Footprint" "antmicro-footprints:L_Coilcraft-XAL5030"
				(at 13.97 -7.62 0)
				(effects
					(font
						(size 1.27 1.27)
						(thickness 0.15)
					)
					(justify left bottom)
					(hide yes)
				)
			)
			(property "Datasheet" "https://www.coilcraft.com/getmedia/49bc46c8-4b2c-45b9-9b6c-2eaa235ea698/xal50xx.pdf"
				(at 13.97 -10.16 0)
				(effects
					(font
						(size 1.27 1.27)
						(thickness 0.15)
					)
					(justify left bottom)
					(hide yes)
				)
			)
			(property "Description" "Power Inductor (SMT), 2.2 µH, 9.7 A, Shielded, 9.2 A, XAL5030"
				(at 13.97 -30.48 0)
				(effects
					(font
						(size 1.27 1.27)
					)
					(justify left bottom)
					(hide yes)
				)
			)
			(property "Val" "2u2/9.7A"
				(at 13.97 -5.08 0)
				(effects
					(font
						(size 1.27 1.27)
						(thickness 0.15)
					)
					(justify left bottom)
				)
			)
			(property "Manufacturer" "Coilcraft"
				(at 13.97 -12.7 0)
				(effects
					(font
						(size 1.27 1.27)
						(thickness 0.15)
					)
					(justify left bottom)
					(hide yes)
				)
			)
			(property "MPN" "XAL5030-222MEC"
				(at 13.97 -15.24 0)
				(effects
					(font
						(size 1.27 1.27)
						(thickness 0.15)
					)
					(justify left bottom)
					(hide yes)
				)
			)
			(property "ISat" "9.2 A"
				(at 13.97 -16.51 0)
				(effects
					(font
						(size 1.27 1.27)
					)
					(justify left)
					(hide yes)
				)
			)
			(property "IMax" "9.7 A"
				(at 13.97 -20.32 0)
				(effects
					(font
						(size 1.27 1.27)
						(thickness 0.15)
					)
					(justify left bottom)
					(hide yes)
				)
			)
			(property "Size" "5.28x5.48"
				(at 13.97 -22.86 0)
				(effects
					(font
						(size 1.27 1.27)
						(thickness 0.15)
					)
					(justify left bottom)
					(hide yes)
				)
			)
			(property "Author" "Antmicro"
				(at 13.97 -25.4 0)
				(effects
					(font
						(size 1.27 1.27)
						(thickness 0.15)
					)
					(justify left bottom)
					(hide yes)
				)
			)
			(property "License" "Apache-2.0"
				(at 13.97 -27.94 0)
				(effects
					(font
						(size 1.27 1.27)
						(thickness 0.15)
					)
					(justify left bottom)
					(hide yes)
				)
			)
			(property "ki_keywords" "SMT, INDUCTOR, PASSIVE"
				(at 0 0 0)
				(effects
					(font
						(size 1.27 1.27)
					)
					(hide yes)
				)
			)
			(symbol "L_2u2_9.7A_Coilcraft-XAL5030_0_1"
				(arc
					(start 0.508 0)
					(mid 1.016 0.5058)
					(end 1.524 0)
					(stroke
						(width 0)
						(type default)
					)
					(fill
						(type none)
					)
				)
				(arc
					(start 1.524 0)
					(mid 2.032 0.5058)
					(end 2.54 0)
					(stroke
						(width 0)
						(type default)
					)
					(fill
						(type none)
					)
				)
				(arc
					(start 2.54 0)
					(mid 3.048 0.5058)
					(end 3.556 0)
					(stroke
						(width 0)
						(type default)
					)
					(fill
						(type none)
					)
				)
				(arc
					(start 3.556 0)
					(mid 4.064 0.5058)
					(end 4.572 0)
					(stroke
						(width 0)
						(type default)
					)
					(fill
						(type none)
					)
				)
			)
			(symbol "L_2u2_9.7A_Coilcraft-XAL5030_1_1"
				(pin passive line
					(at 0 0 0)
					(length 0.508)
					(name "~"
						(effects
							(font
								(size 1.27 1.27)
							)
						)
					)
					(number "1"
						(effects
							(font
								(size 1.27 1.27)
							)
						)
					)
				)
				(pin passive line
					(at 5.08 0 180)
					(length 0.508)
					(name "~"
						(effects
							(font
								(size 1.27 1.27)
							)
						)
					)
					(number "2"
						(effects
							(font
								(size 1.27 1.27)
							)
						)
					)
				)
			)
		)
	(symbol "antmicroFixedInductors:L_3u3_6A_Bourns-SRP7028A"
			(pin_numbers
				(hide yes)
			)
			(pin_names
				(hide yes)
			)
			(exclude_from_sim no)
			(in_bom yes)
			(on_board yes)
			(property "Reference" "L"
				(at 13.97 0 0)
				(effects
					(font
						(size 1.27 1.27)
						(thickness 0.15)
					)
					(justify left bottom)
				)
			)
			(property "Value" "L_3u3_6A_Bourns-SRP7028A"
				(at 13.97 -5.08 0)
				(effects
					(font
						(size 1.27 1.27)
						(thickness 0.15)
					)
					(justify left bottom)
					(hide yes)
				)
			)
			(property "Footprint" "antmicro-footprints:L_Bourns-SRP7028A"
				(at 13.97 -7.62 0)
				(effects
					(font
						(size 1.27 1.27)
						(thickness 0.15)
					)
					(justify left bottom)
					(hide yes)
				)
			)
			(property "Datasheet" "https://www.bourns.com/docs/Product-Datasheets/SRP7028A.pdf"
				(at 13.97 -10.16 0)
				(effects
					(font
						(size 1.27 1.27)
						(thickness 0.15)
					)
					(justify left bottom)
					(hide yes)
				)
			)
			(property "Description" "Power Inductor (SMD), 3.3 µH, 6 A, 28 mOhm, Shielded, 12 A, SRP7028A Series"
				(at 13.97 -30.48 0)
				(effects
					(font
						(size 1.27 1.27)
					)
					(justify left bottom)
					(hide yes)
				)
			)
			(property "Val" "3u3/6A"
				(at 13.97 -2.54 0)
				(effects
					(font
						(size 1.27 1.27)
						(thickness 0.15)
					)
					(justify left bottom)
				)
			)
			(property "Manufacturer" "Bourns"
				(at 13.97 -12.7 0)
				(effects
					(font
						(size 1.27 1.27)
						(thickness 0.15)
					)
					(justify left bottom)
					(hide yes)
				)
			)
			(property "MPN" "SRP7028A-3R3M"
				(at 13.97 -15.24 0)
				(effects
					(font
						(size 1.27 1.27)
						(thickness 0.15)
					)
					(justify left bottom)
					(hide yes)
				)
			)
			(property "ISat" "12 A"
				(at 13.97 -16.51 0)
				(effects
					(font
						(size 1.27 1.27)
					)
					(justify left)
					(hide yes)
				)
			)
			(property "IMax" "6 A"
				(at 13.97 -20.32 0)
				(effects
					(font
						(size 1.27 1.27)
						(thickness 0.15)
					)
					(justify left bottom)
					(hide yes)
				)
			)
			(property "Size" "7.3x6.6x2.8"
				(at 13.97 -22.86 0)
				(effects
					(font
						(size 1.27 1.27)
						(thickness 0.15)
					)
					(justify left bottom)
					(hide yes)
				)
			)
			(property "Author" "Antmicro"
				(at 13.97 -25.4 0)
				(effects
					(font
						(size 1.27 1.27)
						(thickness 0.15)
					)
					(justify left bottom)
					(hide yes)
				)
			)
			(property "License" "Apache-2.0"
				(at 13.97 -27.94 0)
				(effects
					(font
						(size 1.27 1.27)
						(thickness 0.15)
					)
					(justify left bottom)
					(hide yes)
				)
			)
			(property "ki_keywords" "SMT, INDUCTOR, PASSIVE"
				(at 0 0 0)
				(effects
					(font
						(size 1.27 1.27)
					)
					(hide yes)
				)
			)
			(symbol "L_3u3_6A_Bourns-SRP7028A_0_1"
				(arc
					(start 0.508 0)
					(mid 1.016 0.5058)
					(end 1.524 0)
					(stroke
						(width 0)
						(type default)
					)
					(fill
						(type none)
					)
				)
				(arc
					(start 1.524 0)
					(mid 2.032 0.5058)
					(end 2.54 0)
					(stroke
						(width 0)
						(type default)
					)
					(fill
						(type none)
					)
				)
				(arc
					(start 2.54 0)
					(mid 3.048 0.5058)
					(end 3.556 0)
					(stroke
						(width 0)
						(type default)
					)
					(fill
						(type none)
					)
				)
				(arc
					(start 3.556 0)
					(mid 4.064 0.5058)
					(end 4.572 0)
					(stroke
						(width 0)
						(type default)
					)
					(fill
						(type none)
					)
				)
			)
			(symbol "L_3u3_6A_Bourns-SRP7028A_1_1"
				(pin passive line
					(at 0 0 0)
					(length 0.508)
					(name "~"
						(effects
							(font
								(size 1.27 1.27)
							)
						)
					)
					(number "1"
						(effects
							(font
								(size 1.27 1.27)
							)
						)
					)
				)
				(pin passive line
					(at 5.08 0 180)
					(length 0.508)
					(name "~"
						(effects
							(font
								(size 1.27 1.27)
							)
						)
					)
					(number "2"
						(effects
							(font
								(size 1.27 1.27)
							)
						)
					)
				)
			)
		)
	(symbol "antmicroFixedInductors:L_4u7_1.55A_Bourns-SRP2512A"
			(pin_numbers
				(hide yes)
			)
			(pin_names
				(hide yes)
			)
			(exclude_from_sim no)
			(in_bom yes)
			(on_board yes)
			(property "Reference" "L"
				(at 15.24 0 0)
				(effects
					(font
						(size 1.27 1.27)
						(thickness 0.15)
					)
					(justify left bottom)
				)
			)
			(property "Value" "L_4u7_1.55A_Bourns-SRP2512A"
				(at 15.24 -5.08 0)
				(effects
					(font
						(size 1.27 1.27)
						(thickness 0.15)
					)
					(justify left bottom)
					(hide yes)
				)
			)
			(property "Footprint" "antmicro-footprints:L_Bourns-SRP2512A"
				(at 15.24 -7.62 0)
				(effects
					(font
						(size 1.27 1.27)
						(thickness 0.15)
					)
					(justify left bottom)
					(hide yes)
				)
			)
			(property "Datasheet" "https://www.bourns.com/docs/Product-Datasheets/srp2512a.pdf"
				(at 15.24 -10.16 0)
				(effects
					(font
						(size 1.27 1.27)
						(thickness 0.15)
					)
					(justify left bottom)
					(hide yes)
				)
			)
			(property "Description" "4.7 µH Shielded Drum Core, Wirewound Inductor 1.55 A 235mOhm Max 1008 (2520 Metric)"
				(at 15.24 -30.48 0)
				(effects
					(font
						(size 1.27 1.27)
					)
					(justify left bottom)
					(hide yes)
				)
			)
			(property "Val" "4u7/1.55A"
				(at 15.24 -2.54 0)
				(effects
					(font
						(size 1.27 1.27)
						(thickness 0.15)
					)
					(justify left bottom)
				)
			)
			(property "Manufacturer" "Bourns"
				(at 15.24 -12.7 0)
				(effects
					(font
						(size 1.27 1.27)
						(thickness 0.15)
					)
					(justify left bottom)
					(hide yes)
				)
			)
			(property "MPN" "SRP2512A-4R7M"
				(at 15.24 -15.24 0)
				(effects
					(font
						(size 1.27 1.27)
						(thickness 0.15)
					)
					(justify left bottom)
					(hide yes)
				)
			)
			(property "ISat" "1.9 A"
				(at 15.24 -17.78 0)
				(effects
					(font
						(size 1.27 1.27)
					)
					(justify left bottom)
					(hide yes)
				)
			)
			(property "IMax" "1.55 A"
				(at 15.24 -20.32 0)
				(effects
					(font
						(size 1.27 1.27)
					)
					(justify left bottom)
					(hide yes)
				)
			)
			(property "Size" "2.5x2.0"
				(at 15.24 -22.86 0)
				(effects
					(font
						(size 1.27 1.27)
					)
					(justify left bottom)
					(hide yes)
				)
			)
			(property "Author" "Antmicro"
				(at 15.24 -25.4 0)
				(effects
					(font
						(size 1.27 1.27)
						(thickness 0.15)
					)
					(justify left bottom)
					(hide yes)
				)
			)
			(property "License" "Apache-2.0"
				(at 15.24 -27.94 0)
				(effects
					(font
						(size 1.27 1.27)
						(thickness 0.15)
					)
					(justify left bottom)
					(hide yes)
				)
			)
			(property "ki_keywords" "INDUCTOR, PASSIVE"
				(at 0 0 0)
				(effects
					(font
						(size 1.27 1.27)
					)
					(hide yes)
				)
			)
			(symbol "L_4u7_1.55A_Bourns-SRP2512A_0_1"
				(arc
					(start 0.508 0)
					(mid 1.016 0.5058)
					(end 1.524 0)
					(stroke
						(width 0)
						(type default)
					)
					(fill
						(type none)
					)
				)
				(arc
					(start 1.524 0)
					(mid 2.032 0.5058)
					(end 2.54 0)
					(stroke
						(width 0)
						(type default)
					)
					(fill
						(type none)
					)
				)
				(arc
					(start 2.54 0)
					(mid 3.048 0.5058)
					(end 3.556 0)
					(stroke
						(width 0)
						(type default)
					)
					(fill
						(type none)
					)
				)
				(arc
					(start 3.556 0)
					(mid 4.064 0.5058)
					(end 4.572 0)
					(stroke
						(width 0)
						(type default)
					)
					(fill
						(type none)
					)
				)
			)
			(symbol "L_4u7_1.55A_Bourns-SRP2512A_1_1"
				(pin passive line
					(at 0 0 0)
					(length 0.508)
					(name "~"
						(effects
							(font
								(size 1.27 1.27)
							)
						)
					)
					(number "1"
						(effects
							(font
								(size 1.27 1.27)
							)
						)
					)
				)
				(pin passive line
					(at 5.08 0 180)
					(length 0.508)
					(name "~"
						(effects
							(font
								(size 1.27 1.27)
							)
						)
					)
					(number "2"
						(effects
							(font
								(size 1.27 1.27)
							)
						)
					)
				)
			)
		)
	(symbol "antmicroFixedInductors:L_680n_7.6A_IHLP1616BZ"
			(pin_numbers
				(hide yes)
			)
			(pin_names
				(hide yes)
			)
			(exclude_from_sim no)
			(in_bom yes)
			(on_board yes)
			(property "Reference" "L"
				(at 13.97 0 0)
				(effects
					(font
						(size 1.27 1.27)
						(thickness 0.15)
					)
					(justify left bottom)
				)
			)
			(property "Value" "L_680n_7.6A_IHLP1616BZ"
				(at 13.97 -2.54 0)
				(effects
					(font
						(size 1.27 1.27)
						(thickness 0.15)
					)
					(justify left bottom)
					(hide yes)
				)
			)
			(property "Footprint" "antmicro-footprints:L_Vishay-IHLP1616BZ"
				(at 13.97 -7.62 0)
				(effects
					(font
						(size 1.27 1.27)
						(thickness 0.15)
					)
					(justify left bottom)
					(hide yes)
				)
			)
			(property "Datasheet" "https://www.mouser.com/datasheet/2/427/ihlp1616bz5a-1763007.pdf"
				(at 13.97 -10.16 0)
				(effects
					(font
						(size 1.27 1.27)
						(thickness 0.15)
					)
					(justify left bottom)
					(hide yes)
				)
			)
			(property "Description" "Power Inductor (SMT), 680 nH, 7.6 A, Shielded, 6.8 A, IHLP-1616BZ-5A"
				(at 13.97 -30.48 0)
				(effects
					(font
						(size 1.27 1.27)
					)
					(justify left bottom)
					(hide yes)
				)
			)
			(property "Val" "680n/7.6A"
				(at 13.97 -5.08 0)
				(effects
					(font
						(size 1.27 1.27)
						(thickness 0.15)
					)
					(justify left bottom)
				)
			)
			(property "Manufacturer" "Vishay"
				(at 13.97 -12.7 0)
				(effects
					(font
						(size 1.27 1.27)
						(thickness 0.15)
					)
					(justify left bottom)
					(hide yes)
				)
			)
			(property "MPN" "IHLP1616BZERR68M5A"
				(at 13.97 -15.24 0)
				(effects
					(font
						(size 1.27 1.27)
						(thickness 0.15)
					)
					(justify left bottom)
					(hide yes)
				)
			)
			(property "ISat" "6.8 A"
				(at 13.97 -16.51 0)
				(effects
					(font
						(size 1.27 1.27)
					)
					(justify left)
					(hide yes)
				)
			)
			(property "IMax" "7.6 A"
				(at 13.97 -20.32 0)
				(effects
					(font
						(size 1.27 1.27)
						(thickness 0.15)
					)
					(justify left bottom)
					(hide yes)
				)
			)
			(property "Size" "4.06x4.06"
				(at 13.97 -22.86 0)
				(effects
					(font
						(size 1.27 1.27)
						(thickness 0.15)
					)
					(justify left bottom)
					(hide yes)
				)
			)
			(property "Author" "Antmicro"
				(at 13.97 -25.4 0)
				(effects
					(font
						(size 1.27 1.27)
						(thickness 0.15)
					)
					(justify left bottom)
					(hide yes)
				)
			)
			(property "License" "Apache-2.0"
				(at 13.97 -27.94 0)
				(effects
					(font
						(size 1.27 1.27)
						(thickness 0.15)
					)
					(justify left bottom)
					(hide yes)
				)
			)
			(property "ki_keywords" "SMT, INDUCTOR, PASSIVE"
				(at 0 0 0)
				(effects
					(font
						(size 1.27 1.27)
					)
					(hide yes)
				)
			)
			(symbol "L_680n_7.6A_IHLP1616BZ_0_1"
				(arc
					(start 0.508 0)
					(mid 1.016 0.5058)
					(end 1.524 0)
					(stroke
						(width 0)
						(type default)
					)
					(fill
						(type none)
					)
				)
				(arc
					(start 1.524 0)
					(mid 2.032 0.5058)
					(end 2.54 0)
					(stroke
						(width 0)
						(type default)
					)
					(fill
						(type none)
					)
				)
				(arc
					(start 2.54 0)
					(mid 3.048 0.5058)
					(end 3.556 0)
					(stroke
						(width 0)
						(type default)
					)
					(fill
						(type none)
					)
				)
				(arc
					(start 3.556 0)
					(mid 4.064 0.5058)
					(end 4.572 0)
					(stroke
						(width 0)
						(type default)
					)
					(fill
						(type none)
					)
				)
			)
			(symbol "L_680n_7.6A_IHLP1616BZ_1_1"
				(pin passive line
					(at 0 0 0)
					(length 0.508)
					(name "~"
						(effects
							(font
								(size 1.27 1.27)
							)
						)
					)
					(number "1"
						(effects
							(font
								(size 1.27 1.27)
							)
						)
					)
				)
				(pin passive line
					(at 5.08 0 180)
					(length 0.508)
					(name "~"
						(effects
							(font
								(size 1.27 1.27)
							)
						)
					)
					(number "2"
						(effects
							(font
								(size 1.27 1.27)
							)
						)
					)
				)
			)
		)
	(symbol "antmicroInterfaceControllers:EZX710AT2_S_LMR5"
			(exclude_from_sim no)
			(in_bom yes)
			(on_board yes)
			(property "Reference" "U"
				(at 76.2 0 0)
				(effects
					(font
						(size 1.27 1.27)
						(thickness 0.15)
					)
					(justify left bottom)
				)
			)
			(property "Value" "EZX710AT2_S_LMR5"
				(at 76.2 -5.08 0)
				(effects
					(font
						(size 1.27 1.27)
						(thickness 0.15)
					)
					(justify left bottom)
					(hide yes)
				)
			)
			(property "Footprint" "antmicro-footprints:FCBGA-503_22x22mm_Layout21x24_P1mm"
				(at 76.2 -7.62 0)
				(effects
					(font
						(size 1.27 1.27)
						(thickness 0.15)
					)
					(justify left bottom)
					(hide yes)
				)
			)
			(property "Datasheet" "https://www.google.com/url?sa=t&source=web&rct=j&opi=89978449&url=https://cdrdv2-public.intel.com/596333/596333_X710-TM4_Datasheet_v_2_4.pdf&ved=2ahUKEwiSuv20_sCOAxXVCRAIHdxGO_UQFnoECBEQAQ&usg=AOvVaw1CjGyrGWE8ZvOdw4VBsY6U"
				(at 76.2 -10.16 0)
				(effects
					(font
						(size 1.27 1.27)
						(thickness 0.15)
					)
					(justify left bottom)
					(hide yes)
				)
			)
			(property "Description" "Ethernet ICs Intel Ethernet Controller 10 Gigabit X7"
				(at 76.2 -22.86 0)
				(effects
					(font
						(size 1.27 1.27)
						(thickness 0.15)
					)
					(justify left bottom)
					(hide yes)
				)
			)
			(property "MPN" "EZX710AT2 S LMR5"
				(at 76.2 -2.54 0)
				(effects
					(font
						(size 1.27 1.27)
						(thickness 0.15)
					)
					(justify left bottom)
				)
			)
			(property "Manufacturer" "Intel"
				(at 76.2 -15.24 0)
				(effects
					(font
						(size 1.27 1.27)
						(thickness 0.15)
					)
					(justify left bottom)
					(hide yes)
				)
			)
			(property "Author" "Antmicro"
				(at 76.2 -17.78 0)
				(effects
					(font
						(size 1.27 1.27)
						(thickness 0.15)
					)
					(justify left bottom)
					(hide yes)
				)
			)
			(property "License" "Apache-2.0"
				(at 76.2 -20.32 0)
				(effects
					(font
						(size 1.27 1.27)
						(thickness 0.15)
					)
					(justify left bottom)
					(hide yes)
				)
			)
			(property "ki_locked" ""
				(at 0 0 0)
				(effects
					(font
						(size 1.27 1.27)
					)
				)
			)
			(property "ki_keywords" "SMT, IC, ETHERNET"
				(at 0 0 0)
				(effects
					(font
						(size 1.27 1.27)
					)
					(hide yes)
				)
			)
			(symbol "EZX710AT2_S_LMR5_1_1"
				(rectangle
					(start 5.08 2.54)
					(end 30.48 -134.62)
					(stroke
						(width 0.254)
						(type default)
					)
					(fill
						(type background)
					)
				)
				(polyline
					(pts
						(xy 16.51 1.27) (xy 16.51 -133.35)
					)
					(stroke
						(width 0.254)
						(type solid)
					)
					(fill
						(type background)
					)
				)
				(polyline
					(pts
						(xy 24.13 1.27) (xy 24.13 -11.43)
					)
					(stroke
						(width 0.254)
						(type solid)
					)
					(fill
						(type background)
					)
				)
				(text "PCIe"
					(at 21.59 -71.12 900)
					(effects
						(font
							(size 2.54 2.54)
							(thickness 0.508)
							(bold yes)
						)
						(justify left bottom)
					)
				)
				(text "JTAG"
					(at 22.86 -7.112 900)
					(effects
						(font
							(size 1.27 1.27)
							(thickness 0.15)
						)
						(justify left bottom)
					)
				)
				(pin input line
					(at 0 0 0)
					(length 5.08)
					(name "~{PE_RST}"
						(effects
							(font
								(size 1.27 1.27)
							)
						)
					)
					(number "R1"
						(effects
							(font
								(size 1.27 1.27)
							)
						)
					)
				)
				(pin open_collector line
					(at 0 -2.54 0)
					(length 5.08)
					(name "~{PE_WAKE}"
						(effects
							(font
								(size 1.27 1.27)
							)
						)
					)
					(number "P2"
						(effects
							(font
								(size 1.27 1.27)
							)
						)
					)
				)
				(pin input line
					(at 0 -7.62 0)
					(length 5.08)
					(name "PE_CLK_P"
						(effects
							(font
								(size 1.27 1.27)
							)
						)
					)
					(number "AA1"
						(effects
							(font
								(size 1.27 1.27)
							)
						)
					)
				)
				(pin input line
					(at 0 -10.16 0)
					(length 5.08)
					(name "PE_CLK_N"
						(effects
							(font
								(size 1.27 1.27)
							)
						)
					)
					(number "AB2"
						(effects
							(font
								(size 1.27 1.27)
							)
						)
					)
				)
				(pin output line
					(at 0 -15.24 0)
					(length 5.08)
					(name "PET_0_P"
						(effects
							(font
								(size 1.27 1.27)
							)
						)
					)
					(number "AD4"
						(effects
							(font
								(size 1.27 1.27)
							)
						)
					)
				)
				(pin output line
					(at 0 -17.78 0)
					(length 5.08)
					(name "PET_0_N"
						(effects
							(font
								(size 1.27 1.27)
							)
						)
					)
					(number "AC5"
						(effects
							(font
								(size 1.27 1.27)
							)
						)
					)
				)
				(pin input line
					(at 0 -22.86 0)
					(length 5.08)
					(name "PER_0_P"
						(effects
							(font
								(size 1.27 1.27)
							)
						)
					)
					(number "AA5"
						(effects
							(font
								(size 1.27 1.27)
							)
						)
					)
				)
				(pin input line
					(at 0 -25.4 0)
					(length 5.08)
					(name "PER_0_N"
						(effects
							(font
								(size 1.27 1.27)
							)
						)
					)
					(number "AA7"
						(effects
							(font
								(size 1.27 1.27)
							)
						)
					)
				)
				(pin output line
					(at 0 -30.48 0)
					(length 5.08)
					(name "PET_1_P"
						(effects
							(font
								(size 1.27 1.27)
							)
						)
					)
					(number "AD8"
						(effects
							(font
								(size 1.27 1.27)
							)
						)
					)
				)
				(pin output line
					(at 0 -33.02 0)
					(length 5.08)
					(name "PET_1_N"
						(effects
							(font
								(size 1.27 1.27)
							)
						)
					)
					(number "AD10"
						(effects
							(font
								(size 1.27 1.27)
							)
						)
					)
				)
				(pin input line
					(at 0 -38.1 0)
					(length 5.08)
					(name "PER_1_P"
						(effects
							(font
								(size 1.27 1.27)
							)
						)
					)
					(number "AB10"
						(effects
							(font
								(size 1.27 1.27)
							)
						)
					)
				)
				(pin input line
					(at 0 -40.64 0)
					(length 5.08)
					(name "PER_1_N"
						(effects
							(font
								(size 1.27 1.27)
							)
						)
					)
					(number "AB12"
						(effects
							(font
								(size 1.27 1.27)
							)
						)
					)
				)
				(pin output line
					(at 0 -45.72 0)
					(length 5.08)
					(name "PET_2_P"
						(effects
							(font
								(size 1.27 1.27)
							)
						)
					)
					(number "AD14"
						(effects
							(font
								(size 1.27 1.27)
							)
						)
					)
				)
				(pin output line
					(at 0 -48.26 0)
					(length 5.08)
					(name "PET_2_N"
						(effects
							(font
								(size 1.27 1.27)
							)
						)
					)
					(number "AD16"
						(effects
							(font
								(size 1.27 1.27)
							)
						)
					)
				)
				(pin input line
					(at 0 -53.34 0)
					(length 5.08)
					(name "PER_2_P"
						(effects
							(font
								(size 1.27 1.27)
							)
						)
					)
					(number "AB16"
						(effects
							(font
								(size 1.27 1.27)
							)
						)
					)
				)
				(pin input line
					(at 0 -55.88 0)
					(length 5.08)
					(name "PER_2_N"
						(effects
							(font
								(size 1.27 1.27)
							)
						)
					)
					(number "AB18"
						(effects
							(font
								(size 1.27 1.27)
							)
						)
					)
				)
				(pin output line
					(at 0 -60.96 0)
					(length 5.08)
					(name "PET_3_P"
						(effects
							(font
								(size 1.27 1.27)
							)
						)
					)
					(number "AD20"
						(effects
							(font
								(size 1.27 1.27)
							)
						)
					)
				)
				(pin output line
					(at 0 -63.5 0)
					(length 5.08)
					(name "PET_3_N"
						(effects
							(font
								(size 1.27 1.27)
							)
						)
					)
					(number "AD22"
						(effects
							(font
								(size 1.27 1.27)
							)
						)
					)
				)
				(pin input line
					(at 0 -68.58 0)
					(length 5.08)
					(name "PER_3_P"
						(effects
							(font
								(size 1.27 1.27)
							)
						)
					)
					(number "AB22"
						(effects
							(font
								(size 1.27 1.27)
							)
						)
					)
				)
				(pin input line
					(at 0 -71.12 0)
					(length 5.08)
					(name "PER_3_N"
						(effects
							(font
								(size 1.27 1.27)
							)
						)
					)
					(number "AB24"
						(effects
							(font
								(size 1.27 1.27)
							)
						)
					)
				)
				(pin output line
					(at 0 -76.2 0)
					(length 5.08)
					(name "PET_4_P"
						(effects
							(font
								(size 1.27 1.27)
							)
						)
					)
					(number "AD26"
						(effects
							(font
								(size 1.27 1.27)
							)
						)
					)
				)
				(pin output line
					(at 0 -78.74 0)
					(length 5.08)
					(name "PET_4_N"
						(effects
							(font
								(size 1.27 1.27)
							)
						)
					)
					(number "AD28"
						(effects
							(font
								(size 1.27 1.27)
							)
						)
					)
				)
				(pin input line
					(at 0 -83.82 0)
					(length 5.08)
					(name "PER_4_P"
						(effects
							(font
								(size 1.27 1.27)
							)
						)
					)
					(number "AA27"
						(effects
							(font
								(size 1.27 1.27)
							)
						)
					)
				)
				(pin input line
					(at 0 -86.36 0)
					(length 5.08)
					(name "PER_4_N"
						(effects
							(font
								(size 1.27 1.27)
							)
						)
					)
					(number "AB28"
						(effects
							(font
								(size 1.27 1.27)
							)
						)
					)
				)
				(pin output line
					(at 0 -91.44 0)
					(length 5.08)
					(name "PET_5_P"
						(effects
							(font
								(size 1.27 1.27)
							)
						)
					)
					(number "AC31"
						(effects
							(font
								(size 1.27 1.27)
							)
						)
					)
				)
				(pin output line
					(at 0 -93.98 0)
					(length 5.08)
					(name "PET_5_N"
						(effects
							(font
								(size 1.27 1.27)
							)
						)
					)
					(number "AD32"
						(effects
							(font
								(size 1.27 1.27)
							)
						)
					)
				)
				(pin input line
					(at 0 -99.06 0)
					(length 5.08)
					(name "PER_5_P"
						(effects
							(font
								(size 1.27 1.27)
							)
						)
					)
					(number "Y30"
						(effects
							(font
								(size 1.27 1.27)
							)
						)
					)
				)
				(pin input line
					(at 0 -101.6 0)
					(length 5.08)
					(name "PER_5_N"
						(effects
							(font
								(size 1.27 1.27)
							)
						)
					)
					(number "AA31"
						(effects
							(font
								(size 1.27 1.27)
							)
						)
					)
				)
				(pin output line
					(at 0 -106.68 0)
					(length 5.08)
					(name "PET_6_P"
						(effects
							(font
								(size 1.27 1.27)
							)
						)
					)
					(number "AC35"
						(effects
							(font
								(size 1.27 1.27)
							)
						)
					)
				)
				(pin output line
					(at 0 -109.22 0)
					(length 5.08)
					(name "PET_6_N"
						(effects
							(font
								(size 1.27 1.27)
							)
						)
					)
					(number "AD36"
						(effects
							(font
								(size 1.27 1.27)
							)
						)
					)
				)
				(pin input line
					(at 0 -114.3 0)
					(length 5.08)
					(name "PER_6_P"
						(effects
							(font
								(size 1.27 1.27)
							)
						)
					)
					(number "Y34"
						(effects
							(font
								(size 1.27 1.27)
							)
						)
					)
				)
				(pin input line
					(at 0 -116.84 0)
					(length 5.08)
					(name "PER_6_N"
						(effects
							(font
								(size 1.27 1.27)
							)
						)
					)
					(number "AA35"
						(effects
							(font
								(size 1.27 1.27)
							)
						)
					)
				)
				(pin output line
					(at 0 -121.92 0)
					(length 5.08)
					(name "PET_7_P"
						(effects
							(font
								(size 1.27 1.27)
							)
						)
					)
					(number "AC39"
						(effects
							(font
								(size 1.27 1.27)
							)
						)
					)
				)
				(pin output line
					(at 0 -124.46 0)
					(length 5.08)
					(name "PET_7_N"
						(effects
							(font
								(size 1.27 1.27)
							)
						)
					)
					(number "AD40"
						(effects
							(font
								(size 1.27 1.27)
							)
						)
					)
				)
				(pin input line
					(at 0 -129.54 0)
					(length 5.08)
					(name "PER_7_P"
						(effects
							(font
								(size 1.27 1.27)
							)
						)
					)
					(number "Y38"
						(effects
							(font
								(size 1.27 1.27)
							)
						)
					)
				)
				(pin input line
					(at 0 -132.08 0)
					(length 5.08)
					(name "PER_7_N"
						(effects
							(font
								(size 1.27 1.27)
							)
						)
					)
					(number "AA39"
						(effects
							(font
								(size 1.27 1.27)
							)
						)
					)
				)
				(pin input line
					(at 35.56 0 180)
					(length 5.08)
					(name "~{JRST}"
						(effects
							(font
								(size 1.27 1.27)
							)
						)
					)
					(number "V36"
						(effects
							(font
								(size 1.27 1.27)
							)
						)
					)
				)
				(pin input line
					(at 35.56 -2.54 180)
					(length 5.08)
					(name "JTCK"
						(effects
							(font
								(size 1.27 1.27)
							)
						)
					)
					(number "U37"
						(effects
							(font
								(size 1.27 1.27)
							)
						)
					)
				)
				(pin input line
					(at 35.56 -5.08 180)
					(length 5.08)
					(name "JTMS"
						(effects
							(font
								(size 1.27 1.27)
							)
						)
					)
					(number "V38"
						(effects
							(font
								(size 1.27 1.27)
							)
						)
					)
				)
				(pin input line
					(at 35.56 -7.62 180)
					(length 5.08)
					(name "JTDI"
						(effects
							(font
								(size 1.27 1.27)
							)
						)
					)
					(number "T36"
						(effects
							(font
								(size 1.27 1.27)
							)
						)
					)
				)
				(pin open_collector line
					(at 35.56 -10.16 180)
					(length 5.08)
					(name "JTDO"
						(effects
							(font
								(size 1.27 1.27)
							)
						)
					)
					(number "T38"
						(effects
							(font
								(size 1.27 1.27)
							)
						)
					)
				)
				(pin passive line
					(at 35.56 -129.54 180)
					(length 5.08)
					(name "RBIAS"
						(effects
							(font
								(size 1.27 1.27)
							)
						)
					)
					(number "Y10"
						(effects
							(font
								(size 1.27 1.27)
							)
						)
					)
				)
				(pin passive line
					(at 35.56 -132.08 180)
					(length 5.08)
					(name "RSENSE"
						(effects
							(font
								(size 1.27 1.27)
							)
						)
					)
					(number "Y12"
						(effects
							(font
								(size 1.27 1.27)
							)
						)
					)
				)
			)
			(symbol "EZX710AT2_S_LMR5_2_1"
				(rectangle
					(start 5.08 2.54)
					(end 40.64 -60.96)
					(stroke
						(width 0.254)
						(type default)
					)
					(fill
						(type background)
					)
				)
				(polyline
					(pts
						(xy 13.97 1.27) (xy 13.97 -26.67)
					)
					(stroke
						(width 0.254)
						(type solid)
					)
					(fill
						(type background)
					)
				)
				(polyline
					(pts
						(xy 17.78 -31.75) (xy 17.78 -59.69)
					)
					(stroke
						(width 0.254)
						(type solid)
					)
					(fill
						(type background)
					)
				)
				(polyline
					(pts
						(xy 31.75 1.27) (xy 31.75 -26.67)
					)
					(stroke
						(width 0.254)
						(type solid)
					)
					(fill
						(type background)
					)
				)
				(text "P0 10GBASE-T"
					(at 15.24 -19.05 900)
					(effects
						(font
							(size 1.27 1.27)
							(thickness 0.15)
						)
						(justify left top)
					)
				)
				(text "LINE INPUT/OUTPUT"
					(at 20.32 -54.61 900)
					(effects
						(font
							(size 1.27 1.27)
							(thickness 0.15)
						)
						(justify left bottom)
					)
				)
				(text "P1 10GBASE-T"
					(at 30.48 -19.05 900)
					(effects
						(font
							(size 1.27 1.27)
							(thickness 0.15)
						)
						(justify left bottom)
					)
				)
				(pin bidirectional line
					(at 0 0 0)
					(length 5.08)
					(name "P0_A_P"
						(effects
							(font
								(size 1.27 1.27)
							)
						)
					)
					(number "B40"
						(effects
							(font
								(size 1.27 1.27)
							)
						)
					)
				)
				(pin bidirectional line
					(at 0 -2.54 0)
					(length 5.08)
					(name "P0_A_N"
						(effects
							(font
								(size 1.27 1.27)
							)
						)
					)
					(number "A39"
						(effects
							(font
								(size 1.27 1.27)
							)
						)
					)
				)
				(pin bidirectional line
					(at 0 -7.62 0)
					(length 5.08)
					(name "P0_B_P"
						(effects
							(font
								(size 1.27 1.27)
							)
						)
					)
					(number "A37"
						(effects
							(font
								(size 1.27 1.27)
							)
						)
					)
				)
				(pin bidirectional line
					(at 0 -10.16 0)
					(length 5.08)
					(name "P0_B_N"
						(effects
							(font
								(size 1.27 1.27)
							)
						)
					)
					(number "B38"
						(effects
							(font
								(size 1.27 1.27)
							)
						)
					)
				)
				(pin bidirectional line
					(at 0 -15.24 0)
					(length 5.08)
					(name "P0_C_P"
						(effects
							(font
								(size 1.27 1.27)
							)
						)
					)
					(number "B36"
						(effects
							(font
								(size 1.27 1.27)
							)
						)
					)
				)
				(pin bidirectional line
					(at 0 -17.78 0)
					(length 5.08)
					(name "P0_C_N"
						(effects
							(font
								(size 1.27 1.27)
							)
						)
					)
					(number "A35"
						(effects
							(font
								(size 1.27 1.27)
							)
						)
					)
				)
				(pin bidirectional line
					(at 0 -22.86 0)
					(length 5.08)
					(name "P0_D_P"
						(effects
							(font
								(size 1.27 1.27)
							)
						)
					)
					(number "A33"
						(effects
							(font
								(size 1.27 1.27)
							)
						)
					)
				)
				(pin bidirectional line
					(at 0 -25.4 0)
					(length 5.08)
					(name "P0_D_N"
						(effects
							(font
								(size 1.27 1.27)
							)
						)
					)
					(number "B34"
						(effects
							(font
								(size 1.27 1.27)
							)
						)
					)
				)
				(pin output line
					(at 0 -33.02 0)
					(length 5.08)
					(name "SER0_TX_P"
						(effects
							(font
								(size 1.27 1.27)
							)
						)
					)
					(number "A17"
						(effects
							(font
								(size 1.27 1.27)
							)
						)
					)
				)
				(pin output line
					(at 0 -35.56 0)
					(length 5.08)
					(name "SER0_TX_N"
						(effects
							(font
								(size 1.27 1.27)
							)
						)
					)
					(number "B18"
						(effects
							(font
								(size 1.27 1.27)
							)
						)
					)
				)
				(pin input line
					(at 0 -40.64 0)
					(length 5.08)
					(name "SER0_RX_P"
						(effects
							(font
								(size 1.27 1.27)
							)
						)
					)
					(number "B14"
						(effects
							(font
								(size 1.27 1.27)
							)
						)
					)
				)
				(pin input line
					(at 0 -43.18 0)
					(length 5.08)
					(name "SER0_RX_N"
						(effects
							(font
								(size 1.27 1.27)
							)
						)
					)
					(number "A13"
						(effects
							(font
								(size 1.27 1.27)
							)
						)
					)
				)
				(pin output line
					(at 0 -48.26 0)
					(length 5.08)
					(name "SER1_TX_P"
						(effects
							(font
								(size 1.27 1.27)
							)
						)
					)
					(number "A9"
						(effects
							(font
								(size 1.27 1.27)
							)
						)
					)
				)
				(pin output line
					(at 0 -50.8 0)
					(length 5.08)
					(name "SER1_TX_N"
						(effects
							(font
								(size 1.27 1.27)
							)
						)
					)
					(number "B10"
						(effects
							(font
								(size 1.27 1.27)
							)
						)
					)
				)
				(pin input line
					(at 0 -55.88 0)
					(length 5.08)
					(name "SER1_RX_P"
						(effects
							(font
								(size 1.27 1.27)
							)
						)
					)
					(number "B6"
						(effects
							(font
								(size 1.27 1.27)
							)
						)
					)
				)
				(pin input line
					(at 0 -58.42 0)
					(length 5.08)
					(name "SER1_RX_N"
						(effects
							(font
								(size 1.27 1.27)
							)
						)
					)
					(number "A5"
						(effects
							(font
								(size 1.27 1.27)
							)
						)
					)
				)
				(pin bidirectional line
					(at 45.72 0 180)
					(length 5.08)
					(name "P1_A_P"
						(effects
							(font
								(size 1.27 1.27)
							)
						)
					)
					(number "A23"
						(effects
							(font
								(size 1.27 1.27)
							)
						)
					)
				)
				(pin bidirectional line
					(at 45.72 -2.54 180)
					(length 5.08)
					(name "P1_A_N"
						(effects
							(font
								(size 1.27 1.27)
							)
						)
					)
					(number "B24"
						(effects
							(font
								(size 1.27 1.27)
							)
						)
					)
				)
				(pin bidirectional line
					(at 45.72 -7.62 180)
					(length 5.08)
					(name "P1_B_P"
						(effects
							(font
								(size 1.27 1.27)
							)
						)
					)
					(number "B26"
						(effects
							(font
								(size 1.27 1.27)
							)
						)
					)
				)
				(pin bidirectional line
					(at 45.72 -10.16 180)
					(length 5.08)
					(name "P1_B_N"
						(effects
							(font
								(size 1.27 1.27)
							)
						)
					)
					(number "A25"
						(effects
							(font
								(size 1.27 1.27)
							)
						)
					)
				)
				(pin bidirectional line
					(at 45.72 -15.24 180)
					(length 5.08)
					(name "P1_C_P"
						(effects
							(font
								(size 1.27 1.27)
							)
						)
					)
					(number "A27"
						(effects
							(font
								(size 1.27 1.27)
							)
						)
					)
				)
				(pin bidirectional line
					(at 45.72 -17.78 180)
					(length 5.08)
					(name "P1_C_N"
						(effects
							(font
								(size 1.27 1.27)
							)
						)
					)
					(number "B28"
						(effects
							(font
								(size 1.27 1.27)
							)
						)
					)
				)
				(pin bidirectional line
					(at 45.72 -22.86 180)
					(length 5.08)
					(name "P1_D_P"
						(effects
							(font
								(size 1.27 1.27)
							)
						)
					)
					(number "B30"
						(effects
							(font
								(size 1.27 1.27)
							)
						)
					)
				)
				(pin bidirectional line
					(at 45.72 -25.4 180)
					(length 5.08)
					(name "P1_D_N"
						(effects
							(font
								(size 1.27 1.27)
							)
						)
					)
					(number "A29"
						(effects
							(font
								(size 1.27 1.27)
							)
						)
					)
				)
				(pin passive line
					(at 45.72 -55.88 180)
					(length 5.08)
					(name "BIAS_RDAC"
						(effects
							(font
								(size 1.27 1.27)
							)
						)
					)
					(number "E39"
						(effects
							(font
								(size 1.27 1.27)
							)
						)
					)
				)
				(pin passive line
					(at 45.72 -58.42 180)
					(length 5.08)
					(name "RESCAL_RES_P"
						(effects
							(font
								(size 1.27 1.27)
							)
						)
					)
					(number "J37"
						(effects
							(font
								(size 1.27 1.27)
							)
						)
					)
				)
			)
			(symbol "EZX710AT2_S_LMR5_3_1"
				(rectangle
					(start 5.08 2.54)
					(end 40.64 -66.04)
					(stroke
						(width 0.254)
						(type default)
					)
					(fill
						(type background)
					)
				)
				(polyline
					(pts
						(xy 13.97 -29.21) (xy 13.97 -39.37)
					)
					(stroke
						(width 0.254)
						(type solid)
					)
					(fill
						(type background)
					)
				)
				(polyline
					(pts
						(xy 13.97 -41.91) (xy 13.97 -52.07)
					)
					(stroke
						(width 0.254)
						(type solid)
					)
					(fill
						(type background)
					)
				)
				(polyline
					(pts
						(xy 17.78 -6.35) (xy 17.78 -26.67)
					)
					(stroke
						(width 0.254)
						(type solid)
					)
					(fill
						(type background)
					)
				)
				(polyline
					(pts
						(xy 31.75 1.27) (xy 31.75 -8.89)
					)
					(stroke
						(width 0.254)
						(type solid)
					)
					(fill
						(type background)
					)
				)
				(polyline
					(pts
						(xy 31.75 -11.43) (xy 31.75 -21.59)
					)
					(stroke
						(width 0.254)
						(type solid)
					)
					(fill
						(type background)
					)
				)
				(polyline
					(pts
						(xy 31.75 -29.21) (xy 31.75 -39.37)
					)
					(stroke
						(width 0.254)
						(type solid)
					)
					(fill
						(type background)
					)
				)
				(polyline
					(pts
						(xy 31.75 -41.91) (xy 31.75 -52.07)
					)
					(stroke
						(width 0.254)
						(type solid)
					)
					(fill
						(type background)
					)
				)
				(text "P0 SDP"
					(at 16.51 -37.592 900)
					(effects
						(font
							(size 1.27 1.27)
							(thickness 0.15)
						)
						(justify left bottom)
					)
				)
				(text "P1 SDP"
					(at 16.51 -50.8 900)
					(effects
						(font
							(size 1.27 1.27)
							(thickness 0.15)
						)
						(justify left bottom)
					)
				)
				(text "NC (pull-up)"
					(at 19.812 -23.368 900)
					(effects
						(font
							(size 1.27 1.27)
							(thickness 0.15)
						)
						(justify left bottom)
					)
				)
				(text "P3 SDP"
					(at 30.226 -37.846 900)
					(effects
						(font
							(size 1.27 1.27)
							(thickness 0.15)
						)
						(justify left bottom)
					)
				)
				(text "P0 LED"
					(at 30.48 -1.778 0)
					(effects
						(font
							(size 1.27 1.27)
							(thickness 0.15)
						)
						(justify right bottom)
					)
				)
				(text "P2 LED"
					(at 30.48 -6.858 0)
					(effects
						(font
							(size 1.27 1.27)
							(thickness 0.15)
						)
						(justify right bottom)
					)
				)
				(text "P1 LED"
					(at 30.48 -14.732 0)
					(effects
						(font
							(size 1.27 1.27)
							(thickness 0.15)
						)
						(justify right bottom)
					)
				)
				(text "P3 LED"
					(at 30.48 -19.558 0)
					(effects
						(font
							(size 1.27 1.27)
							(thickness 0.15)
						)
						(justify right bottom)
					)
				)
				(text "P3 SDP"
					(at 30.48 -51.054 900)
					(effects
						(font
							(size 1.27 1.27)
							(thickness 0.15)
						)
						(justify left bottom)
					)
				)
				(pin bidirectional line
					(at 0 0 0)
					(length 5.08)
					(name "MDIO0_SDA0"
						(effects
							(font
								(size 1.27 1.27)
							)
						)
					)
					(number "N1"
						(effects
							(font
								(size 1.27 1.27)
							)
						)
					)
				)
				(pin output line
					(at 0 -2.54 0)
					(length 5.08)
					(name "MDC0_SCL0"
						(effects
							(font
								(size 1.27 1.27)
							)
						)
					)
					(number "N3"
						(effects
							(font
								(size 1.27 1.27)
							)
						)
					)
				)
				(pin passive line
					(at 0 -7.62 0)
					(length 5.08)
					(name "MDIO1_SDA1"
						(effects
							(font
								(size 1.27 1.27)
							)
						)
					)
					(number "M2"
						(effects
							(font
								(size 1.27 1.27)
							)
						)
					)
				)
				(pin passive line
					(at 0 -10.16 0)
					(length 5.08)
					(name "MDC1_SCL1"
						(effects
							(font
								(size 1.27 1.27)
							)
						)
					)
					(number "M4"
						(effects
							(font
								(size 1.27 1.27)
							)
						)
					)
				)
				(pin passive line
					(at 0 -15.24 0)
					(length 5.08)
					(name "MDIO2_SDA2"
						(effects
							(font
								(size 1.27 1.27)
							)
						)
					)
					(number "L1"
						(effects
							(font
								(size 1.27 1.27)
							)
						)
					)
				)
				(pin passive line
					(at 0 -17.78 0)
					(length 5.08)
					(name "MDC2_SCL2"
						(effects
							(font
								(size 1.27 1.27)
							)
						)
					)
					(number "L3"
						(effects
							(font
								(size 1.27 1.27)
							)
						)
					)
				)
				(pin passive line
					(at 0 -22.86 0)
					(length 5.08)
					(name "MDIO3_SDA3"
						(effects
							(font
								(size 1.27 1.27)
							)
						)
					)
					(number "K2"
						(effects
							(font
								(size 1.27 1.27)
							)
						)
					)
				)
				(pin passive line
					(at 0 -25.4 0)
					(length 5.08)
					(name "MDC3_SCL3"
						(effects
							(font
								(size 1.27 1.27)
							)
						)
					)
					(number "K4"
						(effects
							(font
								(size 1.27 1.27)
							)
						)
					)
				)
				(pin tri_state line
					(at 0 -30.48 0)
					(length 5.08)
					(name "SDP0_0"
						(effects
							(font
								(size 1.27 1.27)
							)
						)
					)
					(number "E5"
						(effects
							(font
								(size 1.27 1.27)
							)
						)
					)
				)
				(pin tri_state line
					(at 0 -33.02 0)
					(length 5.08)
					(name "SDP0_1"
						(effects
							(font
								(size 1.27 1.27)
							)
						)
					)
					(number "G5"
						(effects
							(font
								(size 1.27 1.27)
							)
						)
					)
				)
				(pin tri_state line
					(at 0 -35.56 0)
					(length 5.08)
					(name "SDP0_2"
						(effects
							(font
								(size 1.27 1.27)
							)
						)
					)
					(number "K6"
						(effects
							(font
								(size 1.27 1.27)
							)
						)
					)
				)
				(pin passive line
					(at 0 -38.1 0)
					(length 5.08)
					(name "SDP0_3"
						(effects
							(font
								(size 1.27 1.27)
							)
						)
					)
					(number "L5"
						(effects
							(font
								(size 1.27 1.27)
							)
						)
					)
				)
				(pin passive line
					(at 0 -43.18 0)
					(length 5.08)
					(name "SDP1_0"
						(effects
							(font
								(size 1.27 1.27)
							)
						)
					)
					(number "R7"
						(effects
							(font
								(size 1.27 1.27)
							)
						)
					)
				)
				(pin passive line
					(at 0 -45.72 0)
					(length 5.08)
					(name "SDP1_1"
						(effects
							(font
								(size 1.27 1.27)
							)
						)
					)
					(number "P4"
						(effects
							(font
								(size 1.27 1.27)
							)
						)
					)
				)
				(pin passive line
					(at 0 -48.26 0)
					(length 5.08)
					(name "SDP1_2"
						(effects
							(font
								(size 1.27 1.27)
							)
						)
					)
					(number "P6"
						(effects
							(font
								(size 1.27 1.27)
							)
						)
					)
				)
				(pin passive line
					(at 0 -50.8 0)
					(length 5.08)
					(name "SDP1_3"
						(effects
							(font
								(size 1.27 1.27)
							)
						)
					)
					(number "H6"
						(effects
							(font
								(size 1.27 1.27)
							)
						)
					)
				)
				(pin input line
					(at 0 -55.88 0)
					(length 5.08)
					(name "REFCLKIN_P"
						(effects
							(font
								(size 1.27 1.27)
							)
						)
					)
					(number "C1"
						(effects
							(font
								(size 1.27 1.27)
							)
						)
					)
					(alternate "XTAL_IN" input line)
				)
				(pin input line
					(at 0 -58.42 0)
					(length 5.08)
					(name "REFCLKIN_N"
						(effects
							(font
								(size 1.27 1.27)
							)
						)
					)
					(number "C3"
						(effects
							(font
								(size 1.27 1.27)
							)
						)
					)
					(alternate "XTAL_OUT" output line)
				)
				(pin tri_state line
					(at 0 -63.5 0)
					(length 5.08)
					(name "OSC_SEL"
						(effects
							(font
								(size 1.27 1.27)
							)
						)
					)
					(number "J9"
						(effects
							(font
								(size 1.27 1.27)
							)
						)
					)
				)
				(pin output line
					(at 45.72 0 180)
					(length 5.08)
					(name "LED0_0"
						(effects
							(font
								(size 1.27 1.27)
							)
						)
					)
					(number "V4"
						(effects
							(font
								(size 1.27 1.27)
							)
						)
					)
				)
				(pin output line
					(at 45.72 -2.54 180)
					(length 5.08)
					(name "LED0_1"
						(effects
							(font
								(size 1.27 1.27)
							)
						)
					)
					(number "V6"
						(effects
							(font
								(size 1.27 1.27)
							)
						)
					)
				)
				(pin output line
					(at 45.72 -5.08 180)
					(length 5.08)
					(name "LED2_0"
						(effects
							(font
								(size 1.27 1.27)
							)
						)
					)
					(number "T4"
						(effects
							(font
								(size 1.27 1.27)
							)
						)
					)
				)
				(pin output line
					(at 45.72 -7.62 180)
					(length 5.08)
					(name "LED2_1"
						(effects
							(font
								(size 1.27 1.27)
							)
						)
					)
					(number "T6"
						(effects
							(font
								(size 1.27 1.27)
							)
						)
					)
				)
				(pin passive line
					(at 45.72 -12.7 180)
					(length 5.08)
					(name "LED1_0"
						(effects
							(font
								(size 1.27 1.27)
							)
						)
					)
					(number "U5"
						(effects
							(font
								(size 1.27 1.27)
							)
						)
					)
				)
				(pin passive line
					(at 45.72 -15.24 180)
					(length 5.08)
					(name "LED1_1"
						(effects
							(font
								(size 1.27 1.27)
							)
						)
					)
					(number "U7"
						(effects
							(font
								(size 1.27 1.27)
							)
						)
					)
				)
				(pin passive line
					(at 45.72 -17.78 180)
					(length 5.08)
					(name "LED3_0"
						(effects
							(font
								(size 1.27 1.27)
							)
						)
					)
					(number "R3"
						(effects
							(font
								(size 1.27 1.27)
							)
						)
					)
				)
				(pin passive line
					(at 45.72 -20.32 180)
					(length 5.08)
					(name "LED3_1"
						(effects
							(font
								(size 1.27 1.27)
							)
						)
					)
					(number "R5"
						(effects
							(font
								(size 1.27 1.27)
							)
						)
					)
				)
				(pin passive line
					(at 45.72 -30.48 180)
					(length 5.08)
					(name "SDP2_0"
						(effects
							(font
								(size 1.27 1.27)
							)
						)
					)
					(number "F6"
						(effects
							(font
								(size 1.27 1.27)
							)
						)
					)
				)
				(pin passive line
					(at 45.72 -33.02 180)
					(length 5.08)
					(name "SDP2_1"
						(effects
							(font
								(size 1.27 1.27)
							)
						)
					)
					(number "J7"
						(effects
							(font
								(size 1.27 1.27)
							)
						)
					)
				)
				(pin passive line
					(at 45.72 -35.56 180)
					(length 5.08)
					(name "SDP2_2"
						(effects
							(font
								(size 1.27 1.27)
							)
						)
					)
					(number "E7"
						(effects
							(font
								(size 1.27 1.27)
							)
						)
					)
				)
				(pin passive line
					(at 45.72 -38.1 180)
					(length 5.08)
					(name "SDP2_3"
						(effects
							(font
								(size 1.27 1.27)
							)
						)
					)
					(number "G7"
						(effects
							(font
								(size 1.27 1.27)
							)
						)
					)
				)
				(pin passive line
					(at 45.72 -43.18 180)
					(length 5.08)
					(name "SDP3_0"
						(effects
							(font
								(size 1.27 1.27)
							)
						)
					)
					(number "N5"
						(effects
							(font
								(size 1.27 1.27)
							)
						)
					)
				)
				(pin passive line
					(at 45.72 -45.72 180)
					(length 5.08)
					(name "SDP3_1"
						(effects
							(font
								(size 1.27 1.27)
							)
						)
					)
					(number "N7"
						(effects
							(font
								(size 1.27 1.27)
							)
						)
					)
				)
				(pin passive line
					(at 45.72 -48.26 180)
					(length 5.08)
					(name "SDP3_2"
						(effects
							(font
								(size 1.27 1.27)
							)
						)
					)
					(number "M6"
						(effects
							(font
								(size 1.27 1.27)
							)
						)
					)
				)
				(pin passive line
					(at 45.72 -50.8 180)
					(length 5.08)
					(name "SDP3_3"
						(effects
							(font
								(size 1.27 1.27)
							)
						)
					)
					(number "M8"
						(effects
							(font
								(size 1.27 1.27)
							)
						)
					)
				)
				(pin passive line
					(at 45.72 -60.96 180)
					(length 5.08)
					(name "TPIN_5"
						(effects
							(font
								(size 1.27 1.27)
							)
						)
					)
					(number "G17"
						(effects
							(font
								(size 1.27 1.27)
							)
						)
					)
				)
				(pin passive line
					(at 45.72 -63.5 180)
					(length 5.08)
					(name "TPIN_3"
						(effects
							(font
								(size 1.27 1.27)
							)
						)
					)
					(number "H20"
						(effects
							(font
								(size 1.27 1.27)
							)
						)
					)
				)
			)
			(symbol "EZX710AT2_S_LMR5_4_1"
				(rectangle
					(start 5.08 2.54)
					(end 40.64 -50.8)
					(stroke
						(width 0.254)
						(type default)
					)
					(fill
						(type background)
					)
				)
				(polyline
					(pts
						(xy 20.32 -26.67) (xy 20.32 1.27)
					)
					(stroke
						(width 0.254)
						(type solid)
					)
					(fill
						(type background)
					)
				)
				(polyline
					(pts
						(xy 29.21 -39.37) (xy 29.21 -49.53)
					)
					(stroke
						(width 0.254)
						(type solid)
					)
					(fill
						(type background)
					)
				)
				(polyline
					(pts
						(xy 30.48 -31.75) (xy 30.48 -24.13)
					)
					(stroke
						(width 0.254)
						(type solid)
					)
					(fill
						(type background)
					)
				)
				(polyline
					(pts
						(xy 31.75 1.27) (xy 31.75 -13.97)
					)
					(stroke
						(width 0.254)
						(type solid)
					)
					(fill
						(type background)
					)
				)
				(text "NC-SI"
					(at 22.86 -16.256 900)
					(effects
						(font
							(size 1.27 1.27)
							(thickness 0.15)
						)
						(justify left bottom)
					)
				)
				(text "SMBus"
					(at 27.94 -30.988 900)
					(effects
						(font
							(size 1.27 1.27)
							(thickness 0.15)
						)
						(justify left top)
					)
				)
				(text "Flash"
					(at 27.94 -47.244 900)
					(effects
						(font
							(size 1.27 1.27)
							(thickness 0.15)
						)
						(justify left bottom)
					)
				)
				(text "GPIO"
					(at 30.48 -8.636 900)
					(effects
						(font
							(size 1.27 1.27)
							(thickness 0.15)
						)
						(justify left bottom)
					)
				)
				(pin input line
					(at 0 0 0)
					(length 5.08)
					(name "NCSI_ARB_IN"
						(effects
							(font
								(size 1.27 1.27)
							)
						)
					)
					(number "G3"
						(effects
							(font
								(size 1.27 1.27)
							)
						)
					)
				)
				(pin output line
					(at 0 -2.54 0)
					(length 5.08)
					(name "NCSI_ARB_OUT"
						(effects
							(font
								(size 1.27 1.27)
							)
						)
					)
					(number "F4"
						(effects
							(font
								(size 1.27 1.27)
							)
						)
					)
				)
				(pin input line
					(at 0 -5.08 0)
					(length 5.08)
					(name "NCSI_CLK_IN"
						(effects
							(font
								(size 1.27 1.27)
							)
						)
					)
					(number "H2"
						(effects
							(font
								(size 1.27 1.27)
							)
						)
					)
				)
				(pin output line
					(at 0 -7.62 0)
					(length 5.08)
					(name "NCSI_CRS_DV"
						(effects
							(font
								(size 1.27 1.27)
							)
						)
					)
					(number "J5"
						(effects
							(font
								(size 1.27 1.27)
							)
						)
					)
				)
				(pin input line
					(at 0 -10.16 0)
					(length 5.08)
					(name "NCSI_TX_EN"
						(effects
							(font
								(size 1.27 1.27)
							)
						)
					)
					(number "H4"
						(effects
							(font
								(size 1.27 1.27)
							)
						)
					)
				)
				(pin input line
					(at 0 -15.24 0)
					(length 5.08)
					(name "NCSI_TXD_0"
						(effects
							(font
								(size 1.27 1.27)
							)
						)
					)
					(number "F2"
						(effects
							(font
								(size 1.27 1.27)
							)
						)
					)
				)
				(pin output line
					(at 0 -17.78 0)
					(length 5.08)
					(name "NCSI_RXD_0"
						(effects
							(font
								(size 1.27 1.27)
							)
						)
					)
					(number "J1"
						(effects
							(font
								(size 1.27 1.27)
							)
						)
					)
				)
				(pin input line
					(at 0 -22.86 0)
					(length 5.08)
					(name "NCSI_TXD_1"
						(effects
							(font
								(size 1.27 1.27)
							)
						)
					)
					(number "G1"
						(effects
							(font
								(size 1.27 1.27)
							)
						)
					)
				)
				(pin output line
					(at 0 -25.4 0)
					(length 5.08)
					(name "NCSI_RXD_1"
						(effects
							(font
								(size 1.27 1.27)
							)
						)
					)
					(number "J3"
						(effects
							(font
								(size 1.27 1.27)
							)
						)
					)
				)
				(pin tri_state line
					(at 0 -33.02 0)
					(length 5.08)
					(name "~{DEV_DIS}"
						(effects
							(font
								(size 1.27 1.27)
							)
						)
					)
					(number "D2"
						(effects
							(font
								(size 1.27 1.27)
							)
						)
					)
				)
				(pin tri_state line
					(at 0 -35.56 0)
					(length 5.08)
					(name "~{PCI_DIS}"
						(effects
							(font
								(size 1.27 1.27)
							)
						)
					)
					(number "U3"
						(effects
							(font
								(size 1.27 1.27)
							)
						)
					)
				)
				(pin input line
					(at 0 -40.64 0)
					(length 5.08)
					(name "MAIN_PWR_OK"
						(effects
							(font
								(size 1.27 1.27)
							)
						)
					)
					(number "E3"
						(effects
							(font
								(size 1.27 1.27)
							)
						)
					)
				)
				(pin tri_state line
					(at 0 -43.18 0)
					(length 5.08)
					(name "AUX_PWR"
						(effects
							(font
								(size 1.27 1.27)
							)
						)
					)
					(number "E1"
						(effects
							(font
								(size 1.27 1.27)
							)
						)
					)
				)
				(pin input line
					(at 0 -45.72 0)
					(length 5.08)
					(name "POR_BYPASS"
						(effects
							(font
								(size 1.27 1.27)
							)
						)
					)
					(number "U39"
						(effects
							(font
								(size 1.27 1.27)
							)
						)
					)
				)
				(pin input line
					(at 0 -48.26 0)
					(length 5.08)
					(name "LAN_PWR_GOOD"
						(effects
							(font
								(size 1.27 1.27)
							)
						)
					)
					(number "AB42"
						(effects
							(font
								(size 1.27 1.27)
							)
						)
					)
				)
				(pin tri_state line
					(at 45.72 0 180)
					(length 5.08)
					(name "GPIO_0"
						(effects
							(font
								(size 1.27 1.27)
							)
						)
					)
					(number "V40"
						(effects
							(font
								(size 1.27 1.27)
							)
						)
					)
				)
				(pin passive line
					(at 45.72 -2.54 180)
					(length 5.08)
					(name "GPIO_1"
						(effects
							(font
								(size 1.27 1.27)
							)
						)
					)
					(number "W41"
						(effects
							(font
								(size 1.27 1.27)
							)
						)
					)
				)
				(pin tri_state line
					(at 45.72 -5.08 180)
					(length 5.08)
					(name "GPIO_2"
						(effects
							(font
								(size 1.27 1.27)
							)
						)
					)
					(number "Y42"
						(effects
							(font
								(size 1.27 1.27)
							)
						)
					)
				)
				(pin passive line
					(at 45.72 -7.62 180)
					(length 5.08)
					(name "GPIO_3"
						(effects
							(font
								(size 1.27 1.27)
							)
						)
					)
					(number "V42"
						(effects
							(font
								(size 1.27 1.27)
							)
						)
					)
				)
				(pin passive line
					(at 45.72 -10.16 180)
					(length 5.08)
					(name "GPIO_4"
						(effects
							(font
								(size 1.27 1.27)
							)
						)
					)
					(number "H8"
						(effects
							(font
								(size 1.27 1.27)
							)
						)
					)
				)
				(pin tri_state line
					(at 45.72 -12.7 180)
					(length 5.08)
					(name "GPIO_5"
						(effects
							(font
								(size 1.27 1.27)
							)
						)
					)
					(number "L7"
						(effects
							(font
								(size 1.27 1.27)
							)
						)
					)
				)
				(pin open_collector line
					(at 45.72 -25.4 180)
					(length 5.08)
					(name "~{SMBALRT}"
						(effects
							(font
								(size 1.27 1.27)
							)
						)
					)
					(number "U41"
						(effects
							(font
								(size 1.27 1.27)
							)
						)
					)
				)
				(pin open_collector line
					(at 45.72 -27.94 180)
					(length 5.08)
					(name "SMBCLK"
						(effects
							(font
								(size 1.27 1.27)
							)
						)
					)
					(number "R39"
						(effects
							(font
								(size 1.27 1.27)
							)
						)
					)
				)
				(pin open_collector line
					(at 45.72 -30.48 180)
					(length 5.08)
					(name "SMBD"
						(effects
							(font
								(size 1.27 1.27)
							)
						)
					)
					(number "T40"
						(effects
							(font
								(size 1.27 1.27)
							)
						)
					)
				)
				(pin tri_state line
					(at 45.72 -40.64 180)
					(length 5.08)
					(name "~{FLSH_CE}"
						(effects
							(font
								(size 1.27 1.27)
							)
						)
					)
					(number "R41"
						(effects
							(font
								(size 1.27 1.27)
							)
						)
					)
				)
				(pin tri_state line
					(at 45.72 -43.18 180)
					(length 5.08)
					(name "FLSH_SCK"
						(effects
							(font
								(size 1.27 1.27)
							)
						)
					)
					(number "P40"
						(effects
							(font
								(size 1.27 1.27)
							)
						)
					)
				)
				(pin tri_state line
					(at 45.72 -45.72 180)
					(length 5.08)
					(name "FLSH_SI"
						(effects
							(font
								(size 1.27 1.27)
							)
						)
					)
					(number "P42"
						(effects
							(font
								(size 1.27 1.27)
							)
						)
					)
				)
				(pin input line
					(at 45.72 -48.26 180)
					(length 5.08)
					(name "FLSH_SO"
						(effects
							(font
								(size 1.27 1.27)
							)
						)
					)
					(number "T42"
						(effects
							(font
								(size 1.27 1.27)
							)
						)
					)
				)
			)
			(symbol "EZX710AT2_S_LMR5_5_1"
				(rectangle
					(start 5.08 2.54)
					(end 38.1 -93.98)
					(stroke
						(width 0.254)
						(type default)
					)
					(fill
						(type background)
					)
				)
				(pin passive line
					(at 0 0 0)
					(length 5.08)
					(name "RSVDY24_VSS"
						(effects
							(font
								(size 1.27 1.27)
							)
						)
					)
					(number "Y24"
						(effects
							(font
								(size 1.27 1.27)
							)
						)
					)
					(alternate "RSVD" passive line)
					(alternate "VSS" power_in line)
				)
				(pin passive line
					(at 0 -5.08 0)
					(length 5.08)
					(name "RSVDY22_VSS"
						(effects
							(font
								(size 1.27 1.27)
							)
						)
					)
					(number "Y22"
						(effects
							(font
								(size 1.27 1.27)
							)
						)
					)
					(alternate "RSVD" passive line)
					(alternate "VSS" power_in line)
				)
				(pin passive line
					(at 0 -7.62 0)
					(length 5.08)
					(name "RSVDW5_VSS"
						(effects
							(font
								(size 1.27 1.27)
							)
						)
					)
					(number "W5"
						(effects
							(font
								(size 1.27 1.27)
							)
						)
					)
					(alternate "RSVD" passive line)
					(alternate "VSS" power_in line)
				)
				(pin passive line
					(at 0 -12.7 0)
					(length 5.08)
					(name "RSVDN9_VSS"
						(effects
							(font
								(size 1.27 1.27)
							)
						)
					)
					(number "N9"
						(effects
							(font
								(size 1.27 1.27)
							)
						)
					)
					(alternate "RSVD" passive line)
					(alternate "VSS" power_in line)
				)
				(pin passive line
					(at 0 -15.24 0)
					(length 5.08)
					(name "RSVDW1_VSS"
						(effects
							(font
								(size 1.27 1.27)
							)
						)
					)
					(number "W1"
						(effects
							(font
								(size 1.27 1.27)
							)
						)
					)
					(alternate "RSVD" passive line)
					(alternate "VSS" power_in line)
				)
				(pin passive line
					(at 0 -17.78 0)
					(length 5.08)
					(name "RSVDP22_VSS"
						(effects
							(font
								(size 1.27 1.27)
							)
						)
					)
					(number "P22"
						(effects
							(font
								(size 1.27 1.27)
							)
						)
					)
					(alternate "RSVD" passive line)
					(alternate "VSS" power_in line)
				)
				(pin passive line
					(at 0 -20.32 0)
					(length 5.08)
					(name "RSVDY18_VSS"
						(effects
							(font
								(size 1.27 1.27)
							)
						)
					)
					(number "Y18"
						(effects
							(font
								(size 1.27 1.27)
							)
						)
					)
					(alternate "RSVD" passive line)
					(alternate "VSS" power_in line)
				)
				(pin passive line
					(at 0 -24.13 0)
					(length 5.08)
					(name "RSVDP8_VSS"
						(effects
							(font
								(size 1.27 1.27)
							)
						)
					)
					(number "P8"
						(effects
							(font
								(size 1.27 1.27)
							)
						)
					)
					(alternate "RSVD" passive line)
					(alternate "VSS" power_in line)
				)
				(pin passive line
					(at 0 -31.75 0)
					(length 5.08)
					(name "RSVDR9_NC"
						(effects
							(font
								(size 1.27 1.27)
							)
						)
					)
					(number "R9"
						(effects
							(font
								(size 1.27 1.27)
							)
						)
					)
				)
				(pin passive line
					(at 0 -34.29 0)
					(length 5.08)
					(name "RSVDU9_NC"
						(effects
							(font
								(size 1.27 1.27)
							)
						)
					)
					(number "U9"
						(effects
							(font
								(size 1.27 1.27)
							)
						)
					)
				)
				(pin passive line
					(at 0 -36.83 0)
					(length 5.08)
					(name "RSVDK24_NC"
						(effects
							(font
								(size 1.27 1.27)
							)
						)
					)
					(number "K24"
						(effects
							(font
								(size 1.27 1.27)
							)
						)
					)
				)
				(pin passive line
					(at 0 -39.37 0)
					(length 5.08)
					(name "RSVDL25_NC"
						(effects
							(font
								(size 1.27 1.27)
							)
						)
					)
					(number "L25"
						(effects
							(font
								(size 1.27 1.27)
							)
						)
					)
				)
				(pin passive line
					(at 43.18 0 180)
					(length 5.08)
					(name "DEBUG_Y16"
						(effects
							(font
								(size 1.27 1.27)
							)
						)
					)
					(number "Y16"
						(effects
							(font
								(size 1.27 1.27)
							)
						)
					)
				)
				(pin passive line
					(at 43.18 -2.54 180)
					(length 5.08)
					(name "DEBUG_W7"
						(effects
							(font
								(size 1.27 1.27)
							)
						)
					)
					(number "W7"
						(effects
							(font
								(size 1.27 1.27)
							)
						)
					)
				)
				(pin passive line
					(at 43.18 -5.08 180)
					(length 5.08)
					(name "DEBUG_Y20"
						(effects
							(font
								(size 1.27 1.27)
							)
						)
					)
					(number "Y20"
						(effects
							(font
								(size 1.27 1.27)
							)
						)
					)
				)
				(pin passive line
					(at 43.18 -10.16 180)
					(length 5.08)
					(name "RSVDW25_NC"
						(effects
							(font
								(size 1.27 1.27)
							)
						)
					)
					(number "W25"
						(effects
							(font
								(size 1.27 1.27)
							)
						)
					)
				)
				(pin passive line
					(at 43.18 -12.7 180)
					(length 5.08)
					(name "RSVDW27_NC"
						(effects
							(font
								(size 1.27 1.27)
							)
						)
					)
					(number "W27"
						(effects
							(font
								(size 1.27 1.27)
							)
						)
					)
				)
				(pin passive line
					(at 43.18 -15.24 180)
					(length 5.08)
					(name "RSVDV22_NC"
						(effects
							(font
								(size 1.27 1.27)
							)
						)
					)
					(number "V22"
						(effects
							(font
								(size 1.27 1.27)
							)
						)
					)
				)
				(pin passive line
					(at 43.18 -17.78 180)
					(length 5.08)
					(name "RSVDV24_NC"
						(effects
							(font
								(size 1.27 1.27)
							)
						)
					)
					(number "V24"
						(effects
							(font
								(size 1.27 1.27)
							)
						)
					)
				)
				(pin passive line
					(at 43.18 -20.32 180)
					(length 5.08)
					(name "RSVDV26_NC"
						(effects
							(font
								(size 1.27 1.27)
							)
						)
					)
					(number "V26"
						(effects
							(font
								(size 1.27 1.27)
							)
						)
					)
				)
				(pin passive line
					(at 43.18 -22.86 180)
					(length 5.08)
					(name "RSVDV28_NC"
						(effects
							(font
								(size 1.27 1.27)
							)
						)
					)
					(number "V28"
						(effects
							(font
								(size 1.27 1.27)
							)
						)
					)
				)
				(pin passive line
					(at 43.18 -25.4 180)
					(length 5.08)
					(name "RSVDU23_NC"
						(effects
							(font
								(size 1.27 1.27)
							)
						)
					)
					(number "U23"
						(effects
							(font
								(size 1.27 1.27)
							)
						)
					)
				)
				(pin passive line
					(at 43.18 -27.94 180)
					(length 5.08)
					(name "RSVDU25_NC"
						(effects
							(font
								(size 1.27 1.27)
							)
						)
					)
					(number "U25"
						(effects
							(font
								(size 1.27 1.27)
							)
						)
					)
				)
				(pin passive line
					(at 43.18 -30.48 180)
					(length 5.08)
					(name "RSVDU27_NC"
						(effects
							(font
								(size 1.27 1.27)
							)
						)
					)
					(number "U27"
						(effects
							(font
								(size 1.27 1.27)
							)
						)
					)
				)
				(pin passive line
					(at 43.18 -33.02 180)
					(length 5.08)
					(name "RSVDU29_NC"
						(effects
							(font
								(size 1.27 1.27)
							)
						)
					)
					(number "U29"
						(effects
							(font
								(size 1.27 1.27)
							)
						)
					)
				)
				(pin passive line
					(at 43.18 -35.56 180)
					(length 5.08)
					(name "RSVDT22_NC"
						(effects
							(font
								(size 1.27 1.27)
							)
						)
					)
					(number "T22"
						(effects
							(font
								(size 1.27 1.27)
							)
						)
					)
				)
				(pin passive line
					(at 43.18 -38.1 180)
					(length 5.08)
					(name "RSVDT24_NC"
						(effects
							(font
								(size 1.27 1.27)
							)
						)
					)
					(number "T24"
						(effects
							(font
								(size 1.27 1.27)
							)
						)
					)
				)
				(pin passive line
					(at 43.18 -40.64 180)
					(length 5.08)
					(name "RSVDT26_NC"
						(effects
							(font
								(size 1.27 1.27)
							)
						)
					)
					(number "T26"
						(effects
							(font
								(size 1.27 1.27)
							)
						)
					)
				)
				(pin passive line
					(at 43.18 -43.18 180)
					(length 5.08)
					(name "RSVDT28_NC"
						(effects
							(font
								(size 1.27 1.27)
							)
						)
					)
					(number "T28"
						(effects
							(font
								(size 1.27 1.27)
							)
						)
					)
				)
				(pin passive line
					(at 43.18 -45.72 180)
					(length 5.08)
					(name "RSVDR23_NC"
						(effects
							(font
								(size 1.27 1.27)
							)
						)
					)
					(number "R23"
						(effects
							(font
								(size 1.27 1.27)
							)
						)
					)
				)
				(pin passive line
					(at 43.18 -48.26 180)
					(length 5.08)
					(name "RSVDR25_NC"
						(effects
							(font
								(size 1.27 1.27)
							)
						)
					)
					(number "R25"
						(effects
							(font
								(size 1.27 1.27)
							)
						)
					)
				)
				(pin passive line
					(at 43.18 -50.8 180)
					(length 5.08)
					(name "RSVDR27_NC"
						(effects
							(font
								(size 1.27 1.27)
							)
						)
					)
					(number "R27"
						(effects
							(font
								(size 1.27 1.27)
							)
						)
					)
				)
				(pin passive line
					(at 43.18 -53.34 180)
					(length 5.08)
					(name "RSVDP24_NC"
						(effects
							(font
								(size 1.27 1.27)
							)
						)
					)
					(number "P24"
						(effects
							(font
								(size 1.27 1.27)
							)
						)
					)
				)
				(pin passive line
					(at 43.18 -55.88 180)
					(length 5.08)
					(name "RSVDP26_NC"
						(effects
							(font
								(size 1.27 1.27)
							)
						)
					)
					(number "P26"
						(effects
							(font
								(size 1.27 1.27)
							)
						)
					)
				)
				(pin passive line
					(at 43.18 -58.42 180)
					(length 5.08)
					(name "RSVDP28_NC"
						(effects
							(font
								(size 1.27 1.27)
							)
						)
					)
					(number "P28"
						(effects
							(font
								(size 1.27 1.27)
							)
						)
					)
				)
				(pin passive line
					(at 43.18 -60.96 180)
					(length 5.08)
					(name "RSVDN23_NC"
						(effects
							(font
								(size 1.27 1.27)
							)
						)
					)
					(number "N23"
						(effects
							(font
								(size 1.27 1.27)
							)
						)
					)
				)
				(pin passive line
					(at 43.18 -63.5 180)
					(length 5.08)
					(name "RSVDN25_NC"
						(effects
							(font
								(size 1.27 1.27)
							)
						)
					)
					(number "N25"
						(effects
							(font
								(size 1.27 1.27)
							)
						)
					)
				)
				(pin passive line
					(at 43.18 -66.04 180)
					(length 5.08)
					(name "RSVDN27_NC"
						(effects
							(font
								(size 1.27 1.27)
							)
						)
					)
					(number "N27"
						(effects
							(font
								(size 1.27 1.27)
							)
						)
					)
				)
				(pin passive line
					(at 43.18 -68.58 180)
					(length 5.08)
					(name "RSVDM22_NC"
						(effects
							(font
								(size 1.27 1.27)
							)
						)
					)
					(number "M22"
						(effects
							(font
								(size 1.27 1.27)
							)
						)
					)
				)
				(pin passive line
					(at 43.18 -71.12 180)
					(length 5.08)
					(name "RSVDM24_NC"
						(effects
							(font
								(size 1.27 1.27)
							)
						)
					)
					(number "M24"
						(effects
							(font
								(size 1.27 1.27)
							)
						)
					)
				)
				(pin passive line
					(at 43.18 -73.66 180)
					(length 5.08)
					(name "RSVDM26_NC"
						(effects
							(font
								(size 1.27 1.27)
							)
						)
					)
					(number "M26"
						(effects
							(font
								(size 1.27 1.27)
							)
						)
					)
				)
				(pin passive line
					(at 43.18 -76.2 180)
					(length 5.08)
					(name "RSVDM28_NC"
						(effects
							(font
								(size 1.27 1.27)
							)
						)
					)
					(number "M28"
						(effects
							(font
								(size 1.27 1.27)
							)
						)
					)
				)
				(pin passive line
					(at 43.18 -78.74 180)
					(length 5.08)
					(name "RSVDL23_NC"
						(effects
							(font
								(size 1.27 1.27)
							)
						)
					)
					(number "L23"
						(effects
							(font
								(size 1.27 1.27)
							)
						)
					)
				)
				(pin passive line
					(at 43.18 -81.28 180)
					(length 5.08)
					(name "RSVDL27_NC"
						(effects
							(font
								(size 1.27 1.27)
							)
						)
					)
					(number "L27"
						(effects
							(font
								(size 1.27 1.27)
							)
						)
					)
				)
				(pin passive line
					(at 43.18 -83.82 180)
					(length 5.08)
					(name "RSVDK22_NC"
						(effects
							(font
								(size 1.27 1.27)
							)
						)
					)
					(number "K22"
						(effects
							(font
								(size 1.27 1.27)
							)
						)
					)
				)
				(pin passive line
					(at 43.18 -86.36 180)
					(length 5.08)
					(name "RSVDJ23_NC"
						(effects
							(font
								(size 1.27 1.27)
							)
						)
					)
					(number "J23"
						(effects
							(font
								(size 1.27 1.27)
							)
						)
					)
				)
				(pin passive line
					(at 43.18 -88.9 180)
					(length 5.08)
					(name "RSVDJ25_NC"
						(effects
							(font
								(size 1.27 1.27)
							)
						)
					)
					(number "J25"
						(effects
							(font
								(size 1.27 1.27)
							)
						)
					)
				)
				(pin passive line
					(at 43.18 -91.44 180)
					(length 5.08)
					(name "RSVDW23_NC"
						(effects
							(font
								(size 1.27 1.27)
							)
						)
					)
					(number "W23"
						(effects
							(font
								(size 1.27 1.27)
							)
						)
					)
				)
			)
			(symbol "EZX710AT2_S_LMR5_6_1"
				(rectangle
					(start 5.08 2.54)
					(end 50.8 -88.9)
					(stroke
						(width 0.254)
						(type default)
					)
					(fill
						(type background)
					)
				)
				(polyline
					(pts
						(xy 20.32 -26.924) (xy 20.32 -34.544)
					)
					(stroke
						(width 0.254)
						(type solid)
					)
					(fill
						(type background)
					)
				)
				(polyline
					(pts
						(xy 20.32 -54.61) (xy 20.32 -59.69)
					)
					(stroke
						(width 0.254)
						(type solid)
					)
					(fill
						(type background)
					)
				)
				(polyline
					(pts
						(xy 20.32 -62.23) (xy 20.32 -77.47)
					)
					(stroke
						(width 0.254)
						(type solid)
					)
					(fill
						(type background)
					)
				)
				(polyline
					(pts
						(xy 22.86 1.27) (xy 22.86 -8.89)
					)
					(stroke
						(width 0.254)
						(type solid)
					)
					(fill
						(type background)
					)
				)
				(polyline
					(pts
						(xy 22.86 -11.43) (xy 22.86 -16.51)
					)
					(stroke
						(width 0.254)
						(type solid)
					)
					(fill
						(type background)
					)
				)
				(polyline
					(pts
						(xy 33.02 -6.35) (xy 33.02 -41.91)
					)
					(stroke
						(width 0.254)
						(type solid)
					)
					(fill
						(type background)
					)
				)
				(text "MDIO"
					(at 22.86 -33.02 900)
					(effects
						(font
							(size 1.27 1.27)
							(thickness 0.15)
						)
						(justify left bottom)
					)
				)
				(text "RST"
					(at 22.86 -58.928 900)
					(effects
						(font
							(size 1.27 1.27)
							(thickness 0.15)
						)
						(justify left bottom)
					)
				)
				(text "JTAG"
					(at 22.86 -72.39 900)
					(effects
						(font
							(size 1.27 1.27)
							(thickness 0.15)
						)
						(justify left bottom)
					)
				)
				(text "XTAL IN"
					(at 25.4 -7.366 900)
					(effects
						(font
							(size 1.27 1.27)
							(thickness 0.15)
						)
						(justify left bottom)
					)
				)
				(text "XTAL PTP"
					(at 25.4 -18.288 900)
					(effects
						(font
							(size 1.27 1.27)
							(thickness 0.15)
						)
						(justify left bottom)
					)
				)
				(text "SYNCE / IEEE1588"
					(at 31.75 -34.29 900)
					(effects
						(font
							(size 1.27 1.27)
							(thickness 0.15)
						)
						(justify left bottom)
					)
				)
				(pin input line
					(at 0 0 0)
					(length 5.08)
					(name "XTAL_P"
						(effects
							(font
								(size 1.27 1.27)
							)
						)
					)
					(number "D42"
						(effects
							(font
								(size 1.27 1.27)
							)
						)
					)
				)
				(pin input line
					(at 0 -2.54 0)
					(length 5.08)
					(name "XTAL_N"
						(effects
							(font
								(size 1.27 1.27)
							)
						)
					)
					(number "E41"
						(effects
							(font
								(size 1.27 1.27)
							)
						)
					)
				)
				(pin passive line
					(at 0 -5.08 0)
					(length 5.08)
					(name "XTAL_BYPASS"
						(effects
							(font
								(size 1.27 1.27)
							)
						)
					)
					(number "D10"
						(effects
							(font
								(size 1.27 1.27)
							)
						)
					)
				)
				(pin input line
					(at 0 -7.62 0)
					(length 5.08)
					(name "REFCLK_SEL"
						(effects
							(font
								(size 1.27 1.27)
							)
						)
					)
					(number "D4"
						(effects
							(font
								(size 1.27 1.27)
							)
						)
					)
				)
				(pin passive line
					(at 0 -12.7 0)
					(length 5.08)
					(name "XTAL_PTP_XTAL_P"
						(effects
							(font
								(size 1.27 1.27)
							)
						)
					)
					(number "J41"
						(effects
							(font
								(size 1.27 1.27)
							)
						)
					)
				)
				(pin passive line
					(at 0 -15.24 0)
					(length 5.08)
					(name "XTAL_PTP_XTAL_N"
						(effects
							(font
								(size 1.27 1.27)
							)
						)
					)
					(number "H42"
						(effects
							(font
								(size 1.27 1.27)
							)
						)
					)
				)
				(pin passive line
					(at 0 -20.32 0)
					(length 5.08)
					(name "RSVDK30_NC"
						(effects
							(font
								(size 1.27 1.27)
							)
						)
					)
					(number "K30"
						(effects
							(font
								(size 1.27 1.27)
							)
						)
					)
				)
				(pin passive line
					(at 0 -22.86 0)
					(length 5.08)
					(name "RSVDK32_NC"
						(effects
							(font
								(size 1.27 1.27)
							)
						)
					)
					(number "K32"
						(effects
							(font
								(size 1.27 1.27)
							)
						)
					)
				)
				(pin input line
					(at 0 -27.94 0)
					(length 5.08)
					(name "MDC"
						(effects
							(font
								(size 1.27 1.27)
							)
						)
					)
					(number "L41"
						(effects
							(font
								(size 1.27 1.27)
							)
						)
					)
				)
				(pin bidirectional line
					(at 0 -30.48 0)
					(length 5.08)
					(name "MDIO"
						(effects
							(font
								(size 1.27 1.27)
							)
						)
					)
					(number "M42"
						(effects
							(font
								(size 1.27 1.27)
							)
						)
					)
				)
				(pin passive line
					(at 0 -33.02 0)
					(length 5.08)
					(name "RSVDL33"
						(effects
							(font
								(size 1.27 1.27)
							)
						)
					)
					(number "L33"
						(effects
							(font
								(size 1.27 1.27)
							)
						)
					)
				)
				(pin passive line
					(at 0 -38.1 0)
					(length 5.08)
					(name "RSVDR33_NC"
						(effects
							(font
								(size 1.27 1.27)
							)
						)
					)
					(number "R33"
						(effects
							(font
								(size 1.27 1.27)
							)
						)
					)
				)
				(pin passive line
					(at 0 -40.64 0)
					(length 5.08)
					(name "RSVDM34_NC"
						(effects
							(font
								(size 1.27 1.27)
							)
						)
					)
					(number "M34"
						(effects
							(font
								(size 1.27 1.27)
							)
						)
					)
				)
				(pin passive line
					(at 0 -43.18 0)
					(length 5.08)
					(name "RSVDP34_NC"
						(effects
							(font
								(size 1.27 1.27)
							)
						)
					)
					(number "P34"
						(effects
							(font
								(size 1.27 1.27)
							)
						)
					)
				)
				(pin passive line
					(at 0 -45.72 0)
					(length 5.08)
					(name "RSVDN33_NC"
						(effects
							(font
								(size 1.27 1.27)
							)
						)
					)
					(number "N33"
						(effects
							(font
								(size 1.27 1.27)
							)
						)
					)
				)
				(pin passive line
					(at 0 -48.26 0)
					(length 5.08)
					(name "RSVDJ17_VSS"
						(effects
							(font
								(size 1.27 1.27)
							)
						)
					)
					(number "J17"
						(effects
							(font
								(size 1.27 1.27)
							)
						)
					)
					(alternate "RSVD" passive line)
					(alternate "VSS" power_in line)
				)
				(pin passive line
					(at 0 -50.8 0)
					(length 5.08)
					(name "RSVD_J11_VSS"
						(effects
							(font
								(size 1.27 1.27)
							)
						)
					)
					(number "J11"
						(effects
							(font
								(size 1.27 1.27)
							)
						)
					)
					(alternate "RSVD" passive line)
					(alternate "VSS" power_in line)
				)
				(pin input line
					(at 0 -55.88 0)
					(length 5.08)
					(name "~{RESET}"
						(effects
							(font
								(size 1.27 1.27)
							)
						)
					)
					(number "D12"
						(effects
							(font
								(size 1.27 1.27)
							)
						)
					)
				)
				(pin passive line
					(at 0 -58.42 0)
					(length 5.08)
					(name "RSVDJ13_VSS"
						(effects
							(font
								(size 1.27 1.27)
							)
						)
					)
					(number "J13"
						(effects
							(font
								(size 1.27 1.27)
							)
						)
					)
					(alternate "RSVD" passive line)
					(alternate "VSS" power_in line)
				)
				(pin input line
					(at 0 -63.5 0)
					(length 5.08)
					(name "~{PHY_TRST}"
						(effects
							(font
								(size 1.27 1.27)
							)
						)
					)
					(number "D18"
						(effects
							(font
								(size 1.27 1.27)
							)
						)
					)
				)
				(pin input line
					(at 0 -66.04 0)
					(length 5.08)
					(name "PHY_TCK"
						(effects
							(font
								(size 1.27 1.27)
							)
						)
					)
					(number "E17"
						(effects
							(font
								(size 1.27 1.27)
							)
						)
					)
				)
				(pin input line
					(at 0 -68.58 0)
					(length 5.08)
					(name "PHY_TMS"
						(effects
							(font
								(size 1.27 1.27)
							)
						)
					)
					(number "D16"
						(effects
							(font
								(size 1.27 1.27)
							)
						)
					)
				)
				(pin input line
					(at 0 -71.12 0)
					(length 5.08)
					(name "PHY_TDI"
						(effects
							(font
								(size 1.27 1.27)
							)
						)
					)
					(number "E15"
						(effects
							(font
								(size 1.27 1.27)
							)
						)
					)
				)
				(pin open_collector line
					(at 0 -73.66 0)
					(length 5.08)
					(name "PHY_TDO"
						(effects
							(font
								(size 1.27 1.27)
							)
						)
					)
					(number "F16"
						(effects
							(font
								(size 1.27 1.27)
							)
						)
					)
				)
				(pin input line
					(at 0 -76.2 0)
					(length 5.08)
					(name "RSVDD14"
						(effects
							(font
								(size 1.27 1.27)
							)
						)
					)
					(number "D14"
						(effects
							(font
								(size 1.27 1.27)
							)
						)
					)
				)
				(pin passive line
					(at 55.88 0 180)
					(length 5.08)
					(name "P0_INT_MLC"
						(effects
							(font
								(size 1.27 1.27)
							)
						)
					)
					(number "M40"
						(effects
							(font
								(size 1.27 1.27)
							)
						)
					)
				)
				(pin passive line
					(at 55.88 -2.54 180)
					(length 5.08)
					(name "P1_INT_MLC"
						(effects
							(font
								(size 1.27 1.27)
							)
						)
					)
					(number "F14"
						(effects
							(font
								(size 1.27 1.27)
							)
						)
					)
				)
				(pin passive line
					(at 55.88 -7.62 180)
					(length 5.08)
					(name "P0_PTP_SYNC0"
						(effects
							(font
								(size 1.27 1.27)
							)
						)
					)
					(number "N39"
						(effects
							(font
								(size 1.27 1.27)
							)
						)
					)
				)
				(pin passive line
					(at 55.88 -10.16 180)
					(length 5.08)
					(name "P0_PTP_SYNC1"
						(effects
							(font
								(size 1.27 1.27)
							)
						)
					)
					(number "N41"
						(effects
							(font
								(size 1.27 1.27)
							)
						)
					)
				)
				(pin passive line
					(at 55.88 -12.7 180)
					(length 5.08)
					(name "P1_PTP_SYNC0"
						(effects
							(font
								(size 1.27 1.27)
							)
						)
					)
					(number "H10"
						(effects
							(font
								(size 1.27 1.27)
							)
						)
					)
				)
				(pin passive line
					(at 55.88 -15.24 180)
					(length 5.08)
					(name "P1_PTP_SYNC1"
						(effects
							(font
								(size 1.27 1.27)
							)
						)
					)
					(number "H12"
						(effects
							(font
								(size 1.27 1.27)
							)
						)
					)
				)
				(pin output line
					(at 55.88 -20.32 180)
					(length 5.08)
					(name "SYNCE_CLKOUT_0"
						(effects
							(font
								(size 1.27 1.27)
							)
						)
					)
					(number "G9"
						(effects
							(font
								(size 1.27 1.27)
							)
						)
					)
				)
				(pin output line
					(at 55.88 -22.86 180)
					(length 5.08)
					(name "SYNCE_CLKOUT_1"
						(effects
							(font
								(size 1.27 1.27)
							)
						)
					)
					(number "F10"
						(effects
							(font
								(size 1.27 1.27)
							)
						)
					)
				)
				(pin output line
					(at 55.88 -25.4 180)
					(length 5.08)
					(name "SYNCE_CLKOUT_2"
						(effects
							(font
								(size 1.27 1.27)
							)
						)
					)
					(number "G11"
						(effects
							(font
								(size 1.27 1.27)
							)
						)
					)
				)
				(pin output line
					(at 55.88 -27.94 180)
					(length 5.08)
					(name "SYNCE_CLKOUT_3"
						(effects
							(font
								(size 1.27 1.27)
							)
						)
					)
					(number "E13"
						(effects
							(font
								(size 1.27 1.27)
							)
						)
					)
				)
				(pin output line
					(at 55.88 -33.02 180)
					(length 5.08)
					(name "SYNCE_LOCK_0"
						(effects
							(font
								(size 1.27 1.27)
							)
						)
					)
					(number "F8"
						(effects
							(font
								(size 1.27 1.27)
							)
						)
					)
				)
				(pin output line
					(at 55.88 -35.56 180)
					(length 5.08)
					(name "SYNCE_LOCK_1"
						(effects
							(font
								(size 1.27 1.27)
							)
						)
					)
					(number "E9"
						(effects
							(font
								(size 1.27 1.27)
							)
						)
					)
				)
				(pin output line
					(at 55.88 -38.1 180)
					(length 5.08)
					(name "SYNCE_LOCK_2"
						(effects
							(font
								(size 1.27 1.27)
							)
						)
					)
					(number "E11"
						(effects
							(font
								(size 1.27 1.27)
							)
						)
					)
				)
				(pin output line
					(at 55.88 -40.64 180)
					(length 5.08)
					(name "SYNCE_LOCK_3"
						(effects
							(font
								(size 1.27 1.27)
							)
						)
					)
					(number "F12"
						(effects
							(font
								(size 1.27 1.27)
							)
						)
					)
				)
				(pin passive line
					(at 55.88 -45.72 180)
					(length 5.08)
					(name "RSVDH40_VSS"
						(effects
							(font
								(size 1.27 1.27)
							)
						)
					)
					(number "H40"
						(effects
							(font
								(size 1.27 1.27)
							)
						)
					)
					(alternate "RSVD" passive line)
					(alternate "VSS" power_in line)
				)
				(pin passive line
					(at 55.88 -48.26 180)
					(length 5.08)
					(name "RSVDK40_1P88V"
						(effects
							(font
								(size 1.27 1.27)
							)
						)
					)
					(number "K40"
						(effects
							(font
								(size 1.27 1.27)
							)
						)
					)
					(alternate "1V88" power_in line)
					(alternate "RSVD" passive line)
				)
				(pin passive line
					(at 55.88 -50.8 180)
					(length 5.08)
					(name "RSVDK42_VSS"
						(effects
							(font
								(size 1.27 1.27)
							)
						)
					)
					(number "K42"
						(effects
							(font
								(size 1.27 1.27)
							)
						)
					)
					(alternate "RSVD" passive line)
					(alternate "VSS" power_in line)
				)
				(pin passive line
					(at 55.88 -53.34 180)
					(length 5.08)
					(name "RSVDP38_VSS"
						(effects
							(font
								(size 1.27 1.27)
							)
						)
					)
					(number "P38"
						(effects
							(font
								(size 1.27 1.27)
							)
						)
					)
					(alternate "RSVD" passive line)
					(alternate "VSS" power_in line)
				)
				(pin passive line
					(at 55.88 -55.88 180)
					(length 5.08)
					(name "RSVDN37_VSS"
						(effects
							(font
								(size 1.27 1.27)
							)
						)
					)
					(number "N37"
						(effects
							(font
								(size 1.27 1.27)
							)
						)
					)
					(alternate "RSVD" passive line)
					(alternate "VSS" power_in line)
				)
				(pin passive line
					(at 55.88 -58.42 180)
					(length 5.08)
					(name "RSVDL37_VSS"
						(effects
							(font
								(size 1.27 1.27)
							)
						)
					)
					(number "L37"
						(effects
							(font
								(size 1.27 1.27)
							)
						)
					)
					(alternate "RSVD" passive line)
					(alternate "VSS" power_in line)
				)
				(pin passive line
					(at 55.88 -63.5 180)
					(length 5.08)
					(name "RSVDL35_NC"
						(effects
							(font
								(size 1.27 1.27)
							)
						)
					)
					(number "L35"
						(effects
							(font
								(size 1.27 1.27)
							)
						)
					)
				)
				(pin passive line
					(at 55.88 -66.04 180)
					(length 5.08)
					(name "RSVDM36_NC"
						(effects
							(font
								(size 1.27 1.27)
							)
						)
					)
					(number "M36"
						(effects
							(font
								(size 1.27 1.27)
							)
						)
					)
				)
				(pin passive line
					(at 55.88 -68.58 180)
					(length 5.08)
					(name "RSVDN35_NC"
						(effects
							(font
								(size 1.27 1.27)
							)
						)
					)
					(number "N35"
						(effects
							(font
								(size 1.27 1.27)
							)
						)
					)
				)
				(pin passive line
					(at 55.88 -71.12 180)
					(length 5.08)
					(name "RSVDP36_NC"
						(effects
							(font
								(size 1.27 1.27)
							)
						)
					)
					(number "P36"
						(effects
							(font
								(size 1.27 1.27)
							)
						)
					)
				)
				(pin passive line
					(at 55.88 -73.66 180)
					(length 5.08)
					(name "RSVDR37_NC"
						(effects
							(font
								(size 1.27 1.27)
							)
						)
					)
					(number "R37"
						(effects
							(font
								(size 1.27 1.27)
							)
						)
					)
				)
				(pin passive line
					(at 55.88 -76.2 180)
					(length 5.08)
					(name "RSVDH16_NC"
						(effects
							(font
								(size 1.27 1.27)
							)
						)
					)
					(number "H16"
						(effects
							(font
								(size 1.27 1.27)
							)
						)
					)
				)
				(pin passive line
					(at 55.88 -78.74 180)
					(length 5.08)
					(name "RSVDG15_NC"
						(effects
							(font
								(size 1.27 1.27)
							)
						)
					)
					(number "G15"
						(effects
							(font
								(size 1.27 1.27)
							)
						)
					)
				)
				(pin passive line
					(at 55.88 -81.28 180)
					(length 5.08)
					(name "RSVDJ15_NC"
						(effects
							(font
								(size 1.27 1.27)
							)
						)
					)
					(number "J15"
						(effects
							(font
								(size 1.27 1.27)
							)
						)
					)
				)
				(pin passive line
					(at 55.88 -83.82 180)
					(length 5.08)
					(name "RSVDH14_NC"
						(effects
							(font
								(size 1.27 1.27)
							)
						)
					)
					(number "H14"
						(effects
							(font
								(size 1.27 1.27)
							)
						)
					)
				)
				(pin passive line
					(at 55.88 -86.36 180)
					(length 5.08)
					(name "RSVDG13_NC"
						(effects
							(font
								(size 1.27 1.27)
							)
						)
					)
					(number "G13"
						(effects
							(font
								(size 1.27 1.27)
							)
						)
					)
				)
			)
			(symbol "EZX710AT2_S_LMR5_7_1"
				(rectangle
					(start 5.08 2.54)
					(end 38.1 -71.12)
					(stroke
						(width 0.254)
						(type default)
					)
					(fill
						(type background)
					)
				)
				(pin passive line
					(at 0 0 0)
					(length 5.08)
					(name "RSVDE19_1P88V"
						(effects
							(font
								(size 1.27 1.27)
							)
						)
					)
					(number "E19"
						(effects
							(font
								(size 1.27 1.27)
							)
						)
					)
					(alternate "1V88" power_in line)
					(alternate "RSVD" passive line)
				)
				(pin passive line
					(at 0 -2.54 0)
					(length 5.08)
					(name "RSVDD8_1P88V"
						(effects
							(font
								(size 1.27 1.27)
							)
						)
					)
					(number "D8"
						(effects
							(font
								(size 1.27 1.27)
							)
						)
					)
					(alternate "1V88" power_in line)
					(alternate "RSVD" passive line)
				)
				(pin passive line
					(at 0 -5.08 0)
					(length 5.08)
					(name "RSVDJ19_VSS"
						(effects
							(font
								(size 1.27 1.27)
							)
						)
					)
					(number "J19"
						(effects
							(font
								(size 1.27 1.27)
							)
						)
					)
					(alternate "RSVD" passive line)
					(alternate "VSS" power_in line)
				)
				(pin passive line
					(at 0 -7.62 0)
					(length 5.08)
					(name "RSVDJ21_VSS"
						(effects
							(font
								(size 1.27 1.27)
							)
						)
					)
					(number "J21"
						(effects
							(font
								(size 1.27 1.27)
							)
						)
					)
					(alternate "RSVD" passive line)
					(alternate "VSS" power_in line)
				)
				(pin passive line
					(at 0 -10.16 0)
					(length 5.08)
					(name "RSVH18_VSS"
						(effects
							(font
								(size 1.27 1.27)
							)
						)
					)
					(number "H18"
						(effects
							(font
								(size 1.27 1.27)
							)
						)
					)
					(alternate "RSVD" passive line)
					(alternate "VSS" power_in line)
				)
				(pin passive line
					(at 0 -12.7 0)
					(length 5.08)
					(name "RSVDH22_VSS"
						(effects
							(font
								(size 1.27 1.27)
							)
						)
					)
					(number "H22"
						(effects
							(font
								(size 1.27 1.27)
							)
						)
					)
					(alternate "RSVD" passive line)
					(alternate "VSS" power_in line)
				)
				(pin passive line
					(at 0 -15.24 0)
					(length 5.08)
					(name "RSVDG19_VSS"
						(effects
							(font
								(size 1.27 1.27)
							)
						)
					)
					(number "G19"
						(effects
							(font
								(size 1.27 1.27)
							)
						)
					)
					(alternate "RSVD" passive line)
					(alternate "VSS" power_in line)
				)
				(pin passive line
					(at 0 -17.78 0)
					(length 5.08)
					(name "RSVDG21_VSS"
						(effects
							(font
								(size 1.27 1.27)
							)
						)
					)
					(number "G21"
						(effects
							(font
								(size 1.27 1.27)
							)
						)
					)
					(alternate "RSVD" passive line)
					(alternate "VSS" power_in line)
				)
				(pin passive line
					(at 0 -20.32 0)
					(length 5.08)
					(name "RSVDF18_VSS"
						(effects
							(font
								(size 1.27 1.27)
							)
						)
					)
					(number "F18"
						(effects
							(font
								(size 1.27 1.27)
							)
						)
					)
					(alternate "RSVD" passive line)
					(alternate "VSS" power_in line)
				)
				(pin passive line
					(at 0 -22.86 0)
					(length 5.08)
					(name "RSVDF20_VSS"
						(effects
							(font
								(size 1.27 1.27)
							)
						)
					)
					(number "F20"
						(effects
							(font
								(size 1.27 1.27)
							)
						)
					)
					(alternate "RSVD" passive line)
					(alternate "VSS" power_in line)
				)
				(pin passive line
					(at 0 -25.4 0)
					(length 5.08)
					(name "RSVDF22_VSS"
						(effects
							(font
								(size 1.27 1.27)
							)
						)
					)
					(number "F22"
						(effects
							(font
								(size 1.27 1.27)
							)
						)
					)
					(alternate "RSVD" passive line)
					(alternate "VSS" power_in line)
				)
				(pin passive line
					(at 0 -27.94 0)
					(length 5.08)
					(name "RSVDE21_VSS"
						(effects
							(font
								(size 1.27 1.27)
							)
						)
					)
					(number "E21"
						(effects
							(font
								(size 1.27 1.27)
							)
						)
					)
					(alternate "RSVD" passive line)
					(alternate "VSS" power_in line)
				)
				(pin passive line
					(at 0 -30.48 0)
					(length 5.08)
					(name "RSVDE23_VSS"
						(effects
							(font
								(size 1.27 1.27)
							)
						)
					)
					(number "E23"
						(effects
							(font
								(size 1.27 1.27)
							)
						)
					)
					(alternate "RSVD" passive line)
					(alternate "VSS" power_in line)
				)
				(pin passive line
					(at 0 -33.02 0)
					(length 5.08)
					(name "RSVDE25_VSS"
						(effects
							(font
								(size 1.27 1.27)
							)
						)
					)
					(number "E25"
						(effects
							(font
								(size 1.27 1.27)
							)
						)
					)
					(alternate "RSVD" passive line)
					(alternate "VSS" power_in line)
				)
				(pin passive line
					(at 0 -35.56 0)
					(length 5.08)
					(name "RSVDD22_VSS"
						(effects
							(font
								(size 1.27 1.27)
							)
						)
					)
					(number "D22"
						(effects
							(font
								(size 1.27 1.27)
							)
						)
					)
					(alternate "RSVD" passive line)
					(alternate "VSS" power_in line)
				)
				(pin passive line
					(at 0 -38.1 0)
					(length 5.08)
					(name "RSVDG23_VSS"
						(effects
							(font
								(size 1.27 1.27)
							)
						)
					)
					(number "G23"
						(effects
							(font
								(size 1.27 1.27)
							)
						)
					)
					(alternate "RSVD" passive line)
					(alternate "VSS" power_in line)
				)
				(pin passive line
					(at 0 -40.64 0)
					(length 5.08)
					(name "RSVDH24_VSS"
						(effects
							(font
								(size 1.27 1.27)
							)
						)
					)
					(number "H24"
						(effects
							(font
								(size 1.27 1.27)
							)
						)
					)
					(alternate "RSVD" passive line)
					(alternate "VSS" power_in line)
				)
				(pin passive line
					(at 0 -45.72 0)
					(length 5.08)
					(name "RSVDK34_NC"
						(effects
							(font
								(size 1.27 1.27)
							)
						)
					)
					(number "K34"
						(effects
							(font
								(size 1.27 1.27)
							)
						)
					)
				)
				(pin passive line
					(at 0 -48.26 0)
					(length 5.08)
					(name "RSVDK36_NC"
						(effects
							(font
								(size 1.27 1.27)
							)
						)
					)
					(number "K36"
						(effects
							(font
								(size 1.27 1.27)
							)
						)
					)
				)
				(pin passive line
					(at 0 -50.8 0)
					(length 5.08)
					(name "RSVDK26_NC"
						(effects
							(font
								(size 1.27 1.27)
							)
						)
					)
					(number "K26"
						(effects
							(font
								(size 1.27 1.27)
							)
						)
					)
				)
				(pin passive line
					(at 0 -53.34 0)
					(length 5.08)
					(name "RSVDK28_NC"
						(effects
							(font
								(size 1.27 1.27)
							)
						)
					)
					(number "K28"
						(effects
							(font
								(size 1.27 1.27)
							)
						)
					)
				)
				(pin passive line
					(at 0 -58.42 0)
					(length 5.08)
					(name "RSVDD20_NC"
						(effects
							(font
								(size 1.27 1.27)
							)
						)
					)
					(number "D20"
						(effects
							(font
								(size 1.27 1.27)
							)
						)
					)
				)
				(pin passive line
					(at 0 -60.96 0)
					(length 5.08)
					(name "RSVDC21_NC"
						(effects
							(font
								(size 1.27 1.27)
							)
						)
					)
					(number "C21"
						(effects
							(font
								(size 1.27 1.27)
							)
						)
					)
				)
				(pin passive line
					(at 0 -66.04 0)
					(length 5.08)
					(name "RSVDB42_NC"
						(effects
							(font
								(size 1.27 1.27)
							)
						)
					)
					(number "B42"
						(effects
							(font
								(size 1.27 1.27)
							)
						)
					)
				)
				(pin passive line
					(at 0 -68.58 0)
					(length 5.08)
					(name "RSVDA41_NC"
						(effects
							(font
								(size 1.27 1.27)
							)
						)
					)
					(number "A41"
						(effects
							(font
								(size 1.27 1.27)
							)
						)
					)
				)
				(pin passive line
					(at 43.18 0 180)
					(length 5.08)
					(name "RSVDL29_NC"
						(effects
							(font
								(size 1.27 1.27)
							)
						)
					)
					(number "L29"
						(effects
							(font
								(size 1.27 1.27)
							)
						)
					)
				)
				(pin passive line
					(at 43.18 -2.54 180)
					(length 5.08)
					(name "RSVDM32_NC"
						(effects
							(font
								(size 1.27 1.27)
							)
						)
					)
					(number "M32"
						(effects
							(font
								(size 1.27 1.27)
							)
						)
					)
				)
				(pin passive line
					(at 43.18 -5.08 180)
					(length 5.08)
					(name "RSVDM30_NC"
						(effects
							(font
								(size 1.27 1.27)
							)
						)
					)
					(number "M30"
						(effects
							(font
								(size 1.27 1.27)
							)
						)
					)
				)
				(pin passive line
					(at 43.18 -7.62 180)
					(length 5.08)
					(name "RSVDN31_NC"
						(effects
							(font
								(size 1.27 1.27)
							)
						)
					)
					(number "N31"
						(effects
							(font
								(size 1.27 1.27)
							)
						)
					)
				)
				(pin passive line
					(at 43.18 -10.16 180)
					(length 5.08)
					(name "RSVDN29_NC"
						(effects
							(font
								(size 1.27 1.27)
							)
						)
					)
					(number "N29"
						(effects
							(font
								(size 1.27 1.27)
							)
						)
					)
				)
				(pin passive line
					(at 43.18 -12.7 180)
					(length 5.08)
					(name "RSVDP32_NC"
						(effects
							(font
								(size 1.27 1.27)
							)
						)
					)
					(number "P32"
						(effects
							(font
								(size 1.27 1.27)
							)
						)
					)
				)
				(pin passive line
					(at 43.18 -15.24 180)
					(length 5.08)
					(name "RSVDP30_NC"
						(effects
							(font
								(size 1.27 1.27)
							)
						)
					)
					(number "P30"
						(effects
							(font
								(size 1.27 1.27)
							)
						)
					)
				)
				(pin passive line
					(at 43.18 -17.78 180)
					(length 5.08)
					(name "RSVDR31_NC"
						(effects
							(font
								(size 1.27 1.27)
							)
						)
					)
					(number "R31"
						(effects
							(font
								(size 1.27 1.27)
							)
						)
					)
				)
				(pin passive line
					(at 43.18 -20.32 180)
					(length 5.08)
					(name "RSVDR29_NC"
						(effects
							(font
								(size 1.27 1.27)
							)
						)
					)
					(number "R29"
						(effects
							(font
								(size 1.27 1.27)
							)
						)
					)
				)
				(pin passive line
					(at 43.18 -22.86 180)
					(length 5.08)
					(name "RSVDT32_NC"
						(effects
							(font
								(size 1.27 1.27)
							)
						)
					)
					(number "T32"
						(effects
							(font
								(size 1.27 1.27)
							)
						)
					)
				)
				(pin passive line
					(at 43.18 -25.4 180)
					(length 5.08)
					(name "RSVDT30_NC"
						(effects
							(font
								(size 1.27 1.27)
							)
						)
					)
					(number "T30"
						(effects
							(font
								(size 1.27 1.27)
							)
						)
					)
				)
				(pin passive line
					(at 43.18 -27.94 180)
					(length 5.08)
					(name "RSVDU35_NC"
						(effects
							(font
								(size 1.27 1.27)
							)
						)
					)
					(number "U35"
						(effects
							(font
								(size 1.27 1.27)
							)
						)
					)
				)
				(pin passive line
					(at 43.18 -30.48 180)
					(length 5.08)
					(name "RSVDU33_NC"
						(effects
							(font
								(size 1.27 1.27)
							)
						)
					)
					(number "U33"
						(effects
							(font
								(size 1.27 1.27)
							)
						)
					)
				)
				(pin passive line
					(at 43.18 -33.02 180)
					(length 5.08)
					(name "RSVDU31_NC"
						(effects
							(font
								(size 1.27 1.27)
							)
						)
					)
					(number "U31"
						(effects
							(font
								(size 1.27 1.27)
							)
						)
					)
				)
				(pin passive line
					(at 43.18 -35.56 180)
					(length 5.08)
					(name "RSVDV34_NC"
						(effects
							(font
								(size 1.27 1.27)
							)
						)
					)
					(number "V34"
						(effects
							(font
								(size 1.27 1.27)
							)
						)
					)
				)
				(pin passive line
					(at 43.18 -38.1 180)
					(length 5.08)
					(name "RSVDV32_NC"
						(effects
							(font
								(size 1.27 1.27)
							)
						)
					)
					(number "V32"
						(effects
							(font
								(size 1.27 1.27)
							)
						)
					)
				)
				(pin passive line
					(at 43.18 -40.64 180)
					(length 5.08)
					(name "RSVDV30_NC"
						(effects
							(font
								(size 1.27 1.27)
							)
						)
					)
					(number "V30"
						(effects
							(font
								(size 1.27 1.27)
							)
						)
					)
				)
				(pin passive line
					(at 43.18 -45.72 180)
					(length 5.08)
					(name "RSVDL31_VSS"
						(effects
							(font
								(size 1.27 1.27)
							)
						)
					)
					(number "L31"
						(effects
							(font
								(size 1.27 1.27)
							)
						)
					)
					(alternate "RSVD" passive line)
					(alternate "VSS" power_in line)
				)
				(pin passive line
					(at 43.18 -50.8 180)
					(length 5.08)
					(name "RSVDD6_VSS"
						(effects
							(font
								(size 1.27 1.27)
							)
						)
					)
					(number "D6"
						(effects
							(font
								(size 1.27 1.27)
							)
						)
					)
					(alternate "RSVD" passive line)
					(alternate "VSS" power_in line)
				)
				(pin passive line
					(at 43.18 -53.34 180)
					(length 5.08)
					(name "RSVDF38_VSS"
						(effects
							(font
								(size 1.27 1.27)
							)
						)
					)
					(number "F38"
						(effects
							(font
								(size 1.27 1.27)
							)
						)
					)
					(alternate "RSVD" passive line)
					(alternate "VSS" power_in line)
				)
				(pin passive line
					(at 43.18 -55.88 180)
					(length 5.08)
					(name "RSVDD32_NC"
						(effects
							(font
								(size 1.27 1.27)
							)
						)
					)
					(number "D32"
						(effects
							(font
								(size 1.27 1.27)
							)
						)
					)
				)
				(pin passive line
					(at 43.18 -58.42 180)
					(length 5.08)
					(name "RSVDJ39_NC"
						(effects
							(font
								(size 1.27 1.27)
							)
						)
					)
					(number "J39"
						(effects
							(font
								(size 1.27 1.27)
							)
						)
					)
				)
			)
			(symbol "EZX710AT2_S_LMR5_8_1"
				(rectangle
					(start 5.08 2.54)
					(end 45.72 -55.88)
					(stroke
						(width 0.254)
						(type default)
					)
					(fill
						(type background)
					)
				)
				(polyline
					(pts
						(xy 31.75 -39.37) (xy 31.75 -54.61)
					)
					(stroke
						(width 0.254)
						(type solid)
					)
					(fill
						(type background)
					)
				)
				(text "Power supply"
					(at 19.05 -1.27 0)
					(effects
						(font
							(size 1.27 1.27)
							(thickness 0.15)
						)
						(justify left bottom)
					)
				)
				(text "GND"
					(at 30.48 -49.53 900)
					(effects
						(font
							(size 1.27 1.27)
							(thickness 0.15)
						)
						(justify left bottom)
					)
				)
				(pin power_in line
					(at 0 0 0)
					(length 5.08)
					(name "DVDD"
						(effects
							(font
								(size 1.27 1.27)
							)
						)
					)
					(number "G27"
						(effects
							(font
								(size 1.27 1.27)
							)
						)
					)
				)
				(pin passive line
					(at 0 0 0)
					(length 5.08)
					(hide yes)
					(name "DVDD"
						(effects
							(font
								(size 1.27 1.27)
							)
						)
					)
					(number "G29"
						(effects
							(font
								(size 1.27 1.27)
							)
						)
					)
				)
				(pin passive line
					(at 0 0 0)
					(length 5.08)
					(hide yes)
					(name "DVDD"
						(effects
							(font
								(size 1.27 1.27)
							)
						)
					)
					(number "G31"
						(effects
							(font
								(size 1.27 1.27)
							)
						)
					)
				)
				(pin passive line
					(at 0 0 0)
					(length 5.08)
					(hide yes)
					(name "DVDD"
						(effects
							(font
								(size 1.27 1.27)
							)
						)
					)
					(number "G33"
						(effects
							(font
								(size 1.27 1.27)
							)
						)
					)
				)
				(pin passive line
					(at 0 0 0)
					(length 5.08)
					(hide yes)
					(name "DVDD"
						(effects
							(font
								(size 1.27 1.27)
							)
						)
					)
					(number "G35"
						(effects
							(font
								(size 1.27 1.27)
							)
						)
					)
				)
				(pin power_in line
					(at 0 -5.08 0)
					(length 5.08)
					(name "VDDIO1"
						(effects
							(font
								(size 1.27 1.27)
							)
						)
					)
					(number "G25"
						(effects
							(font
								(size 1.27 1.27)
							)
						)
					)
				)
				(pin passive line
					(at 0 -5.08 0)
					(length 5.08)
					(hide yes)
					(name "VDDIO1"
						(effects
							(font
								(size 1.27 1.27)
							)
						)
					)
					(number "G37"
						(effects
							(font
								(size 1.27 1.27)
							)
						)
					)
				)
				(pin power_in line
					(at 0 -7.62 0)
					(length 5.08)
					(name "VDDIO2"
						(effects
							(font
								(size 1.27 1.27)
							)
						)
					)
					(number "L39"
						(effects
							(font
								(size 1.27 1.27)
							)
						)
					)
				)
				(pin power_in line
					(at 0 -10.16 0)
					(length 5.08)
					(name "VDDP2"
						(effects
							(font
								(size 1.27 1.27)
							)
						)
					)
					(number "M38"
						(effects
							(font
								(size 1.27 1.27)
							)
						)
					)
				)
				(pin power_in line
					(at 0 -15.24 0)
					(length 5.08)
					(name "XGB_AVDDH"
						(effects
							(font
								(size 1.27 1.27)
							)
						)
					)
					(number "D34"
						(effects
							(font
								(size 1.27 1.27)
							)
						)
					)
				)
				(pin power_in line
					(at 0 -20.32 0)
					(length 5.08)
					(name "BIAS_AVDDH"
						(effects
							(font
								(size 1.27 1.27)
							)
						)
					)
					(number "D30"
						(effects
							(font
								(size 1.27 1.27)
							)
						)
					)
				)
				(pin power_in line
					(at 0 -22.86 0)
					(length 5.08)
					(name "P0_AVDDH"
						(effects
							(font
								(size 1.27 1.27)
							)
						)
					)
					(number "E35"
						(effects
							(font
								(size 1.27 1.27)
							)
						)
					)
				)
				(pin passive line
					(at 0 -22.86 0)
					(length 5.08)
					(hide yes)
					(name "P0_AVDDH"
						(effects
							(font
								(size 1.27 1.27)
							)
						)
					)
					(number "E37"
						(effects
							(font
								(size 1.27 1.27)
							)
						)
					)
				)
				(pin power_in line
					(at 0 -25.4 0)
					(length 5.08)
					(name "P1_AVDDH"
						(effects
							(font
								(size 1.27 1.27)
							)
						)
					)
					(number "E27"
						(effects
							(font
								(size 1.27 1.27)
							)
						)
					)
				)
				(pin passive line
					(at 0 -25.4 0)
					(length 5.08)
					(hide yes)
					(name "P1_AVDDH"
						(effects
							(font
								(size 1.27 1.27)
							)
						)
					)
					(number "E29"
						(effects
							(font
								(size 1.27 1.27)
							)
						)
					)
				)
				(pin power_in line
					(at 0 -30.48 0)
					(length 5.08)
					(name "P0_AVDDL"
						(effects
							(font
								(size 1.27 1.27)
							)
						)
					)
					(number "C33"
						(effects
							(font
								(size 1.27 1.27)
							)
						)
					)
				)
				(pin passive line
					(at 0 -30.48 0)
					(length 5.08)
					(hide yes)
					(name "P0_AVDDL"
						(effects
							(font
								(size 1.27 1.27)
							)
						)
					)
					(number "C35"
						(effects
							(font
								(size 1.27 1.27)
							)
						)
					)
				)
				(pin passive line
					(at 0 -30.48 0)
					(length 5.08)
					(hide yes)
					(name "P0_AVDDL"
						(effects
							(font
								(size 1.27 1.27)
							)
						)
					)
					(number "C37"
						(effects
							(font
								(size 1.27 1.27)
							)
						)
					)
				)
				(pin passive line
					(at 0 -30.48 0)
					(length 5.08)
					(hide yes)
					(name "P0_AVDDL"
						(effects
							(font
								(size 1.27 1.27)
							)
						)
					)
					(number "C39"
						(effects
							(font
								(size 1.27 1.27)
							)
						)
					)
				)
				(pin power_in line
					(at 0 -35.56 0)
					(length 5.08)
					(name "P1_AVDDL"
						(effects
							(font
								(size 1.27 1.27)
							)
						)
					)
					(number "C23"
						(effects
							(font
								(size 1.27 1.27)
							)
						)
					)
				)
				(pin passive line
					(at 0 -35.56 0)
					(length 5.08)
					(hide yes)
					(name "P1_AVDDL"
						(effects
							(font
								(size 1.27 1.27)
							)
						)
					)
					(number "C25"
						(effects
							(font
								(size 1.27 1.27)
							)
						)
					)
				)
				(pin passive line
					(at 0 -35.56 0)
					(length 5.08)
					(hide yes)
					(name "P1_AVDDL"
						(effects
							(font
								(size 1.27 1.27)
							)
						)
					)
					(number "C27"
						(effects
							(font
								(size 1.27 1.27)
							)
						)
					)
				)
				(pin passive line
					(at 0 -35.56 0)
					(length 5.08)
					(hide yes)
					(name "P1_AVDDL"
						(effects
							(font
								(size 1.27 1.27)
							)
						)
					)
					(number "C29"
						(effects
							(font
								(size 1.27 1.27)
							)
						)
					)
				)
				(pin power_in line
					(at 0 -40.64 0)
					(length 5.08)
					(name "XFI_VDD"
						(effects
							(font
								(size 1.27 1.27)
							)
						)
					)
					(number "J27"
						(effects
							(font
								(size 1.27 1.27)
							)
						)
					)
				)
				(pin passive line
					(at 0 -40.64 0)
					(length 5.08)
					(hide yes)
					(name "XFI_VDD"
						(effects
							(font
								(size 1.27 1.27)
							)
						)
					)
					(number "J29"
						(effects
							(font
								(size 1.27 1.27)
							)
						)
					)
				)
				(pin passive line
					(at 0 -40.64 0)
					(length 5.08)
					(hide yes)
					(name "XFI_VDD"
						(effects
							(font
								(size 1.27 1.27)
							)
						)
					)
					(number "J31"
						(effects
							(font
								(size 1.27 1.27)
							)
						)
					)
				)
				(pin passive line
					(at 0 -40.64 0)
					(length 5.08)
					(hide yes)
					(name "XFI_VDD"
						(effects
							(font
								(size 1.27 1.27)
							)
						)
					)
					(number "J35"
						(effects
							(font
								(size 1.27 1.27)
							)
						)
					)
				)
				(pin power_in line
					(at 0 -45.72 0)
					(length 5.08)
					(name "XFI_PVDD"
						(effects
							(font
								(size 1.27 1.27)
							)
						)
					)
					(number "J33"
						(effects
							(font
								(size 1.27 1.27)
							)
						)
					)
				)
				(pin power_in line
					(at 0 -50.8 0)
					(length 5.08)
					(name "PLL_VDD"
						(effects
							(font
								(size 1.27 1.27)
							)
						)
					)
					(number "G39"
						(effects
							(font
								(size 1.27 1.27)
							)
						)
					)
				)
				(pin power_in line
					(at 50.8 0 180)
					(length 5.08)
					(name "VCCA"
						(effects
							(font
								(size 1.27 1.27)
							)
						)
					)
					(number "L11"
						(effects
							(font
								(size 1.27 1.27)
							)
						)
					)
				)
				(pin passive line
					(at 50.8 0 180)
					(length 5.08)
					(hide yes)
					(name "VCCA"
						(effects
							(font
								(size 1.27 1.27)
							)
						)
					)
					(number "L13"
						(effects
							(font
								(size 1.27 1.27)
							)
						)
					)
				)
				(pin passive line
					(at 50.8 0 180)
					(length 5.08)
					(hide yes)
					(name "VCCA"
						(effects
							(font
								(size 1.27 1.27)
							)
						)
					)
					(number "L15"
						(effects
							(font
								(size 1.27 1.27)
							)
						)
					)
				)
				(pin passive line
					(at 50.8 0 180)
					(length 5.08)
					(hide yes)
					(name "VCCA"
						(effects
							(font
								(size 1.27 1.27)
							)
						)
					)
					(number "L17"
						(effects
							(font
								(size 1.27 1.27)
							)
						)
					)
				)
				(pin passive line
					(at 50.8 0 180)
					(length 5.08)
					(hide yes)
					(name "VCCA"
						(effects
							(font
								(size 1.27 1.27)
							)
						)
					)
					(number "N11"
						(effects
							(font
								(size 1.27 1.27)
							)
						)
					)
				)
				(pin passive line
					(at 50.8 0 180)
					(length 5.08)
					(hide yes)
					(name "VCCA"
						(effects
							(font
								(size 1.27 1.27)
							)
						)
					)
					(number "N13"
						(effects
							(font
								(size 1.27 1.27)
							)
						)
					)
				)
				(pin passive line
					(at 50.8 0 180)
					(length 5.08)
					(hide yes)
					(name "VCCA"
						(effects
							(font
								(size 1.27 1.27)
							)
						)
					)
					(number "N15"
						(effects
							(font
								(size 1.27 1.27)
							)
						)
					)
				)
				(pin passive line
					(at 50.8 0 180)
					(length 5.08)
					(hide yes)
					(name "VCCA"
						(effects
							(font
								(size 1.27 1.27)
							)
						)
					)
					(number "W13"
						(effects
							(font
								(size 1.27 1.27)
							)
						)
					)
				)
				(pin passive line
					(at 50.8 0 180)
					(length 5.08)
					(hide yes)
					(name "VCCA"
						(effects
							(font
								(size 1.27 1.27)
							)
						)
					)
					(number "W15"
						(effects
							(font
								(size 1.27 1.27)
							)
						)
					)
				)
				(pin passive line
					(at 50.8 0 180)
					(length 5.08)
					(hide yes)
					(name "VCCA"
						(effects
							(font
								(size 1.27 1.27)
							)
						)
					)
					(number "W17"
						(effects
							(font
								(size 1.27 1.27)
							)
						)
					)
				)
				(pin passive line
					(at 50.8 0 180)
					(length 5.08)
					(hide yes)
					(name "VCCA"
						(effects
							(font
								(size 1.27 1.27)
							)
						)
					)
					(number "W19"
						(effects
							(font
								(size 1.27 1.27)
							)
						)
					)
				)
				(pin passive line
					(at 50.8 0 180)
					(length 5.08)
					(hide yes)
					(name "VCCA"
						(effects
							(font
								(size 1.27 1.27)
							)
						)
					)
					(number "W21"
						(effects
							(font
								(size 1.27 1.27)
							)
						)
					)
				)
				(pin power_in line
					(at 50.8 -5.08 180)
					(length 5.08)
					(name "VCCD"
						(effects
							(font
								(size 1.27 1.27)
							)
						)
					)
					(number "L19"
						(effects
							(font
								(size 1.27 1.27)
							)
						)
					)
				)
				(pin passive line
					(at 50.8 -5.08 180)
					(length 5.08)
					(hide yes)
					(name "VCCD"
						(effects
							(font
								(size 1.27 1.27)
							)
						)
					)
					(number "L21"
						(effects
							(font
								(size 1.27 1.27)
							)
						)
					)
				)
				(pin passive line
					(at 50.8 -5.08 180)
					(length 5.08)
					(hide yes)
					(name "VCCD"
						(effects
							(font
								(size 1.27 1.27)
							)
						)
					)
					(number "N17"
						(effects
							(font
								(size 1.27 1.27)
							)
						)
					)
				)
				(pin passive line
					(at 50.8 -5.08 180)
					(length 5.08)
					(hide yes)
					(name "VCCD"
						(effects
							(font
								(size 1.27 1.27)
							)
						)
					)
					(number "N19"
						(effects
							(font
								(size 1.27 1.27)
							)
						)
					)
				)
				(pin passive line
					(at 50.8 -5.08 180)
					(length 5.08)
					(hide yes)
					(name "VCCD"
						(effects
							(font
								(size 1.27 1.27)
							)
						)
					)
					(number "N21"
						(effects
							(font
								(size 1.27 1.27)
							)
						)
					)
				)
				(pin passive line
					(at 50.8 -5.08 180)
					(length 5.08)
					(hide yes)
					(name "VCCD"
						(effects
							(font
								(size 1.27 1.27)
							)
						)
					)
					(number "R13"
						(effects
							(font
								(size 1.27 1.27)
							)
						)
					)
				)
				(pin passive line
					(at 50.8 -5.08 180)
					(length 5.08)
					(hide yes)
					(name "VCCD"
						(effects
							(font
								(size 1.27 1.27)
							)
						)
					)
					(number "R15"
						(effects
							(font
								(size 1.27 1.27)
							)
						)
					)
				)
				(pin passive line
					(at 50.8 -5.08 180)
					(length 5.08)
					(hide yes)
					(name "VCCD"
						(effects
							(font
								(size 1.27 1.27)
							)
						)
					)
					(number "R17"
						(effects
							(font
								(size 1.27 1.27)
							)
						)
					)
				)
				(pin passive line
					(at 50.8 -5.08 180)
					(length 5.08)
					(hide yes)
					(name "VCCD"
						(effects
							(font
								(size 1.27 1.27)
							)
						)
					)
					(number "R19"
						(effects
							(font
								(size 1.27 1.27)
							)
						)
					)
				)
				(pin passive line
					(at 50.8 -5.08 180)
					(length 5.08)
					(hide yes)
					(name "VCCD"
						(effects
							(font
								(size 1.27 1.27)
							)
						)
					)
					(number "R21"
						(effects
							(font
								(size 1.27 1.27)
							)
						)
					)
				)
				(pin passive line
					(at 50.8 -5.08 180)
					(length 5.08)
					(hide yes)
					(name "VCCD"
						(effects
							(font
								(size 1.27 1.27)
							)
						)
					)
					(number "U11"
						(effects
							(font
								(size 1.27 1.27)
							)
						)
					)
				)
				(pin passive line
					(at 50.8 -5.08 180)
					(length 5.08)
					(hide yes)
					(name "VCCD"
						(effects
							(font
								(size 1.27 1.27)
							)
						)
					)
					(number "U13"
						(effects
							(font
								(size 1.27 1.27)
							)
						)
					)
				)
				(pin passive line
					(at 50.8 -5.08 180)
					(length 5.08)
					(hide yes)
					(name "VCCD"
						(effects
							(font
								(size 1.27 1.27)
							)
						)
					)
					(number "U15"
						(effects
							(font
								(size 1.27 1.27)
							)
						)
					)
				)
				(pin passive line
					(at 50.8 -5.08 180)
					(length 5.08)
					(hide yes)
					(name "VCCD"
						(effects
							(font
								(size 1.27 1.27)
							)
						)
					)
					(number "U17"
						(effects
							(font
								(size 1.27 1.27)
							)
						)
					)
				)
				(pin passive line
					(at 50.8 -5.08 180)
					(length 5.08)
					(hide yes)
					(name "VCCD"
						(effects
							(font
								(size 1.27 1.27)
							)
						)
					)
					(number "U19"
						(effects
							(font
								(size 1.27 1.27)
							)
						)
					)
				)
				(pin power_in line
					(at 50.8 -7.62 180)
					(length 5.08)
					(name "VCCD_A"
						(effects
							(font
								(size 1.27 1.27)
							)
						)
					)
					(number "W9"
						(effects
							(font
								(size 1.27 1.27)
							)
						)
					)
				)
				(pin passive line
					(at 50.8 -10.16 180)
					(length 5.08)
					(name "RSVDT8_VCCD"
						(effects
							(font
								(size 1.27 1.27)
							)
						)
					)
					(number "T8"
						(effects
							(font
								(size 1.27 1.27)
							)
						)
					)
				)
				(pin passive line
					(at 50.8 -15.24 180)
					(length 5.08)
					(hide yes)
					(name "VCC3P3"
						(effects
							(font
								(size 1.27 1.27)
							)
						)
					)
					(number "R11"
						(effects
							(font
								(size 1.27 1.27)
							)
						)
					)
				)
				(pin passive line
					(at 50.8 -15.24 180)
					(length 5.08)
					(hide yes)
					(name "VCC3P3"
						(effects
							(font
								(size 1.27 1.27)
							)
						)
					)
					(number "T34"
						(effects
							(font
								(size 1.27 1.27)
							)
						)
					)
				)
				(pin power_in line
					(at 50.8 -15.24 180)
					(length 5.08)
					(name "VCC3P3"
						(effects
							(font
								(size 1.27 1.27)
							)
						)
					)
					(number "U21"
						(effects
							(font
								(size 1.27 1.27)
							)
						)
					)
				)
				(pin power_in line
					(at 50.8 -17.78 180)
					(length 5.08)
					(name "VCC3P3_A"
						(effects
							(font
								(size 1.27 1.27)
							)
						)
					)
					(number "W11"
						(effects
							(font
								(size 1.27 1.27)
							)
						)
					)
				)
				(pin power_in line
					(at 50.8 -20.32 180)
					(length 5.08)
					(name "VCC3P3_TX"
						(effects
							(font
								(size 1.27 1.27)
							)
						)
					)
					(number "L9"
						(effects
							(font
								(size 1.27 1.27)
							)
						)
					)
				)
				(pin power_in line
					(at 50.8 -25.4 180)
					(length 5.08)
					(name "VCC3P3_SVR"
						(effects
							(font
								(size 1.27 1.27)
							)
						)
					)
					(number "T2"
						(effects
							(font
								(size 1.27 1.27)
							)
						)
					)
				)
				(pin passive line
					(at 50.8 -27.94 180)
					(length 5.08)
					(name "SVR_IND"
						(effects
							(font
								(size 1.27 1.27)
							)
						)
					)
					(number "V2"
						(effects
							(font
								(size 1.27 1.27)
							)
						)
					)
				)
				(pin passive line
					(at 50.8 -33.02 180)
					(length 5.08)
					(name "RSVDV8_NC"
						(effects
							(font
								(size 1.27 1.27)
							)
						)
					)
					(number "V8"
						(effects
							(font
								(size 1.27 1.27)
							)
						)
					)
				)
				(pin passive line
					(at 50.8 -35.56 180)
					(length 5.08)
					(name "RSVDV10_NC"
						(effects
							(font
								(size 1.27 1.27)
							)
						)
					)
					(number "V10"
						(effects
							(font
								(size 1.27 1.27)
							)
						)
					)
				)
				(pin passive line
					(at 50.8 -40.64 180)
					(length 5.08)
					(hide yes)
					(name "VSSA"
						(effects
							(font
								(size 1.27 1.27)
							)
						)
					)
					(number "A11"
						(effects
							(font
								(size 1.27 1.27)
							)
						)
					)
				)
				(pin passive line
					(at 50.8 -40.64 180)
					(length 5.08)
					(hide yes)
					(name "VSSA"
						(effects
							(font
								(size 1.27 1.27)
							)
						)
					)
					(number "A15"
						(effects
							(font
								(size 1.27 1.27)
							)
						)
					)
				)
				(pin passive line
					(at 50.8 -40.64 180)
					(length 5.08)
					(hide yes)
					(name "VSSA"
						(effects
							(font
								(size 1.27 1.27)
							)
						)
					)
					(number "A19"
						(effects
							(font
								(size 1.27 1.27)
							)
						)
					)
				)
				(pin power_in line
					(at 50.8 -40.64 180)
					(length 5.08)
					(name "VSSA"
						(effects
							(font
								(size 1.27 1.27)
							)
						)
					)
					(number "A3"
						(effects
							(font
								(size 1.27 1.27)
							)
						)
					)
				)
				(pin passive line
					(at 50.8 -40.64 180)
					(length 5.08)
					(hide yes)
					(name "VSSA"
						(effects
							(font
								(size 1.27 1.27)
							)
						)
					)
					(number "A7"
						(effects
							(font
								(size 1.27 1.27)
							)
						)
					)
				)
				(pin passive line
					(at 50.8 -40.64 180)
					(length 5.08)
					(hide yes)
					(name "VSSA"
						(effects
							(font
								(size 1.27 1.27)
							)
						)
					)
					(number "AA11"
						(effects
							(font
								(size 1.27 1.27)
							)
						)
					)
				)
				(pin passive line
					(at 50.8 -40.64 180)
					(length 5.08)
					(hide yes)
					(name "VSSA"
						(effects
							(font
								(size 1.27 1.27)
							)
						)
					)
					(number "AA13"
						(effects
							(font
								(size 1.27 1.27)
							)
						)
					)
				)
				(pin passive line
					(at 50.8 -40.64 180)
					(length 5.08)
					(hide yes)
					(name "VSSA"
						(effects
							(font
								(size 1.27 1.27)
							)
						)
					)
					(number "AA15"
						(effects
							(font
								(size 1.27 1.27)
							)
						)
					)
				)
				(pin passive line
					(at 50.8 -40.64 180)
					(length 5.08)
					(hide yes)
					(name "VSSA"
						(effects
							(font
								(size 1.27 1.27)
							)
						)
					)
					(number "AA17"
						(effects
							(font
								(size 1.27 1.27)
							)
						)
					)
				)
				(pin passive line
					(at 50.8 -40.64 180)
					(length 5.08)
					(hide yes)
					(name "VSSA"
						(effects
							(font
								(size 1.27 1.27)
							)
						)
					)
					(number "AA19"
						(effects
							(font
								(size 1.27 1.27)
							)
						)
					)
				)
				(pin passive line
					(at 50.8 -40.64 180)
					(length 5.08)
					(hide yes)
					(name "VSSA"
						(effects
							(font
								(size 1.27 1.27)
							)
						)
					)
					(number "AA21"
						(effects
							(font
								(size 1.27 1.27)
							)
						)
					)
				)
				(pin passive line
					(at 50.8 -40.64 180)
					(length 5.08)
					(hide yes)
					(name "VSSA"
						(effects
							(font
								(size 1.27 1.27)
							)
						)
					)
					(number "AA23"
						(effects
							(font
								(size 1.27 1.27)
							)
						)
					)
				)
				(pin passive line
					(at 50.8 -40.64 180)
					(length 5.08)
					(hide yes)
					(name "VSSA"
						(effects
							(font
								(size 1.27 1.27)
							)
						)
					)
					(number "AA25"
						(effects
							(font
								(size 1.27 1.27)
							)
						)
					)
				)
				(pin passive line
					(at 50.8 -40.64 180)
					(length 5.08)
					(hide yes)
					(name "VSSA"
						(effects
							(font
								(size 1.27 1.27)
							)
						)
					)
					(number "AA29"
						(effects
							(font
								(size 1.27 1.27)
							)
						)
					)
				)
				(pin passive line
					(at 50.8 -40.64 180)
					(length 5.08)
					(hide yes)
					(name "VSSA"
						(effects
							(font
								(size 1.27 1.27)
							)
						)
					)
					(number "AA3"
						(effects
							(font
								(size 1.27 1.27)
							)
						)
					)
				)
				(pin passive line
					(at 50.8 -40.64 180)
					(length 5.08)
					(hide yes)
					(name "VSSA"
						(effects
							(font
								(size 1.27 1.27)
							)
						)
					)
					(number "AA33"
						(effects
							(font
								(size 1.27 1.27)
							)
						)
					)
				)
				(pin passive line
					(at 50.8 -40.64 180)
					(length 5.08)
					(hide yes)
					(name "VSSA"
						(effects
							(font
								(size 1.27 1.27)
							)
						)
					)
					(number "AA37"
						(effects
							(font
								(size 1.27 1.27)
							)
						)
					)
				)
				(pin passive line
					(at 50.8 -40.64 180)
					(length 5.08)
					(hide yes)
					(name "VSSA"
						(effects
							(font
								(size 1.27 1.27)
							)
						)
					)
					(number "AA41"
						(effects
							(font
								(size 1.27 1.27)
							)
						)
					)
				)
				(pin passive line
					(at 50.8 -40.64 180)
					(length 5.08)
					(hide yes)
					(name "VSSA"
						(effects
							(font
								(size 1.27 1.27)
							)
						)
					)
					(number "AA9"
						(effects
							(font
								(size 1.27 1.27)
							)
						)
					)
				)
				(pin passive line
					(at 50.8 -40.64 180)
					(length 5.08)
					(hide yes)
					(name "VSSA"
						(effects
							(font
								(size 1.27 1.27)
							)
						)
					)
					(number "AB14"
						(effects
							(font
								(size 1.27 1.27)
							)
						)
					)
				)
				(pin passive line
					(at 50.8 -40.64 180)
					(length 5.08)
					(hide yes)
					(name "VSSA"
						(effects
							(font
								(size 1.27 1.27)
							)
						)
					)
					(number "AB20"
						(effects
							(font
								(size 1.27 1.27)
							)
						)
					)
				)
				(pin passive line
					(at 50.8 -40.64 180)
					(length 5.08)
					(hide yes)
					(name "VSSA"
						(effects
							(font
								(size 1.27 1.27)
							)
						)
					)
					(number "AB26"
						(effects
							(font
								(size 1.27 1.27)
							)
						)
					)
				)
				(pin passive line
					(at 50.8 -40.64 180)
					(length 5.08)
					(hide yes)
					(name "VSSA"
						(effects
							(font
								(size 1.27 1.27)
							)
						)
					)
					(number "AB30"
						(effects
							(font
								(size 1.27 1.27)
							)
						)
					)
				)
				(pin passive line
					(at 50.8 -40.64 180)
					(length 5.08)
					(hide yes)
					(name "VSSA"
						(effects
							(font
								(size 1.27 1.27)
							)
						)
					)
					(number "AB32"
						(effects
							(font
								(size 1.27 1.27)
							)
						)
					)
				)
				(pin passive line
					(at 50.8 -40.64 180)
					(length 5.08)
					(hide yes)
					(name "VSSA"
						(effects
							(font
								(size 1.27 1.27)
							)
						)
					)
					(number "AB34"
						(effects
							(font
								(size 1.27 1.27)
							)
						)
					)
				)
				(pin passive line
					(at 50.8 -40.64 180)
					(length 5.08)
					(hide yes)
					(name "VSSA"
						(effects
							(font
								(size 1.27 1.27)
							)
						)
					)
					(number "AB36"
						(effects
							(font
								(size 1.27 1.27)
							)
						)
					)
				)
				(pin passive line
					(at 50.8 -40.64 180)
					(length 5.08)
					(hide yes)
					(name "VSSA"
						(effects
							(font
								(size 1.27 1.27)
							)
						)
					)
					(number "AB38"
						(effects
							(font
								(size 1.27 1.27)
							)
						)
					)
				)
				(pin passive line
					(at 50.8 -40.64 180)
					(length 5.08)
					(hide yes)
					(name "VSSA"
						(effects
							(font
								(size 1.27 1.27)
							)
						)
					)
					(number "AB4"
						(effects
							(font
								(size 1.27 1.27)
							)
						)
					)
				)
				(pin passive line
					(at 50.8 -40.64 180)
					(length 5.08)
					(hide yes)
					(name "VSSA"
						(effects
							(font
								(size 1.27 1.27)
							)
						)
					)
					(number "AB40"
						(effects
							(font
								(size 1.27 1.27)
							)
						)
					)
				)
				(pin passive line
					(at 50.8 -40.64 180)
					(length 5.08)
					(hide yes)
					(name "VSSA"
						(effects
							(font
								(size 1.27 1.27)
							)
						)
					)
					(number "AB6"
						(effects
							(font
								(size 1.27 1.27)
							)
						)
					)
				)
				(pin passive line
					(at 50.8 -40.64 180)
					(length 5.08)
					(hide yes)
					(name "VSSA"
						(effects
							(font
								(size 1.27 1.27)
							)
						)
					)
					(number "AB8"
						(effects
							(font
								(size 1.27 1.27)
							)
						)
					)
				)
				(pin passive line
					(at 50.8 -40.64 180)
					(length 5.08)
					(hide yes)
					(name "VSSA"
						(effects
							(font
								(size 1.27 1.27)
							)
						)
					)
					(number "AC1"
						(effects
							(font
								(size 1.27 1.27)
							)
						)
					)
				)
				(pin passive line
					(at 50.8 -40.64 180)
					(length 5.08)
					(hide yes)
					(name "VSSA"
						(effects
							(font
								(size 1.27 1.27)
							)
						)
					)
					(number "AC11"
						(effects
							(font
								(size 1.27 1.27)
							)
						)
					)
				)
				(pin passive line
					(at 50.8 -40.64 180)
					(length 5.08)
					(hide yes)
					(name "VSSA"
						(effects
							(font
								(size 1.27 1.27)
							)
						)
					)
					(number "AC13"
						(effects
							(font
								(size 1.27 1.27)
							)
						)
					)
				)
				(pin passive line
					(at 50.8 -40.64 180)
					(length 5.08)
					(hide yes)
					(name "VSSA"
						(effects
							(font
								(size 1.27 1.27)
							)
						)
					)
					(number "AC15"
						(effects
							(font
								(size 1.27 1.27)
							)
						)
					)
				)
				(pin passive line
					(at 50.8 -40.64 180)
					(length 5.08)
					(hide yes)
					(name "VSSA"
						(effects
							(font
								(size 1.27 1.27)
							)
						)
					)
					(number "AC17"
						(effects
							(font
								(size 1.27 1.27)
							)
						)
					)
				)
				(pin passive line
					(at 50.8 -40.64 180)
					(length 5.08)
					(hide yes)
					(name "VSSA"
						(effects
							(font
								(size 1.27 1.27)
							)
						)
					)
					(number "AC19"
						(effects
							(font
								(size 1.27 1.27)
							)
						)
					)
				)
				(pin passive line
					(at 50.8 -40.64 180)
					(length 5.08)
					(hide yes)
					(name "VSSA"
						(effects
							(font
								(size 1.27 1.27)
							)
						)
					)
					(number "AC21"
						(effects
							(font
								(size 1.27 1.27)
							)
						)
					)
				)
				(pin passive line
					(at 50.8 -40.64 180)
					(length 5.08)
					(hide yes)
					(name "VSSA"
						(effects
							(font
								(size 1.27 1.27)
							)
						)
					)
					(number "AC23"
						(effects
							(font
								(size 1.27 1.27)
							)
						)
					)
				)
				(pin passive line
					(at 50.8 -40.64 180)
					(length 5.08)
					(hide yes)
					(name "VSSA"
						(effects
							(font
								(size 1.27 1.27)
							)
						)
					)
					(number "AC25"
						(effects
							(font
								(size 1.27 1.27)
							)
						)
					)
				)
				(pin passive line
					(at 50.8 -40.64 180)
					(length 5.08)
					(hide yes)
					(name "VSSA"
						(effects
							(font
								(size 1.27 1.27)
							)
						)
					)
					(number "AC27"
						(effects
							(font
								(size 1.27 1.27)
							)
						)
					)
				)
				(pin passive line
					(at 50.8 -40.64 180)
					(length 5.08)
					(hide yes)
					(name "VSSA"
						(effects
							(font
								(size 1.27 1.27)
							)
						)
					)
					(number "AC29"
						(effects
							(font
								(size 1.27 1.27)
							)
						)
					)
				)
				(pin passive line
					(at 50.8 -40.64 180)
					(length 5.08)
					(hide yes)
					(name "VSSA"
						(effects
							(font
								(size 1.27 1.27)
							)
						)
					)
					(number "AC3"
						(effects
							(font
								(size 1.27 1.27)
							)
						)
					)
				)
				(pin passive line
					(at 50.8 -40.64 180)
					(length 5.08)
					(hide yes)
					(name "VSSA"
						(effects
							(font
								(size 1.27 1.27)
							)
						)
					)
					(number "AC33"
						(effects
							(font
								(size 1.27 1.27)
							)
						)
					)
				)
				(pin passive line
					(at 50.8 -40.64 180)
					(length 5.08)
					(hide yes)
					(name "VSSA"
						(effects
							(font
								(size 1.27 1.27)
							)
						)
					)
					(number "AC37"
						(effects
							(font
								(size 1.27 1.27)
							)
						)
					)
				)
				(pin passive line
					(at 50.8 -40.64 180)
					(length 5.08)
					(hide yes)
					(name "VSSA"
						(effects
							(font
								(size 1.27 1.27)
							)
						)
					)
					(number "AC41"
						(effects
							(font
								(size 1.27 1.27)
							)
						)
					)
				)
				(pin passive line
					(at 50.8 -40.64 180)
					(length 5.08)
					(hide yes)
					(name "VSSA"
						(effects
							(font
								(size 1.27 1.27)
							)
						)
					)
					(number "AC7"
						(effects
							(font
								(size 1.27 1.27)
							)
						)
					)
				)
				(pin passive line
					(at 50.8 -40.64 180)
					(length 5.08)
					(hide yes)
					(name "VSSA"
						(effects
							(font
								(size 1.27 1.27)
							)
						)
					)
					(number "AC9"
						(effects
							(font
								(size 1.27 1.27)
							)
						)
					)
				)
				(pin passive line
					(at 50.8 -40.64 180)
					(length 5.08)
					(hide yes)
					(name "VSSA"
						(effects
							(font
								(size 1.27 1.27)
							)
						)
					)
					(number "AD12"
						(effects
							(font
								(size 1.27 1.27)
							)
						)
					)
				)
				(pin passive line
					(at 50.8 -40.64 180)
					(length 5.08)
					(hide yes)
					(name "VSSA"
						(effects
							(font
								(size 1.27 1.27)
							)
						)
					)
					(number "AD18"
						(effects
							(font
								(size 1.27 1.27)
							)
						)
					)
				)
				(pin passive line
					(at 50.8 -40.64 180)
					(length 5.08)
					(hide yes)
					(name "VSSA"
						(effects
							(font
								(size 1.27 1.27)
							)
						)
					)
					(number "AD2"
						(effects
							(font
								(size 1.27 1.27)
							)
						)
					)
				)
				(pin passive line
					(at 50.8 -40.64 180)
					(length 5.08)
					(hide yes)
					(name "VSSA"
						(effects
							(font
								(size 1.27 1.27)
							)
						)
					)
					(number "AD24"
						(effects
							(font
								(size 1.27 1.27)
							)
						)
					)
				)
				(pin passive line
					(at 50.8 -40.64 180)
					(length 5.08)
					(hide yes)
					(name "VSSA"
						(effects
							(font
								(size 1.27 1.27)
							)
						)
					)
					(number "AD30"
						(effects
							(font
								(size 1.27 1.27)
							)
						)
					)
				)
				(pin passive line
					(at 50.8 -40.64 180)
					(length 5.08)
					(hide yes)
					(name "VSSA"
						(effects
							(font
								(size 1.27 1.27)
							)
						)
					)
					(number "AD34"
						(effects
							(font
								(size 1.27 1.27)
							)
						)
					)
				)
				(pin passive line
					(at 50.8 -40.64 180)
					(length 5.08)
					(hide yes)
					(name "VSSA"
						(effects
							(font
								(size 1.27 1.27)
							)
						)
					)
					(number "AD38"
						(effects
							(font
								(size 1.27 1.27)
							)
						)
					)
				)
				(pin passive line
					(at 50.8 -40.64 180)
					(length 5.08)
					(hide yes)
					(name "VSSA"
						(effects
							(font
								(size 1.27 1.27)
							)
						)
					)
					(number "AD42"
						(effects
							(font
								(size 1.27 1.27)
							)
						)
					)
				)
				(pin passive line
					(at 50.8 -40.64 180)
					(length 5.08)
					(hide yes)
					(name "VSSA"
						(effects
							(font
								(size 1.27 1.27)
							)
						)
					)
					(number "AD6"
						(effects
							(font
								(size 1.27 1.27)
							)
						)
					)
				)
				(pin passive line
					(at 50.8 -40.64 180)
					(length 5.08)
					(hide yes)
					(name "VSSA"
						(effects
							(font
								(size 1.27 1.27)
							)
						)
					)
					(number "B12"
						(effects
							(font
								(size 1.27 1.27)
							)
						)
					)
				)
				(pin passive line
					(at 50.8 -40.64 180)
					(length 5.08)
					(hide yes)
					(name "VSSA"
						(effects
							(font
								(size 1.27 1.27)
							)
						)
					)
					(number "B16"
						(effects
							(font
								(size 1.27 1.27)
							)
						)
					)
				)
				(pin passive line
					(at 50.8 -40.64 180)
					(length 5.08)
					(hide yes)
					(name "VSSA"
						(effects
							(font
								(size 1.27 1.27)
							)
						)
					)
					(number "B2"
						(effects
							(font
								(size 1.27 1.27)
							)
						)
					)
				)
				(pin passive line
					(at 50.8 -40.64 180)
					(length 5.08)
					(hide yes)
					(name "VSSA"
						(effects
							(font
								(size 1.27 1.27)
							)
						)
					)
					(number "B20"
						(effects
							(font
								(size 1.27 1.27)
							)
						)
					)
				)
				(pin passive line
					(at 50.8 -40.64 180)
					(length 5.08)
					(hide yes)
					(name "VSSA"
						(effects
							(font
								(size 1.27 1.27)
							)
						)
					)
					(number "B4"
						(effects
							(font
								(size 1.27 1.27)
							)
						)
					)
				)
				(pin passive line
					(at 50.8 -40.64 180)
					(length 5.08)
					(hide yes)
					(name "VSSA"
						(effects
							(font
								(size 1.27 1.27)
							)
						)
					)
					(number "B8"
						(effects
							(font
								(size 1.27 1.27)
							)
						)
					)
				)
				(pin passive line
					(at 50.8 -40.64 180)
					(length 5.08)
					(hide yes)
					(name "VSSA"
						(effects
							(font
								(size 1.27 1.27)
							)
						)
					)
					(number "C11"
						(effects
							(font
								(size 1.27 1.27)
							)
						)
					)
				)
				(pin passive line
					(at 50.8 -40.64 180)
					(length 5.08)
					(hide yes)
					(name "VSSA"
						(effects
							(font
								(size 1.27 1.27)
							)
						)
					)
					(number "C13"
						(effects
							(font
								(size 1.27 1.27)
							)
						)
					)
				)
				(pin passive line
					(at 50.8 -40.64 180)
					(length 5.08)
					(hide yes)
					(name "VSSA"
						(effects
							(font
								(size 1.27 1.27)
							)
						)
					)
					(number "C15"
						(effects
							(font
								(size 1.27 1.27)
							)
						)
					)
				)
				(pin passive line
					(at 50.8 -40.64 180)
					(length 5.08)
					(hide yes)
					(name "VSSA"
						(effects
							(font
								(size 1.27 1.27)
							)
						)
					)
					(number "C17"
						(effects
							(font
								(size 1.27 1.27)
							)
						)
					)
				)
				(pin passive line
					(at 50.8 -40.64 180)
					(length 5.08)
					(hide yes)
					(name "VSSA"
						(effects
							(font
								(size 1.27 1.27)
							)
						)
					)
					(number "C19"
						(effects
							(font
								(size 1.27 1.27)
							)
						)
					)
				)
				(pin passive line
					(at 50.8 -40.64 180)
					(length 5.08)
					(hide yes)
					(name "VSSA"
						(effects
							(font
								(size 1.27 1.27)
							)
						)
					)
					(number "C5"
						(effects
							(font
								(size 1.27 1.27)
							)
						)
					)
				)
				(pin passive line
					(at 50.8 -40.64 180)
					(length 5.08)
					(hide yes)
					(name "VSSA"
						(effects
							(font
								(size 1.27 1.27)
							)
						)
					)
					(number "C7"
						(effects
							(font
								(size 1.27 1.27)
							)
						)
					)
				)
				(pin passive line
					(at 50.8 -40.64 180)
					(length 5.08)
					(hide yes)
					(name "VSSA"
						(effects
							(font
								(size 1.27 1.27)
							)
						)
					)
					(number "C9"
						(effects
							(font
								(size 1.27 1.27)
							)
						)
					)
				)
				(pin passive line
					(at 50.8 -40.64 180)
					(length 5.08)
					(hide yes)
					(name "VSSA"
						(effects
							(font
								(size 1.27 1.27)
							)
						)
					)
					(number "H26"
						(effects
							(font
								(size 1.27 1.27)
							)
						)
					)
				)
				(pin passive line
					(at 50.8 -40.64 180)
					(length 5.08)
					(hide yes)
					(name "VSSA"
						(effects
							(font
								(size 1.27 1.27)
							)
						)
					)
					(number "H28"
						(effects
							(font
								(size 1.27 1.27)
							)
						)
					)
				)
				(pin passive line
					(at 50.8 -40.64 180)
					(length 5.08)
					(hide yes)
					(name "VSSA"
						(effects
							(font
								(size 1.27 1.27)
							)
						)
					)
					(number "H30"
						(effects
							(font
								(size 1.27 1.27)
							)
						)
					)
				)
				(pin passive line
					(at 50.8 -40.64 180)
					(length 5.08)
					(hide yes)
					(name "VSSA"
						(effects
							(font
								(size 1.27 1.27)
							)
						)
					)
					(number "H32"
						(effects
							(font
								(size 1.27 1.27)
							)
						)
					)
				)
				(pin passive line
					(at 50.8 -40.64 180)
					(length 5.08)
					(hide yes)
					(name "VSSA"
						(effects
							(font
								(size 1.27 1.27)
							)
						)
					)
					(number "H34"
						(effects
							(font
								(size 1.27 1.27)
							)
						)
					)
				)
				(pin passive line
					(at 50.8 -40.64 180)
					(length 5.08)
					(hide yes)
					(name "VSSA"
						(effects
							(font
								(size 1.27 1.27)
							)
						)
					)
					(number "H36"
						(effects
							(font
								(size 1.27 1.27)
							)
						)
					)
				)
				(pin passive line
					(at 50.8 -40.64 180)
					(length 5.08)
					(hide yes)
					(name "VSSA"
						(effects
							(font
								(size 1.27 1.27)
							)
						)
					)
					(number "H38"
						(effects
							(font
								(size 1.27 1.27)
							)
						)
					)
				)
				(pin passive line
					(at 50.8 -40.64 180)
					(length 5.08)
					(hide yes)
					(name "VSSA"
						(effects
							(font
								(size 1.27 1.27)
							)
						)
					)
					(number "K10"
						(effects
							(font
								(size 1.27 1.27)
							)
						)
					)
				)
				(pin passive line
					(at 50.8 -40.64 180)
					(length 5.08)
					(hide yes)
					(name "VSSA"
						(effects
							(font
								(size 1.27 1.27)
							)
						)
					)
					(number "K12"
						(effects
							(font
								(size 1.27 1.27)
							)
						)
					)
				)
				(pin passive line
					(at 50.8 -40.64 180)
					(length 5.08)
					(hide yes)
					(name "VSSA"
						(effects
							(font
								(size 1.27 1.27)
							)
						)
					)
					(number "K14"
						(effects
							(font
								(size 1.27 1.27)
							)
						)
					)
				)
				(pin passive line
					(at 50.8 -40.64 180)
					(length 5.08)
					(hide yes)
					(name "VSSA"
						(effects
							(font
								(size 1.27 1.27)
							)
						)
					)
					(number "K16"
						(effects
							(font
								(size 1.27 1.27)
							)
						)
					)
				)
				(pin passive line
					(at 50.8 -40.64 180)
					(length 5.08)
					(hide yes)
					(name "VSSA"
						(effects
							(font
								(size 1.27 1.27)
							)
						)
					)
					(number "K38"
						(effects
							(font
								(size 1.27 1.27)
							)
						)
					)
				)
				(pin passive line
					(at 50.8 -40.64 180)
					(length 5.08)
					(hide yes)
					(name "VSSA"
						(effects
							(font
								(size 1.27 1.27)
							)
						)
					)
					(number "K8"
						(effects
							(font
								(size 1.27 1.27)
							)
						)
					)
				)
				(pin passive line
					(at 50.8 -40.64 180)
					(length 5.08)
					(hide yes)
					(name "VSSA"
						(effects
							(font
								(size 1.27 1.27)
							)
						)
					)
					(number "M10"
						(effects
							(font
								(size 1.27 1.27)
							)
						)
					)
				)
				(pin passive line
					(at 50.8 -40.64 180)
					(length 5.08)
					(hide yes)
					(name "VSSA"
						(effects
							(font
								(size 1.27 1.27)
							)
						)
					)
					(number "M12"
						(effects
							(font
								(size 1.27 1.27)
							)
						)
					)
				)
				(pin passive line
					(at 50.8 -40.64 180)
					(length 5.08)
					(hide yes)
					(name "VSSA"
						(effects
							(font
								(size 1.27 1.27)
							)
						)
					)
					(number "M14"
						(effects
							(font
								(size 1.27 1.27)
							)
						)
					)
				)
				(pin passive line
					(at 50.8 -40.64 180)
					(length 5.08)
					(hide yes)
					(name "VSSA"
						(effects
							(font
								(size 1.27 1.27)
							)
						)
					)
					(number "M16"
						(effects
							(font
								(size 1.27 1.27)
							)
						)
					)
				)
				(pin passive line
					(at 50.8 -40.64 180)
					(length 5.08)
					(hide yes)
					(name "VSSA"
						(effects
							(font
								(size 1.27 1.27)
							)
						)
					)
					(number "V12"
						(effects
							(font
								(size 1.27 1.27)
							)
						)
					)
				)
				(pin passive line
					(at 50.8 -40.64 180)
					(length 5.08)
					(hide yes)
					(name "VSSA"
						(effects
							(font
								(size 1.27 1.27)
							)
						)
					)
					(number "V14"
						(effects
							(font
								(size 1.27 1.27)
							)
						)
					)
				)
				(pin passive line
					(at 50.8 -40.64 180)
					(length 5.08)
					(hide yes)
					(name "VSSA"
						(effects
							(font
								(size 1.27 1.27)
							)
						)
					)
					(number "V16"
						(effects
							(font
								(size 1.27 1.27)
							)
						)
					)
				)
				(pin passive line
					(at 50.8 -40.64 180)
					(length 5.08)
					(hide yes)
					(name "VSSA"
						(effects
							(font
								(size 1.27 1.27)
							)
						)
					)
					(number "V18"
						(effects
							(font
								(size 1.27 1.27)
							)
						)
					)
				)
				(pin passive line
					(at 50.8 -40.64 180)
					(length 5.08)
					(hide yes)
					(name "VSSA"
						(effects
							(font
								(size 1.27 1.27)
							)
						)
					)
					(number "V20"
						(effects
							(font
								(size 1.27 1.27)
							)
						)
					)
				)
				(pin passive line
					(at 50.8 -40.64 180)
					(length 5.08)
					(hide yes)
					(name "VSSA"
						(effects
							(font
								(size 1.27 1.27)
							)
						)
					)
					(number "W29"
						(effects
							(font
								(size 1.27 1.27)
							)
						)
					)
				)
				(pin passive line
					(at 50.8 -40.64 180)
					(length 5.08)
					(hide yes)
					(name "VSSA"
						(effects
							(font
								(size 1.27 1.27)
							)
						)
					)
					(number "W31"
						(effects
							(font
								(size 1.27 1.27)
							)
						)
					)
				)
				(pin passive line
					(at 50.8 -40.64 180)
					(length 5.08)
					(hide yes)
					(name "VSSA"
						(effects
							(font
								(size 1.27 1.27)
							)
						)
					)
					(number "W33"
						(effects
							(font
								(size 1.27 1.27)
							)
						)
					)
				)
				(pin passive line
					(at 50.8 -40.64 180)
					(length 5.08)
					(hide yes)
					(name "VSSA"
						(effects
							(font
								(size 1.27 1.27)
							)
						)
					)
					(number "W35"
						(effects
							(font
								(size 1.27 1.27)
							)
						)
					)
				)
				(pin passive line
					(at 50.8 -40.64 180)
					(length 5.08)
					(hide yes)
					(name "VSSA"
						(effects
							(font
								(size 1.27 1.27)
							)
						)
					)
					(number "W37"
						(effects
							(font
								(size 1.27 1.27)
							)
						)
					)
				)
				(pin passive line
					(at 50.8 -40.64 180)
					(length 5.08)
					(hide yes)
					(name "VSSA"
						(effects
							(font
								(size 1.27 1.27)
							)
						)
					)
					(number "W39"
						(effects
							(font
								(size 1.27 1.27)
							)
						)
					)
				)
				(pin passive line
					(at 50.8 -40.64 180)
					(length 5.08)
					(hide yes)
					(name "VSSA"
						(effects
							(font
								(size 1.27 1.27)
							)
						)
					)
					(number "Y14"
						(effects
							(font
								(size 1.27 1.27)
							)
						)
					)
				)
				(pin passive line
					(at 50.8 -40.64 180)
					(length 5.08)
					(hide yes)
					(name "VSSA"
						(effects
							(font
								(size 1.27 1.27)
							)
						)
					)
					(number "Y26"
						(effects
							(font
								(size 1.27 1.27)
							)
						)
					)
				)
				(pin passive line
					(at 50.8 -40.64 180)
					(length 5.08)
					(hide yes)
					(name "VSSA"
						(effects
							(font
								(size 1.27 1.27)
							)
						)
					)
					(number "Y28"
						(effects
							(font
								(size 1.27 1.27)
							)
						)
					)
				)
				(pin passive line
					(at 50.8 -40.64 180)
					(length 5.08)
					(hide yes)
					(name "VSSA"
						(effects
							(font
								(size 1.27 1.27)
							)
						)
					)
					(number "Y32"
						(effects
							(font
								(size 1.27 1.27)
							)
						)
					)
				)
				(pin passive line
					(at 50.8 -40.64 180)
					(length 5.08)
					(hide yes)
					(name "VSSA"
						(effects
							(font
								(size 1.27 1.27)
							)
						)
					)
					(number "Y36"
						(effects
							(font
								(size 1.27 1.27)
							)
						)
					)
				)
				(pin passive line
					(at 50.8 -40.64 180)
					(length 5.08)
					(hide yes)
					(name "VSSA"
						(effects
							(font
								(size 1.27 1.27)
							)
						)
					)
					(number "Y4"
						(effects
							(font
								(size 1.27 1.27)
							)
						)
					)
				)
				(pin passive line
					(at 50.8 -40.64 180)
					(length 5.08)
					(hide yes)
					(name "VSSA"
						(effects
							(font
								(size 1.27 1.27)
							)
						)
					)
					(number "Y40"
						(effects
							(font
								(size 1.27 1.27)
							)
						)
					)
				)
				(pin passive line
					(at 50.8 -40.64 180)
					(length 5.08)
					(hide yes)
					(name "VSSA"
						(effects
							(font
								(size 1.27 1.27)
							)
						)
					)
					(number "Y6"
						(effects
							(font
								(size 1.27 1.27)
							)
						)
					)
				)
				(pin passive line
					(at 50.8 -40.64 180)
					(length 5.08)
					(hide yes)
					(name "VSSA"
						(effects
							(font
								(size 1.27 1.27)
							)
						)
					)
					(number "Y8"
						(effects
							(font
								(size 1.27 1.27)
							)
						)
					)
				)
				(pin power_in line
					(at 50.8 -43.18 180)
					(length 5.08)
					(name "AVSS"
						(effects
							(font
								(size 1.27 1.27)
							)
						)
					)
					(number "A21"
						(effects
							(font
								(size 1.27 1.27)
							)
						)
					)
				)
				(pin passive line
					(at 50.8 -43.18 180)
					(length 5.08)
					(hide yes)
					(name "AVSS"
						(effects
							(font
								(size 1.27 1.27)
							)
						)
					)
					(number "A31"
						(effects
							(font
								(size 1.27 1.27)
							)
						)
					)
				)
				(pin passive line
					(at 50.8 -43.18 180)
					(length 5.08)
					(hide yes)
					(name "AVSS"
						(effects
							(font
								(size 1.27 1.27)
							)
						)
					)
					(number "B22"
						(effects
							(font
								(size 1.27 1.27)
							)
						)
					)
				)
				(pin passive line
					(at 50.8 -43.18 180)
					(length 5.08)
					(hide yes)
					(name "AVSS"
						(effects
							(font
								(size 1.27 1.27)
							)
						)
					)
					(number "B32"
						(effects
							(font
								(size 1.27 1.27)
							)
						)
					)
				)
				(pin passive line
					(at 50.8 -43.18 180)
					(length 5.08)
					(hide yes)
					(name "AVSS"
						(effects
							(font
								(size 1.27 1.27)
							)
						)
					)
					(number "C31"
						(effects
							(font
								(size 1.27 1.27)
							)
						)
					)
				)
				(pin passive line
					(at 50.8 -43.18 180)
					(length 5.08)
					(hide yes)
					(name "AVSS"
						(effects
							(font
								(size 1.27 1.27)
							)
						)
					)
					(number "C41"
						(effects
							(font
								(size 1.27 1.27)
							)
						)
					)
				)
				(pin passive line
					(at 50.8 -43.18 180)
					(length 5.08)
					(hide yes)
					(name "AVSS"
						(effects
							(font
								(size 1.27 1.27)
							)
						)
					)
					(number "D24"
						(effects
							(font
								(size 1.27 1.27)
							)
						)
					)
				)
				(pin passive line
					(at 50.8 -43.18 180)
					(length 5.08)
					(hide yes)
					(name "AVSS"
						(effects
							(font
								(size 1.27 1.27)
							)
						)
					)
					(number "D26"
						(effects
							(font
								(size 1.27 1.27)
							)
						)
					)
				)
				(pin passive line
					(at 50.8 -43.18 180)
					(length 5.08)
					(hide yes)
					(name "AVSS"
						(effects
							(font
								(size 1.27 1.27)
							)
						)
					)
					(number "D28"
						(effects
							(font
								(size 1.27 1.27)
							)
						)
					)
				)
				(pin passive line
					(at 50.8 -43.18 180)
					(length 5.08)
					(hide yes)
					(name "AVSS"
						(effects
							(font
								(size 1.27 1.27)
							)
						)
					)
					(number "D36"
						(effects
							(font
								(size 1.27 1.27)
							)
						)
					)
				)
				(pin passive line
					(at 50.8 -43.18 180)
					(length 5.08)
					(hide yes)
					(name "AVSS"
						(effects
							(font
								(size 1.27 1.27)
							)
						)
					)
					(number "D38"
						(effects
							(font
								(size 1.27 1.27)
							)
						)
					)
				)
				(pin passive line
					(at 50.8 -43.18 180)
					(length 5.08)
					(hide yes)
					(name "AVSS"
						(effects
							(font
								(size 1.27 1.27)
							)
						)
					)
					(number "D40"
						(effects
							(font
								(size 1.27 1.27)
							)
						)
					)
				)
				(pin passive line
					(at 50.8 -43.18 180)
					(length 5.08)
					(hide yes)
					(name "AVSS"
						(effects
							(font
								(size 1.27 1.27)
							)
						)
					)
					(number "E31"
						(effects
							(font
								(size 1.27 1.27)
							)
						)
					)
				)
				(pin passive line
					(at 50.8 -43.18 180)
					(length 5.08)
					(hide yes)
					(name "AVSS"
						(effects
							(font
								(size 1.27 1.27)
							)
						)
					)
					(number "E33"
						(effects
							(font
								(size 1.27 1.27)
							)
						)
					)
				)
				(pin passive line
					(at 50.8 -43.18 180)
					(length 5.08)
					(hide yes)
					(name "AVSS"
						(effects
							(font
								(size 1.27 1.27)
							)
						)
					)
					(number "F40"
						(effects
							(font
								(size 1.27 1.27)
							)
						)
					)
				)
				(pin passive line
					(at 50.8 -43.18 180)
					(length 5.08)
					(hide yes)
					(name "AVSS"
						(effects
							(font
								(size 1.27 1.27)
							)
						)
					)
					(number "F42"
						(effects
							(font
								(size 1.27 1.27)
							)
						)
					)
				)
				(pin passive line
					(at 50.8 -43.18 180)
					(length 5.08)
					(hide yes)
					(name "AVSS"
						(effects
							(font
								(size 1.27 1.27)
							)
						)
					)
					(number "G41"
						(effects
							(font
								(size 1.27 1.27)
							)
						)
					)
				)
				(pin power_in line
					(at 50.8 -45.72 180)
					(length 5.08)
					(name "RSVDW3_VSS"
						(effects
							(font
								(size 1.27 1.27)
							)
						)
					)
					(number "W3"
						(effects
							(font
								(size 1.27 1.27)
							)
						)
					)
				)
				(pin power_in line
					(at 50.8 -48.26 180)
					(length 5.08)
					(name "VSS_SVR"
						(effects
							(font
								(size 1.27 1.27)
							)
						)
					)
					(number "U1"
						(effects
							(font
								(size 1.27 1.27)
							)
						)
					)
				)
				(pin power_in line
					(at 50.8 -50.8 180)
					(length 5.08)
					(name "VSS_S"
						(effects
							(font
								(size 1.27 1.27)
							)
						)
					)
					(number "Y2"
						(effects
							(font
								(size 1.27 1.27)
							)
						)
					)
				)
				(pin power_in line
					(at 50.8 -53.34 180)
					(length 5.08)
					(name "VSS"
						(effects
							(font
								(size 1.27 1.27)
							)
						)
					)
					(number "F24"
						(effects
							(font
								(size 1.27 1.27)
							)
						)
					)
				)
				(pin passive line
					(at 50.8 -53.34 180)
					(length 5.08)
					(hide yes)
					(name "VSS"
						(effects
							(font
								(size 1.27 1.27)
							)
						)
					)
					(number "F26"
						(effects
							(font
								(size 1.27 1.27)
							)
						)
					)
				)
				(pin passive line
					(at 50.8 -53.34 180)
					(length 5.08)
					(hide yes)
					(name "VSS"
						(effects
							(font
								(size 1.27 1.27)
							)
						)
					)
					(number "F28"
						(effects
							(font
								(size 1.27 1.27)
							)
						)
					)
				)
				(pin passive line
					(at 50.8 -53.34 180)
					(length 5.08)
					(hide yes)
					(name "VSS"
						(effects
							(font
								(size 1.27 1.27)
							)
						)
					)
					(number "F30"
						(effects
							(font
								(size 1.27 1.27)
							)
						)
					)
				)
				(pin passive line
					(at 50.8 -53.34 180)
					(length 5.08)
					(hide yes)
					(name "VSS"
						(effects
							(font
								(size 1.27 1.27)
							)
						)
					)
					(number "F32"
						(effects
							(font
								(size 1.27 1.27)
							)
						)
					)
				)
				(pin passive line
					(at 50.8 -53.34 180)
					(length 5.08)
					(hide yes)
					(name "VSS"
						(effects
							(font
								(size 1.27 1.27)
							)
						)
					)
					(number "F34"
						(effects
							(font
								(size 1.27 1.27)
							)
						)
					)
				)
				(pin passive line
					(at 50.8 -53.34 180)
					(length 5.08)
					(hide yes)
					(name "VSS"
						(effects
							(font
								(size 1.27 1.27)
							)
						)
					)
					(number "F36"
						(effects
							(font
								(size 1.27 1.27)
							)
						)
					)
				)
				(pin passive line
					(at 50.8 -53.34 180)
					(length 5.08)
					(hide yes)
					(name "VSS"
						(effects
							(font
								(size 1.27 1.27)
							)
						)
					)
					(number "K18"
						(effects
							(font
								(size 1.27 1.27)
							)
						)
					)
				)
				(pin passive line
					(at 50.8 -53.34 180)
					(length 5.08)
					(hide yes)
					(name "VSS"
						(effects
							(font
								(size 1.27 1.27)
							)
						)
					)
					(number "K20"
						(effects
							(font
								(size 1.27 1.27)
							)
						)
					)
				)
				(pin passive line
					(at 50.8 -53.34 180)
					(length 5.08)
					(hide yes)
					(name "VSS"
						(effects
							(font
								(size 1.27 1.27)
							)
						)
					)
					(number "M18"
						(effects
							(font
								(size 1.27 1.27)
							)
						)
					)
				)
				(pin passive line
					(at 50.8 -53.34 180)
					(length 5.08)
					(hide yes)
					(name "VSS"
						(effects
							(font
								(size 1.27 1.27)
							)
						)
					)
					(number "M20"
						(effects
							(font
								(size 1.27 1.27)
							)
						)
					)
				)
				(pin passive line
					(at 50.8 -53.34 180)
					(length 5.08)
					(hide yes)
					(name "VSS"
						(effects
							(font
								(size 1.27 1.27)
							)
						)
					)
					(number "P10"
						(effects
							(font
								(size 1.27 1.27)
							)
						)
					)
				)
				(pin passive line
					(at 50.8 -53.34 180)
					(length 5.08)
					(hide yes)
					(name "VSS"
						(effects
							(font
								(size 1.27 1.27)
							)
						)
					)
					(number "P12"
						(effects
							(font
								(size 1.27 1.27)
							)
						)
					)
				)
				(pin passive line
					(at 50.8 -53.34 180)
					(length 5.08)
					(hide yes)
					(name "VSS"
						(effects
							(font
								(size 1.27 1.27)
							)
						)
					)
					(number "P14"
						(effects
							(font
								(size 1.27 1.27)
							)
						)
					)
				)
				(pin passive line
					(at 50.8 -53.34 180)
					(length 5.08)
					(hide yes)
					(name "VSS"
						(effects
							(font
								(size 1.27 1.27)
							)
						)
					)
					(number "P16"
						(effects
							(font
								(size 1.27 1.27)
							)
						)
					)
				)
				(pin passive line
					(at 50.8 -53.34 180)
					(length 5.08)
					(hide yes)
					(name "VSS"
						(effects
							(font
								(size 1.27 1.27)
							)
						)
					)
					(number "P18"
						(effects
							(font
								(size 1.27 1.27)
							)
						)
					)
				)
				(pin passive line
					(at 50.8 -53.34 180)
					(length 5.08)
					(hide yes)
					(name "VSS"
						(effects
							(font
								(size 1.27 1.27)
							)
						)
					)
					(number "P20"
						(effects
							(font
								(size 1.27 1.27)
							)
						)
					)
				)
				(pin passive line
					(at 50.8 -53.34 180)
					(length 5.08)
					(hide yes)
					(name "VSS"
						(effects
							(font
								(size 1.27 1.27)
							)
						)
					)
					(number "R35"
						(effects
							(font
								(size 1.27 1.27)
							)
						)
					)
				)
				(pin passive line
					(at 50.8 -53.34 180)
					(length 5.08)
					(hide yes)
					(name "VSS"
						(effects
							(font
								(size 1.27 1.27)
							)
						)
					)
					(number "T10"
						(effects
							(font
								(size 1.27 1.27)
							)
						)
					)
				)
				(pin passive line
					(at 50.8 -53.34 180)
					(length 5.08)
					(hide yes)
					(name "VSS"
						(effects
							(font
								(size 1.27 1.27)
							)
						)
					)
					(number "T12"
						(effects
							(font
								(size 1.27 1.27)
							)
						)
					)
				)
				(pin passive line
					(at 50.8 -53.34 180)
					(length 5.08)
					(hide yes)
					(name "VSS"
						(effects
							(font
								(size 1.27 1.27)
							)
						)
					)
					(number "T14"
						(effects
							(font
								(size 1.27 1.27)
							)
						)
					)
				)
				(pin passive line
					(at 50.8 -53.34 180)
					(length 5.08)
					(hide yes)
					(name "VSS"
						(effects
							(font
								(size 1.27 1.27)
							)
						)
					)
					(number "T16"
						(effects
							(font
								(size 1.27 1.27)
							)
						)
					)
				)
				(pin passive line
					(at 50.8 -53.34 180)
					(length 5.08)
					(hide yes)
					(name "VSS"
						(effects
							(font
								(size 1.27 1.27)
							)
						)
					)
					(number "T18"
						(effects
							(font
								(size 1.27 1.27)
							)
						)
					)
				)
				(pin passive line
					(at 50.8 -53.34 180)
					(length 5.08)
					(hide yes)
					(name "VSS"
						(effects
							(font
								(size 1.27 1.27)
							)
						)
					)
					(number "T20"
						(effects
							(font
								(size 1.27 1.27)
							)
						)
					)
				)
			)
		)
	(symbol "antmicroInterfaceControllers:JHL6340SLLSQ"
			(exclude_from_sim no)
			(in_bom yes)
			(on_board yes)
			(property "Reference" "U"
				(at 71.12 0 0)
				(effects
					(font
						(size 1.27 1.27)
						(thickness 0.15)
					)
					(justify left bottom)
				)
			)
			(property "Value" "JHL6340SLLSQ"
				(at 71.12 -2.54 0)
				(effects
					(font
						(size 1.27 1.27)
						(thickness 0.15)
					)
					(justify left bottom)
					(hide yes)
				)
			)
			(property "Footprint" "antmicro-footprints:JHL6340SLLSQ"
				(at 71.12 -5.08 0)
				(effects
					(font
						(size 1.27 1.27)
						(thickness 0.15)
					)
					(justify left bottom)
					(hide yes)
				)
			)
			(property "Datasheet" "https://www.thunderbolttechnology.net/sites/default/files/18-241_ThunderboltController_Brief_HI.pdf"
				(at 71.12 -7.62 0)
				(effects
					(font
						(size 1.27 1.27)
						(thickness 0.15)
					)
					(justify left bottom)
					(hide yes)
				)
			)
			(property "Description" "Thunderbolt™ 3 Controller, I/O"
				(at 71.12 -20.32 0)
				(effects
					(font
						(size 1.27 1.27)
					)
					(justify left bottom)
					(hide yes)
				)
			)
			(property "Manufacturer" "Intel"
				(at 71.12 -10.16 0)
				(effects
					(font
						(size 1.27 1.27)
						(thickness 0.15)
					)
					(justify left bottom)
					(hide yes)
				)
			)
			(property "MPN" "JHL6340SLLSQ"
				(at 71.12 -12.7 0)
				(effects
					(font
						(size 1.27 1.27)
						(thickness 0.15)
					)
					(justify left bottom)
				)
			)
			(property "Author" "Antmicro"
				(at 71.12 -15.24 0)
				(effects
					(font
						(size 1.27 1.27)
						(thickness 0.15)
					)
					(justify left bottom)
					(hide yes)
				)
			)
			(property "License" "Apache-2.0"
				(at 71.12 -17.78 0)
				(effects
					(font
						(size 1.27 1.27)
						(thickness 0.15)
					)
					(justify left bottom)
					(hide yes)
				)
			)
			(property "ki_locked" ""
				(at 0 0 0)
				(effects
					(font
						(size 1.27 1.27)
					)
				)
			)
			(property "ki_keywords" "IC"
				(at 0 0 0)
				(effects
					(font
						(size 1.27 1.27)
					)
					(hide yes)
				)
			)
			(symbol "JHL6340SLLSQ_1_0"
				(rectangle
					(start 5.08 3.81)
					(end 49.53 -85.09)
					(stroke
						(width 0.254)
						(type default)
					)
					(fill
						(type background)
					)
				)
			)
			(symbol "JHL6340SLLSQ_1_1"
				(pin power_in line
					(at 0 0 0)
					(length 5.08)
					(name "VCC0P9_DP"
						(effects
							(font
								(size 1.27 1.27)
							)
						)
					)
					(number "L11"
						(effects
							(font
								(size 1.27 1.27)
							)
						)
					)
				)
				(pin passive line
					(at 0 0 0)
					(length 5.08)
					(hide yes)
					(name "VCC0P9_DP"
						(effects
							(font
								(size 1.27 1.27)
							)
						)
					)
					(number "L12"
						(effects
							(font
								(size 1.27 1.27)
							)
						)
					)
				)
				(pin passive line
					(at 0 0 0)
					(length 5.08)
					(hide yes)
					(name "VCC0P9_DP"
						(effects
							(font
								(size 1.27 1.27)
							)
						)
					)
					(number "L8"
						(effects
							(font
								(size 1.27 1.27)
							)
						)
					)
				)
				(pin passive line
					(at 0 0 0)
					(length 5.08)
					(hide yes)
					(name "VCC0P9_DP"
						(effects
							(font
								(size 1.27 1.27)
							)
						)
					)
					(number "M8"
						(effects
							(font
								(size 1.27 1.27)
							)
						)
					)
				)
				(pin passive line
					(at 0 0 0)
					(length 5.08)
					(hide yes)
					(name "VCC0P9_DP"
						(effects
							(font
								(size 1.27 1.27)
							)
						)
					)
					(number "T11"
						(effects
							(font
								(size 1.27 1.27)
							)
						)
					)
				)
				(pin passive line
					(at 0 0 0)
					(length 5.08)
					(hide yes)
					(name "VCC0P9_DP"
						(effects
							(font
								(size 1.27 1.27)
							)
						)
					)
					(number "T12"
						(effects
							(font
								(size 1.27 1.27)
							)
						)
					)
				)
				(pin power_in line
					(at 0 -2.54 0)
					(length 5.08)
					(name "VCC0P9_ANA_DPSRC"
						(effects
							(font
								(size 1.27 1.27)
							)
						)
					)
					(number "L6"
						(effects
							(font
								(size 1.27 1.27)
							)
						)
					)
				)
				(pin passive line
					(at 0 -2.54 0)
					(length 5.08)
					(hide yes)
					(name "VCC0P9_ANA_DPSRC"
						(effects
							(font
								(size 1.27 1.27)
							)
						)
					)
					(number "M6"
						(effects
							(font
								(size 1.27 1.27)
							)
						)
					)
				)
				(pin power_in line
					(at 0 -5.08 0)
					(length 5.08)
					(name "VCC0P9_ANA_DPSNK"
						(effects
							(font
								(size 1.27 1.27)
							)
						)
					)
					(number "V11"
						(effects
							(font
								(size 1.27 1.27)
							)
						)
					)
				)
				(pin passive line
					(at 0 -5.08 0)
					(length 5.08)
					(hide yes)
					(name "VCC0P9_ANA_DPSNK"
						(effects
							(font
								(size 1.27 1.27)
							)
						)
					)
					(number "V12"
						(effects
							(font
								(size 1.27 1.27)
							)
						)
					)
				)
				(pin passive line
					(at 0 -5.08 0)
					(length 5.08)
					(hide yes)
					(name "VCC0P9_ANA_DPSNK"
						(effects
							(font
								(size 1.27 1.27)
							)
						)
					)
					(number "V13"
						(effects
							(font
								(size 1.27 1.27)
							)
						)
					)
				)
				(pin power_in line
					(at 0 -17.78 0)
					(length 5.08)
					(name "VCC0P9_PCIE"
						(effects
							(font
								(size 1.27 1.27)
							)
						)
					)
					(number "M13"
						(effects
							(font
								(size 1.27 1.27)
							)
						)
					)
				)
				(pin passive line
					(at 0 -17.78 0)
					(length 5.08)
					(hide yes)
					(name "VCC0P9_PCIE"
						(effects
							(font
								(size 1.27 1.27)
							)
						)
					)
					(number "M15"
						(effects
							(font
								(size 1.27 1.27)
							)
						)
					)
				)
				(pin passive line
					(at 0 -17.78 0)
					(length 5.08)
					(hide yes)
					(name "VCC0P9_PCIE"
						(effects
							(font
								(size 1.27 1.27)
							)
						)
					)
					(number "M16"
						(effects
							(font
								(size 1.27 1.27)
							)
						)
					)
				)
				(pin power_in line
					(at 0 -20.32 0)
					(length 5.08)
					(name "VCC0P9_ANA_PCIE_1"
						(effects
							(font
								(size 1.27 1.27)
							)
						)
					)
					(number "L19"
						(effects
							(font
								(size 1.27 1.27)
							)
						)
					)
				)
				(pin passive line
					(at 0 -20.32 0)
					(length 5.08)
					(hide yes)
					(name "VCC0P9_ANA_PCIE_1"
						(effects
							(font
								(size 1.27 1.27)
							)
						)
					)
					(number "N19"
						(effects
							(font
								(size 1.27 1.27)
							)
						)
					)
				)
				(pin power_in line
					(at 0 -22.86 0)
					(length 5.08)
					(name "VCC0P9_ANA_PCIE_2"
						(effects
							(font
								(size 1.27 1.27)
							)
						)
					)
					(number "L18"
						(effects
							(font
								(size 1.27 1.27)
							)
						)
					)
				)
				(pin passive line
					(at 0 -22.86 0)
					(length 5.08)
					(hide yes)
					(name "VCC0P9_ANA_PCIE_2"
						(effects
							(font
								(size 1.27 1.27)
							)
						)
					)
					(number "M18"
						(effects
							(font
								(size 1.27 1.27)
							)
						)
					)
				)
				(pin passive line
					(at 0 -22.86 0)
					(length 5.08)
					(hide yes)
					(name "VCC0P9_ANA_PCIE_2"
						(effects
							(font
								(size 1.27 1.27)
							)
						)
					)
					(number "N18"
						(effects
							(font
								(size 1.27 1.27)
							)
						)
					)
				)
				(pin power_in line
					(at 0 -35.56 0)
					(length 5.08)
					(name "VCC0P9_USB"
						(effects
							(font
								(size 1.27 1.27)
							)
						)
					)
					(number "R15"
						(effects
							(font
								(size 1.27 1.27)
							)
						)
					)
				)
				(pin passive line
					(at 0 -35.56 0)
					(length 5.08)
					(hide yes)
					(name "VCC0P9_USB"
						(effects
							(font
								(size 1.27 1.27)
							)
						)
					)
					(number "R16"
						(effects
							(font
								(size 1.27 1.27)
							)
						)
					)
				)
				(pin power_in line
					(at 0 -53.34 0)
					(length 5.08)
					(name "VCC0P9_CIO"
						(effects
							(font
								(size 1.27 1.27)
							)
						)
					)
					(number "R11"
						(effects
							(font
								(size 1.27 1.27)
							)
						)
					)
				)
				(pin passive line
					(at 0 -53.34 0)
					(length 5.08)
					(hide yes)
					(name "VCC0P9_CIO"
						(effects
							(font
								(size 1.27 1.27)
							)
						)
					)
					(number "R12"
						(effects
							(font
								(size 1.27 1.27)
							)
						)
					)
				)
				(pin passive line
					(at 0 -53.34 0)
					(length 5.08)
					(hide yes)
					(name "VCC0P9_CIO"
						(effects
							(font
								(size 1.27 1.27)
							)
						)
					)
					(number "R8"
						(effects
							(font
								(size 1.27 1.27)
							)
						)
					)
				)
				(pin passive line
					(at 0 -53.34 0)
					(length 5.08)
					(hide yes)
					(name "VCC0P9_CIO"
						(effects
							(font
								(size 1.27 1.27)
							)
						)
					)
					(number "R9"
						(effects
							(font
								(size 1.27 1.27)
							)
						)
					)
				)
				(pin power_in line
					(at 0 -71.12 0)
					(length 5.08)
					(name "VCC3P3_ANA_PCIE"
						(effects
							(font
								(size 1.27 1.27)
							)
						)
					)
					(number "L16"
						(effects
							(font
								(size 1.27 1.27)
							)
						)
					)
				)
				(pin power_in line
					(at 0 -73.66 0)
					(length 5.08)
					(name "VCC3P3_ANA_USB2"
						(effects
							(font
								(size 1.27 1.27)
							)
						)
					)
					(number "J16"
						(effects
							(font
								(size 1.27 1.27)
							)
						)
					)
				)
				(pin passive line
					(at 0 -81.28 0)
					(length 5.08)
					(name "VSS_ANA"
						(effects
							(font
								(size 1.27 1.27)
							)
						)
					)
					(number "A10"
						(effects
							(font
								(size 1.27 1.27)
							)
						)
					)
				)
				(pin passive line
					(at 0 -81.28 0)
					(length 5.08)
					(hide yes)
					(name "VSS_ANA"
						(effects
							(font
								(size 1.27 1.27)
							)
						)
					)
					(number "A12"
						(effects
							(font
								(size 1.27 1.27)
							)
						)
					)
				)
				(pin passive line
					(at 0 -81.28 0)
					(length 5.08)
					(hide yes)
					(name "VSS_ANA"
						(effects
							(font
								(size 1.27 1.27)
							)
						)
					)
					(number "A14"
						(effects
							(font
								(size 1.27 1.27)
							)
						)
					)
				)
				(pin passive line
					(at 0 -81.28 0)
					(length 5.08)
					(hide yes)
					(name "VSS_ANA"
						(effects
							(font
								(size 1.27 1.27)
							)
						)
					)
					(number "A16"
						(effects
							(font
								(size 1.27 1.27)
							)
						)
					)
				)
				(pin passive line
					(at 0 -81.28 0)
					(length 5.08)
					(hide yes)
					(name "VSS_ANA"
						(effects
							(font
								(size 1.27 1.27)
							)
						)
					)
					(number "A18"
						(effects
							(font
								(size 1.27 1.27)
							)
						)
					)
				)
				(pin passive line
					(at 0 -81.28 0)
					(length 5.08)
					(hide yes)
					(name "VSS_ANA"
						(effects
							(font
								(size 1.27 1.27)
							)
						)
					)
					(number "A20"
						(effects
							(font
								(size 1.27 1.27)
							)
						)
					)
				)
				(pin passive line
					(at 0 -81.28 0)
					(length 5.08)
					(hide yes)
					(name "VSS_ANA"
						(effects
							(font
								(size 1.27 1.27)
							)
						)
					)
					(number "A22"
						(effects
							(font
								(size 1.27 1.27)
							)
						)
					)
				)
				(pin passive line
					(at 0 -81.28 0)
					(length 5.08)
					(hide yes)
					(name "VSS_ANA"
						(effects
							(font
								(size 1.27 1.27)
							)
						)
					)
					(number "A6"
						(effects
							(font
								(size 1.27 1.27)
							)
						)
					)
				)
				(pin passive line
					(at 0 -81.28 0)
					(length 5.08)
					(hide yes)
					(name "VSS_ANA"
						(effects
							(font
								(size 1.27 1.27)
							)
						)
					)
					(number "A8"
						(effects
							(font
								(size 1.27 1.27)
							)
						)
					)
				)
				(pin passive line
					(at 0 -81.28 0)
					(length 5.08)
					(hide yes)
					(name "VSS_ANA"
						(effects
							(font
								(size 1.27 1.27)
							)
						)
					)
					(number "AA22"
						(effects
							(font
								(size 1.27 1.27)
							)
						)
					)
				)
				(pin passive line
					(at 0 -81.28 0)
					(length 5.08)
					(hide yes)
					(name "VSS_ANA"
						(effects
							(font
								(size 1.27 1.27)
							)
						)
					)
					(number "AA23"
						(effects
							(font
								(size 1.27 1.27)
							)
						)
					)
				)
				(pin passive line
					(at 0 -81.28 0)
					(length 5.08)
					(hide yes)
					(name "VSS_ANA"
						(effects
							(font
								(size 1.27 1.27)
							)
						)
					)
					(number "AB10"
						(effects
							(font
								(size 1.27 1.27)
							)
						)
					)
				)
				(pin passive line
					(at 0 -81.28 0)
					(length 5.08)
					(hide yes)
					(name "VSS_ANA"
						(effects
							(font
								(size 1.27 1.27)
							)
						)
					)
					(number "AB12"
						(effects
							(font
								(size 1.27 1.27)
							)
						)
					)
				)
				(pin passive line
					(at 0 -81.28 0)
					(length 5.08)
					(hide yes)
					(name "VSS_ANA"
						(effects
							(font
								(size 1.27 1.27)
							)
						)
					)
					(number "AB14"
						(effects
							(font
								(size 1.27 1.27)
							)
						)
					)
				)
				(pin passive line
					(at 0 -81.28 0)
					(length 5.08)
					(hide yes)
					(name "VSS_ANA"
						(effects
							(font
								(size 1.27 1.27)
							)
						)
					)
					(number "AB16"
						(effects
							(font
								(size 1.27 1.27)
							)
						)
					)
				)
				(pin passive line
					(at 0 -81.28 0)
					(length 5.08)
					(hide yes)
					(name "VSS_ANA"
						(effects
							(font
								(size 1.27 1.27)
							)
						)
					)
					(number "AB18"
						(effects
							(font
								(size 1.27 1.27)
							)
						)
					)
				)
				(pin passive line
					(at 0 -81.28 0)
					(length 5.08)
					(hide yes)
					(name "VSS_ANA"
						(effects
							(font
								(size 1.27 1.27)
							)
						)
					)
					(number "AB20"
						(effects
							(font
								(size 1.27 1.27)
							)
						)
					)
				)
				(pin passive line
					(at 0 -81.28 0)
					(length 5.08)
					(hide yes)
					(name "VSS_ANA"
						(effects
							(font
								(size 1.27 1.27)
							)
						)
					)
					(number "AB22"
						(effects
							(font
								(size 1.27 1.27)
							)
						)
					)
				)
				(pin passive line
					(at 0 -81.28 0)
					(length 5.08)
					(hide yes)
					(name "VSS_ANA"
						(effects
							(font
								(size 1.27 1.27)
							)
						)
					)
					(number "AB6"
						(effects
							(font
								(size 1.27 1.27)
							)
						)
					)
				)
				(pin passive line
					(at 0 -81.28 0)
					(length 5.08)
					(hide yes)
					(name "VSS_ANA"
						(effects
							(font
								(size 1.27 1.27)
							)
						)
					)
					(number "AB8"
						(effects
							(font
								(size 1.27 1.27)
							)
						)
					)
				)
				(pin passive line
					(at 0 -81.28 0)
					(length 5.08)
					(hide yes)
					(name "VSS_ANA"
						(effects
							(font
								(size 1.27 1.27)
							)
						)
					)
					(number "AC10"
						(effects
							(font
								(size 1.27 1.27)
							)
						)
					)
				)
				(pin passive line
					(at 0 -81.28 0)
					(length 5.08)
					(hide yes)
					(name "VSS_ANA"
						(effects
							(font
								(size 1.27 1.27)
							)
						)
					)
					(number "AC12"
						(effects
							(font
								(size 1.27 1.27)
							)
						)
					)
				)
				(pin passive line
					(at 0 -81.28 0)
					(length 5.08)
					(hide yes)
					(name "VSS_ANA"
						(effects
							(font
								(size 1.27 1.27)
							)
						)
					)
					(number "AC14"
						(effects
							(font
								(size 1.27 1.27)
							)
						)
					)
				)
				(pin passive line
					(at 0 -81.28 0)
					(length 5.08)
					(hide yes)
					(name "VSS_ANA"
						(effects
							(font
								(size 1.27 1.27)
							)
						)
					)
					(number "AC16"
						(effects
							(font
								(size 1.27 1.27)
							)
						)
					)
				)
				(pin passive line
					(at 0 -81.28 0)
					(length 5.08)
					(hide yes)
					(name "VSS_ANA"
						(effects
							(font
								(size 1.27 1.27)
							)
						)
					)
					(number "AC18"
						(effects
							(font
								(size 1.27 1.27)
							)
						)
					)
				)
				(pin passive line
					(at 0 -81.28 0)
					(length 5.08)
					(hide yes)
					(name "VSS_ANA"
						(effects
							(font
								(size 1.27 1.27)
							)
						)
					)
					(number "AC20"
						(effects
							(font
								(size 1.27 1.27)
							)
						)
					)
				)
				(pin passive line
					(at 0 -81.28 0)
					(length 5.08)
					(hide yes)
					(name "VSS_ANA"
						(effects
							(font
								(size 1.27 1.27)
							)
						)
					)
					(number "AC22"
						(effects
							(font
								(size 1.27 1.27)
							)
						)
					)
				)
				(pin passive line
					(at 0 -81.28 0)
					(length 5.08)
					(hide yes)
					(name "VSS_ANA"
						(effects
							(font
								(size 1.27 1.27)
							)
						)
					)
					(number "AC6"
						(effects
							(font
								(size 1.27 1.27)
							)
						)
					)
				)
				(pin passive line
					(at 0 -81.28 0)
					(length 5.08)
					(hide yes)
					(name "VSS_ANA"
						(effects
							(font
								(size 1.27 1.27)
							)
						)
					)
					(number "AC8"
						(effects
							(font
								(size 1.27 1.27)
							)
						)
					)
				)
				(pin passive line
					(at 0 -81.28 0)
					(length 5.08)
					(hide yes)
					(name "VSS_ANA"
						(effects
							(font
								(size 1.27 1.27)
							)
						)
					)
					(number "B10"
						(effects
							(font
								(size 1.27 1.27)
							)
						)
					)
				)
				(pin passive line
					(at 0 -81.28 0)
					(length 5.08)
					(hide yes)
					(name "VSS_ANA"
						(effects
							(font
								(size 1.27 1.27)
							)
						)
					)
					(number "B12"
						(effects
							(font
								(size 1.27 1.27)
							)
						)
					)
				)
				(pin passive line
					(at 0 -81.28 0)
					(length 5.08)
					(hide yes)
					(name "VSS_ANA"
						(effects
							(font
								(size 1.27 1.27)
							)
						)
					)
					(number "B14"
						(effects
							(font
								(size 1.27 1.27)
							)
						)
					)
				)
				(pin passive line
					(at 0 -81.28 0)
					(length 5.08)
					(hide yes)
					(name "VSS_ANA"
						(effects
							(font
								(size 1.27 1.27)
							)
						)
					)
					(number "B16"
						(effects
							(font
								(size 1.27 1.27)
							)
						)
					)
				)
				(pin passive line
					(at 0 -81.28 0)
					(length 5.08)
					(hide yes)
					(name "VSS_ANA"
						(effects
							(font
								(size 1.27 1.27)
							)
						)
					)
					(number "B18"
						(effects
							(font
								(size 1.27 1.27)
							)
						)
					)
				)
				(pin passive line
					(at 0 -81.28 0)
					(length 5.08)
					(hide yes)
					(name "VSS_ANA"
						(effects
							(font
								(size 1.27 1.27)
							)
						)
					)
					(number "B20"
						(effects
							(font
								(size 1.27 1.27)
							)
						)
					)
				)
				(pin passive line
					(at 0 -81.28 0)
					(length 5.08)
					(hide yes)
					(name "VSS_ANA"
						(effects
							(font
								(size 1.27 1.27)
							)
						)
					)
					(number "B22"
						(effects
							(font
								(size 1.27 1.27)
							)
						)
					)
				)
				(pin passive line
					(at 0 -81.28 0)
					(length 5.08)
					(hide yes)
					(name "VSS_ANA"
						(effects
							(font
								(size 1.27 1.27)
							)
						)
					)
					(number "B6"
						(effects
							(font
								(size 1.27 1.27)
							)
						)
					)
				)
				(pin passive line
					(at 0 -81.28 0)
					(length 5.08)
					(hide yes)
					(name "VSS_ANA"
						(effects
							(font
								(size 1.27 1.27)
							)
						)
					)
					(number "B8"
						(effects
							(font
								(size 1.27 1.27)
							)
						)
					)
				)
				(pin passive line
					(at 0 -81.28 0)
					(length 5.08)
					(hide yes)
					(name "VSS_ANA"
						(effects
							(font
								(size 1.27 1.27)
							)
						)
					)
					(number "D11"
						(effects
							(font
								(size 1.27 1.27)
							)
						)
					)
				)
				(pin passive line
					(at 0 -81.28 0)
					(length 5.08)
					(hide yes)
					(name "VSS_ANA"
						(effects
							(font
								(size 1.27 1.27)
							)
						)
					)
					(number "D12"
						(effects
							(font
								(size 1.27 1.27)
							)
						)
					)
				)
				(pin passive line
					(at 0 -81.28 0)
					(length 5.08)
					(hide yes)
					(name "VSS_ANA"
						(effects
							(font
								(size 1.27 1.27)
							)
						)
					)
					(number "D13"
						(effects
							(font
								(size 1.27 1.27)
							)
						)
					)
				)
				(pin passive line
					(at 0 -81.28 0)
					(length 5.08)
					(hide yes)
					(name "VSS_ANA"
						(effects
							(font
								(size 1.27 1.27)
							)
						)
					)
					(number "D15"
						(effects
							(font
								(size 1.27 1.27)
							)
						)
					)
				)
				(pin passive line
					(at 0 -81.28 0)
					(length 5.08)
					(hide yes)
					(name "VSS_ANA"
						(effects
							(font
								(size 1.27 1.27)
							)
						)
					)
					(number "D16"
						(effects
							(font
								(size 1.27 1.27)
							)
						)
					)
				)
				(pin passive line
					(at 0 -81.28 0)
					(length 5.08)
					(hide yes)
					(name "VSS_ANA"
						(effects
							(font
								(size 1.27 1.27)
							)
						)
					)
					(number "D18"
						(effects
							(font
								(size 1.27 1.27)
							)
						)
					)
				)
				(pin passive line
					(at 0 -81.28 0)
					(length 5.08)
					(hide yes)
					(name "VSS_ANA"
						(effects
							(font
								(size 1.27 1.27)
							)
						)
					)
					(number "D8"
						(effects
							(font
								(size 1.27 1.27)
							)
						)
					)
				)
				(pin passive line
					(at 0 -81.28 0)
					(length 5.08)
					(hide yes)
					(name "VSS_ANA"
						(effects
							(font
								(size 1.27 1.27)
							)
						)
					)
					(number "D9"
						(effects
							(font
								(size 1.27 1.27)
							)
						)
					)
				)
				(pin passive line
					(at 0 -81.28 0)
					(length 5.08)
					(hide yes)
					(name "VSS_ANA"
						(effects
							(font
								(size 1.27 1.27)
							)
						)
					)
					(number "E11"
						(effects
							(font
								(size 1.27 1.27)
							)
						)
					)
				)
				(pin passive line
					(at 0 -81.28 0)
					(length 5.08)
					(hide yes)
					(name "VSS_ANA"
						(effects
							(font
								(size 1.27 1.27)
							)
						)
					)
					(number "E15"
						(effects
							(font
								(size 1.27 1.27)
							)
						)
					)
				)
				(pin passive line
					(at 0 -81.28 0)
					(length 5.08)
					(hide yes)
					(name "VSS_ANA"
						(effects
							(font
								(size 1.27 1.27)
							)
						)
					)
					(number "E16"
						(effects
							(font
								(size 1.27 1.27)
							)
						)
					)
				)
				(pin passive line
					(at 0 -81.28 0)
					(length 5.08)
					(hide yes)
					(name "VSS_ANA"
						(effects
							(font
								(size 1.27 1.27)
							)
						)
					)
					(number "E22"
						(effects
							(font
								(size 1.27 1.27)
							)
						)
					)
				)
				(pin passive line
					(at 0 -81.28 0)
					(length 5.08)
					(hide yes)
					(name "VSS_ANA"
						(effects
							(font
								(size 1.27 1.27)
							)
						)
					)
					(number "E23"
						(effects
							(font
								(size 1.27 1.27)
							)
						)
					)
				)
				(pin passive line
					(at 0 -81.28 0)
					(length 5.08)
					(hide yes)
					(name "VSS_ANA"
						(effects
							(font
								(size 1.27 1.27)
							)
						)
					)
					(number "E8"
						(effects
							(font
								(size 1.27 1.27)
							)
						)
					)
				)
				(pin passive line
					(at 0 -81.28 0)
					(length 5.08)
					(hide yes)
					(name "VSS_ANA"
						(effects
							(font
								(size 1.27 1.27)
							)
						)
					)
					(number "E9"
						(effects
							(font
								(size 1.27 1.27)
							)
						)
					)
				)
				(pin passive line
					(at 0 -81.28 0)
					(length 5.08)
					(hide yes)
					(name "VSS_ANA"
						(effects
							(font
								(size 1.27 1.27)
							)
						)
					)
					(number "F16"
						(effects
							(font
								(size 1.27 1.27)
							)
						)
					)
				)
				(pin passive line
					(at 0 -81.28 0)
					(length 5.08)
					(hide yes)
					(name "VSS_ANA"
						(effects
							(font
								(size 1.27 1.27)
							)
						)
					)
					(number "F20"
						(effects
							(font
								(size 1.27 1.27)
							)
						)
					)
				)
				(pin passive line
					(at 0 -81.28 0)
					(length 5.08)
					(hide yes)
					(name "VSS_ANA"
						(effects
							(font
								(size 1.27 1.27)
							)
						)
					)
					(number "F9"
						(effects
							(font
								(size 1.27 1.27)
							)
						)
					)
				)
				(pin passive line
					(at 0 -81.28 0)
					(length 5.08)
					(hide yes)
					(name "VSS_ANA"
						(effects
							(font
								(size 1.27 1.27)
							)
						)
					)
					(number "G22"
						(effects
							(font
								(size 1.27 1.27)
							)
						)
					)
				)
				(pin passive line
					(at 0 -81.28 0)
					(length 5.08)
					(hide yes)
					(name "VSS_ANA"
						(effects
							(font
								(size 1.27 1.27)
							)
						)
					)
					(number "G23"
						(effects
							(font
								(size 1.27 1.27)
							)
						)
					)
				)
				(pin passive line
					(at 0 -81.28 0)
					(length 5.08)
					(hide yes)
					(name "VSS_ANA"
						(effects
							(font
								(size 1.27 1.27)
							)
						)
					)
					(number "H1"
						(effects
							(font
								(size 1.27 1.27)
							)
						)
					)
				)
				(pin passive line
					(at 0 -81.28 0)
					(length 5.08)
					(hide yes)
					(name "VSS_ANA"
						(effects
							(font
								(size 1.27 1.27)
							)
						)
					)
					(number "H12"
						(effects
							(font
								(size 1.27 1.27)
							)
						)
					)
				)
				(pin passive line
					(at 0 -81.28 0)
					(length 5.08)
					(hide yes)
					(name "VSS_ANA"
						(effects
							(font
								(size 1.27 1.27)
							)
						)
					)
					(number "H13"
						(effects
							(font
								(size 1.27 1.27)
							)
						)
					)
				)
				(pin passive line
					(at 0 -81.28 0)
					(length 5.08)
					(hide yes)
					(name "VSS_ANA"
						(effects
							(font
								(size 1.27 1.27)
							)
						)
					)
					(number "H15"
						(effects
							(font
								(size 1.27 1.27)
							)
						)
					)
				)
				(pin passive line
					(at 0 -81.28 0)
					(length 5.08)
					(hide yes)
					(name "VSS_ANA"
						(effects
							(font
								(size 1.27 1.27)
							)
						)
					)
					(number "H16"
						(effects
							(font
								(size 1.27 1.27)
							)
						)
					)
				)
				(pin passive line
					(at 0 -81.28 0)
					(length 5.08)
					(hide yes)
					(name "VSS_ANA"
						(effects
							(font
								(size 1.27 1.27)
							)
						)
					)
					(number "H2"
						(effects
							(font
								(size 1.27 1.27)
							)
						)
					)
				)
				(pin passive line
					(at 0 -81.28 0)
					(length 5.08)
					(hide yes)
					(name "VSS_ANA"
						(effects
							(font
								(size 1.27 1.27)
							)
						)
					)
					(number "H20"
						(effects
							(font
								(size 1.27 1.27)
							)
						)
					)
				)
				(pin passive line
					(at 0 -81.28 0)
					(length 5.08)
					(hide yes)
					(name "VSS_ANA"
						(effects
							(font
								(size 1.27 1.27)
							)
						)
					)
					(number "J18"
						(effects
							(font
								(size 1.27 1.27)
							)
						)
					)
				)
				(pin passive line
					(at 0 -81.28 0)
					(length 5.08)
					(hide yes)
					(name "VSS_ANA"
						(effects
							(font
								(size 1.27 1.27)
							)
						)
					)
					(number "J19"
						(effects
							(font
								(size 1.27 1.27)
							)
						)
					)
				)
				(pin passive line
					(at 0 -81.28 0)
					(length 5.08)
					(hide yes)
					(name "VSS_ANA"
						(effects
							(font
								(size 1.27 1.27)
							)
						)
					)
					(number "J20"
						(effects
							(font
								(size 1.27 1.27)
							)
						)
					)
				)
				(pin passive line
					(at 0 -81.28 0)
					(length 5.08)
					(hide yes)
					(name "VSS_ANA"
						(effects
							(font
								(size 1.27 1.27)
							)
						)
					)
					(number "J22"
						(effects
							(font
								(size 1.27 1.27)
							)
						)
					)
				)
				(pin passive line
					(at 0 -81.28 0)
					(length 5.08)
					(hide yes)
					(name "VSS_ANA"
						(effects
							(font
								(size 1.27 1.27)
							)
						)
					)
					(number "J23"
						(effects
							(font
								(size 1.27 1.27)
							)
						)
					)
				)
				(pin passive line
					(at 0 -81.28 0)
					(length 5.08)
					(hide yes)
					(name "VSS_ANA"
						(effects
							(font
								(size 1.27 1.27)
							)
						)
					)
					(number "J5"
						(effects
							(font
								(size 1.27 1.27)
							)
						)
					)
				)
				(pin passive line
					(at 0 -81.28 0)
					(length 5.08)
					(hide yes)
					(name "VSS_ANA"
						(effects
							(font
								(size 1.27 1.27)
							)
						)
					)
					(number "K1"
						(effects
							(font
								(size 1.27 1.27)
							)
						)
					)
				)
				(pin passive line
					(at 0 -81.28 0)
					(length 5.08)
					(hide yes)
					(name "VSS_ANA"
						(effects
							(font
								(size 1.27 1.27)
							)
						)
					)
					(number "K2"
						(effects
							(font
								(size 1.27 1.27)
							)
						)
					)
				)
				(pin passive line
					(at 0 -81.28 0)
					(length 5.08)
					(hide yes)
					(name "VSS_ANA"
						(effects
							(font
								(size 1.27 1.27)
							)
						)
					)
					(number "L20"
						(effects
							(font
								(size 1.27 1.27)
							)
						)
					)
				)
				(pin passive line
					(at 0 -81.28 0)
					(length 5.08)
					(hide yes)
					(name "VSS_ANA"
						(effects
							(font
								(size 1.27 1.27)
							)
						)
					)
					(number "L22"
						(effects
							(font
								(size 1.27 1.27)
							)
						)
					)
				)
				(pin passive line
					(at 0 -81.28 0)
					(length 5.08)
					(hide yes)
					(name "VSS_ANA"
						(effects
							(font
								(size 1.27 1.27)
							)
						)
					)
					(number "L23"
						(effects
							(font
								(size 1.27 1.27)
							)
						)
					)
				)
				(pin passive line
					(at 0 -81.28 0)
					(length 5.08)
					(hide yes)
					(name "VSS_ANA"
						(effects
							(font
								(size 1.27 1.27)
							)
						)
					)
					(number "L5"
						(effects
							(font
								(size 1.27 1.27)
							)
						)
					)
				)
				(pin passive line
					(at 0 -81.28 0)
					(length 5.08)
					(hide yes)
					(name "VSS_ANA"
						(effects
							(font
								(size 1.27 1.27)
							)
						)
					)
					(number "M1"
						(effects
							(font
								(size 1.27 1.27)
							)
						)
					)
				)
				(pin passive line
					(at 0 -81.28 0)
					(length 5.08)
					(hide yes)
					(name "VSS_ANA"
						(effects
							(font
								(size 1.27 1.27)
							)
						)
					)
					(number "M19"
						(effects
							(font
								(size 1.27 1.27)
							)
						)
					)
				)
				(pin passive line
					(at 0 -81.28 0)
					(length 5.08)
					(hide yes)
					(name "VSS_ANA"
						(effects
							(font
								(size 1.27 1.27)
							)
						)
					)
					(number "M2"
						(effects
							(font
								(size 1.27 1.27)
							)
						)
					)
				)
				(pin passive line
					(at 0 -81.28 0)
					(length 5.08)
					(hide yes)
					(name "VSS_ANA"
						(effects
							(font
								(size 1.27 1.27)
							)
						)
					)
					(number "M20"
						(effects
							(font
								(size 1.27 1.27)
							)
						)
					)
				)
				(pin passive line
					(at 0 -81.28 0)
					(length 5.08)
					(hide yes)
					(name "VSS_ANA"
						(effects
							(font
								(size 1.27 1.27)
							)
						)
					)
					(number "M5"
						(effects
							(font
								(size 1.27 1.27)
							)
						)
					)
				)
				(pin passive line
					(at 0 -81.28 0)
					(length 5.08)
					(hide yes)
					(name "VSS_ANA"
						(effects
							(font
								(size 1.27 1.27)
							)
						)
					)
					(number "N20"
						(effects
							(font
								(size 1.27 1.27)
							)
						)
					)
				)
				(pin passive line
					(at 0 -81.28 0)
					(length 5.08)
					(hide yes)
					(name "VSS_ANA"
						(effects
							(font
								(size 1.27 1.27)
							)
						)
					)
					(number "N22"
						(effects
							(font
								(size 1.27 1.27)
							)
						)
					)
				)
				(pin passive line
					(at 0 -81.28 0)
					(length 5.08)
					(hide yes)
					(name "VSS_ANA"
						(effects
							(font
								(size 1.27 1.27)
							)
						)
					)
					(number "N23"
						(effects
							(font
								(size 1.27 1.27)
							)
						)
					)
				)
				(pin passive line
					(at 0 -81.28 0)
					(length 5.08)
					(hide yes)
					(name "VSS_ANA"
						(effects
							(font
								(size 1.27 1.27)
							)
						)
					)
					(number "N5"
						(effects
							(font
								(size 1.27 1.27)
							)
						)
					)
				)
				(pin passive line
					(at 0 -81.28 0)
					(length 5.08)
					(hide yes)
					(name "VSS_ANA"
						(effects
							(font
								(size 1.27 1.27)
							)
						)
					)
					(number "P1"
						(effects
							(font
								(size 1.27 1.27)
							)
						)
					)
				)
				(pin passive line
					(at 0 -81.28 0)
					(length 5.08)
					(hide yes)
					(name "VSS_ANA"
						(effects
							(font
								(size 1.27 1.27)
							)
						)
					)
					(number "P2"
						(effects
							(font
								(size 1.27 1.27)
							)
						)
					)
				)
				(pin passive line
					(at 0 -81.28 0)
					(length 5.08)
					(hide yes)
					(name "VSS_ANA"
						(effects
							(font
								(size 1.27 1.27)
							)
						)
					)
					(number "R18"
						(effects
							(font
								(size 1.27 1.27)
							)
						)
					)
				)
				(pin passive line
					(at 0 -81.28 0)
					(length 5.08)
					(hide yes)
					(name "VSS_ANA"
						(effects
							(font
								(size 1.27 1.27)
							)
						)
					)
					(number "R19"
						(effects
							(font
								(size 1.27 1.27)
							)
						)
					)
				)
				(pin passive line
					(at 0 -81.28 0)
					(length 5.08)
					(hide yes)
					(name "VSS_ANA"
						(effects
							(font
								(size 1.27 1.27)
							)
						)
					)
					(number "R20"
						(effects
							(font
								(size 1.27 1.27)
							)
						)
					)
				)
				(pin passive line
					(at 0 -81.28 0)
					(length 5.08)
					(hide yes)
					(name "VSS_ANA"
						(effects
							(font
								(size 1.27 1.27)
							)
						)
					)
					(number "R22"
						(effects
							(font
								(size 1.27 1.27)
							)
						)
					)
				)
				(pin passive line
					(at 0 -81.28 0)
					(length 5.08)
					(hide yes)
					(name "VSS_ANA"
						(effects
							(font
								(size 1.27 1.27)
							)
						)
					)
					(number "R23"
						(effects
							(font
								(size 1.27 1.27)
							)
						)
					)
				)
				(pin passive line
					(at 0 -81.28 0)
					(length 5.08)
					(hide yes)
					(name "VSS_ANA"
						(effects
							(font
								(size 1.27 1.27)
							)
						)
					)
					(number "R5"
						(effects
							(font
								(size 1.27 1.27)
							)
						)
					)
				)
				(pin passive line
					(at 0 -81.28 0)
					(length 5.08)
					(hide yes)
					(name "VSS_ANA"
						(effects
							(font
								(size 1.27 1.27)
							)
						)
					)
					(number "T1"
						(effects
							(font
								(size 1.27 1.27)
							)
						)
					)
				)
				(pin passive line
					(at 0 -81.28 0)
					(length 5.08)
					(hide yes)
					(name "VSS_ANA"
						(effects
							(font
								(size 1.27 1.27)
							)
						)
					)
					(number "T2"
						(effects
							(font
								(size 1.27 1.27)
							)
						)
					)
				)
				(pin passive line
					(at 0 -81.28 0)
					(length 5.08)
					(hide yes)
					(name "VSS_ANA"
						(effects
							(font
								(size 1.27 1.27)
							)
						)
					)
					(number "T20"
						(effects
							(font
								(size 1.27 1.27)
							)
						)
					)
				)
				(pin passive line
					(at 0 -81.28 0)
					(length 5.08)
					(hide yes)
					(name "VSS_ANA"
						(effects
							(font
								(size 1.27 1.27)
							)
						)
					)
					(number "T5"
						(effects
							(font
								(size 1.27 1.27)
							)
						)
					)
				)
				(pin passive line
					(at 0 -81.28 0)
					(length 5.08)
					(hide yes)
					(name "VSS_ANA"
						(effects
							(font
								(size 1.27 1.27)
							)
						)
					)
					(number "U22"
						(effects
							(font
								(size 1.27 1.27)
							)
						)
					)
				)
				(pin passive line
					(at 0 -81.28 0)
					(length 5.08)
					(hide yes)
					(name "VSS_ANA"
						(effects
							(font
								(size 1.27 1.27)
							)
						)
					)
					(number "U23"
						(effects
							(font
								(size 1.27 1.27)
							)
						)
					)
				)
				(pin passive line
					(at 0 -81.28 0)
					(length 5.08)
					(hide yes)
					(name "VSS_ANA"
						(effects
							(font
								(size 1.27 1.27)
							)
						)
					)
					(number "V15"
						(effects
							(font
								(size 1.27 1.27)
							)
						)
					)
				)
				(pin passive line
					(at 0 -81.28 0)
					(length 5.08)
					(hide yes)
					(name "VSS_ANA"
						(effects
							(font
								(size 1.27 1.27)
							)
						)
					)
					(number "V16"
						(effects
							(font
								(size 1.27 1.27)
							)
						)
					)
				)
				(pin passive line
					(at 0 -81.28 0)
					(length 5.08)
					(hide yes)
					(name "VSS_ANA"
						(effects
							(font
								(size 1.27 1.27)
							)
						)
					)
					(number "V20"
						(effects
							(font
								(size 1.27 1.27)
							)
						)
					)
				)
				(pin passive line
					(at 0 -81.28 0)
					(length 5.08)
					(hide yes)
					(name "VSS_ANA"
						(effects
							(font
								(size 1.27 1.27)
							)
						)
					)
					(number "V5"
						(effects
							(font
								(size 1.27 1.27)
							)
						)
					)
				)
				(pin passive line
					(at 0 -81.28 0)
					(length 5.08)
					(hide yes)
					(name "VSS_ANA"
						(effects
							(font
								(size 1.27 1.27)
							)
						)
					)
					(number "V6"
						(effects
							(font
								(size 1.27 1.27)
							)
						)
					)
				)
				(pin passive line
					(at 0 -81.28 0)
					(length 5.08)
					(hide yes)
					(name "VSS_ANA"
						(effects
							(font
								(size 1.27 1.27)
							)
						)
					)
					(number "V8"
						(effects
							(font
								(size 1.27 1.27)
							)
						)
					)
				)
				(pin passive line
					(at 0 -81.28 0)
					(length 5.08)
					(hide yes)
					(name "VSS_ANA"
						(effects
							(font
								(size 1.27 1.27)
							)
						)
					)
					(number "V9"
						(effects
							(font
								(size 1.27 1.27)
							)
						)
					)
				)
				(pin passive line
					(at 0 -81.28 0)
					(length 5.08)
					(hide yes)
					(name "VSS_ANA"
						(effects
							(font
								(size 1.27 1.27)
							)
						)
					)
					(number "W20"
						(effects
							(font
								(size 1.27 1.27)
							)
						)
					)
				)
				(pin passive line
					(at 0 -81.28 0)
					(length 5.08)
					(hide yes)
					(name "VSS_ANA"
						(effects
							(font
								(size 1.27 1.27)
							)
						)
					)
					(number "W22"
						(effects
							(font
								(size 1.27 1.27)
							)
						)
					)
				)
				(pin passive line
					(at 0 -81.28 0)
					(length 5.08)
					(hide yes)
					(name "VSS_ANA"
						(effects
							(font
								(size 1.27 1.27)
							)
						)
					)
					(number "W23"
						(effects
							(font
								(size 1.27 1.27)
							)
						)
					)
				)
				(pin passive line
					(at 0 -81.28 0)
					(length 5.08)
					(hide yes)
					(name "VSS_ANA"
						(effects
							(font
								(size 1.27 1.27)
							)
						)
					)
					(number "W5"
						(effects
							(font
								(size 1.27 1.27)
							)
						)
					)
				)
				(pin passive line
					(at 0 -81.28 0)
					(length 5.08)
					(hide yes)
					(name "VSS_ANA"
						(effects
							(font
								(size 1.27 1.27)
							)
						)
					)
					(number "W6"
						(effects
							(font
								(size 1.27 1.27)
							)
						)
					)
				)
				(pin passive line
					(at 0 -81.28 0)
					(length 5.08)
					(hide yes)
					(name "VSS_ANA"
						(effects
							(font
								(size 1.27 1.27)
							)
						)
					)
					(number "W8"
						(effects
							(font
								(size 1.27 1.27)
							)
						)
					)
				)
				(pin passive line
					(at 0 -81.28 0)
					(length 5.08)
					(hide yes)
					(name "VSS_ANA"
						(effects
							(font
								(size 1.27 1.27)
							)
						)
					)
					(number "W9"
						(effects
							(font
								(size 1.27 1.27)
							)
						)
					)
				)
				(pin passive line
					(at 0 -81.28 0)
					(length 5.08)
					(hide yes)
					(name "VSS_ANA"
						(effects
							(font
								(size 1.27 1.27)
							)
						)
					)
					(number "Y13"
						(effects
							(font
								(size 1.27 1.27)
							)
						)
					)
				)
				(pin passive line
					(at 0 -81.28 0)
					(length 5.08)
					(hide yes)
					(name "VSS_ANA"
						(effects
							(font
								(size 1.27 1.27)
							)
						)
					)
					(number "Y20"
						(effects
							(font
								(size 1.27 1.27)
							)
						)
					)
				)
				(pin passive line
					(at 0 -81.28 0)
					(length 5.08)
					(hide yes)
					(name "VSS_ANA"
						(effects
							(font
								(size 1.27 1.27)
							)
						)
					)
					(number "Y9"
						(effects
							(font
								(size 1.27 1.27)
							)
						)
					)
				)
				(pin power_in line
					(at 54.61 0 180)
					(length 5.08)
					(name "VCC3P3_SVR"
						(effects
							(font
								(size 1.27 1.27)
							)
						)
					)
					(number "A2"
						(effects
							(font
								(size 1.27 1.27)
							)
						)
					)
				)
				(pin passive line
					(at 54.61 0 180)
					(length 5.08)
					(hide yes)
					(name "VCC3P3_SVR"
						(effects
							(font
								(size 1.27 1.27)
							)
						)
					)
					(number "A3"
						(effects
							(font
								(size 1.27 1.27)
							)
						)
					)
				)
				(pin passive line
					(at 54.61 0 180)
					(length 5.08)
					(hide yes)
					(name "VCC3P3_SVR"
						(effects
							(font
								(size 1.27 1.27)
							)
						)
					)
					(number "B3"
						(effects
							(font
								(size 1.27 1.27)
							)
						)
					)
				)
				(pin power_in line
					(at 54.61 -2.54 180)
					(length 5.08)
					(name "VCC3P3_SX"
						(effects
							(font
								(size 1.27 1.27)
							)
						)
					)
					(number "F8"
						(effects
							(font
								(size 1.27 1.27)
							)
						)
					)
				)
				(pin power_in line
					(at 54.61 -5.08 180)
					(length 5.08)
					(name "VCC3P3A"
						(effects
							(font
								(size 1.27 1.27)
							)
						)
					)
					(number "H9"
						(effects
							(font
								(size 1.27 1.27)
							)
						)
					)
				)
				(pin power_in line
					(at 54.61 -17.78 180)
					(length 5.08)
					(name "VCC3P3_S0"
						(effects
							(font
								(size 1.27 1.27)
							)
						)
					)
					(number "R13"
						(effects
							(font
								(size 1.27 1.27)
							)
						)
					)
				)
				(pin power_in line
					(at 54.61 -20.32 180)
					(length 5.08)
					(name "VCC3P3_LC"
						(effects
							(font
								(size 1.27 1.27)
							)
						)
					)
					(number "R6"
						(effects
							(font
								(size 1.27 1.27)
							)
						)
					)
				)
				(pin power_in line
					(at 54.61 -35.56 180)
					(length 5.08)
					(name "VCC0P9_SVR"
						(effects
							(font
								(size 1.27 1.27)
							)
						)
					)
					(number "L9"
						(effects
							(font
								(size 1.27 1.27)
							)
						)
					)
				)
				(pin passive line
					(at 54.61 -35.56 180)
					(length 5.08)
					(hide yes)
					(name "VCC0P9_SVR"
						(effects
							(font
								(size 1.27 1.27)
							)
						)
					)
					(number "M9"
						(effects
							(font
								(size 1.27 1.27)
							)
						)
					)
				)
				(pin power_in line
					(at 54.61 -38.1 180)
					(length 5.08)
					(name "VCC0P9_SVR_ANA"
						(effects
							(font
								(size 1.27 1.27)
							)
						)
					)
					(number "E12"
						(effects
							(font
								(size 1.27 1.27)
							)
						)
					)
				)
				(pin passive line
					(at 54.61 -38.1 180)
					(length 5.08)
					(hide yes)
					(name "VCC0P9_SVR_ANA"
						(effects
							(font
								(size 1.27 1.27)
							)
						)
					)
					(number "E13"
						(effects
							(font
								(size 1.27 1.27)
							)
						)
					)
				)
				(pin passive line
					(at 54.61 -38.1 180)
					(length 5.08)
					(hide yes)
					(name "VCC0P9_SVR_ANA"
						(effects
							(font
								(size 1.27 1.27)
							)
						)
					)
					(number "F11"
						(effects
							(font
								(size 1.27 1.27)
							)
						)
					)
				)
				(pin passive line
					(at 54.61 -38.1 180)
					(length 5.08)
					(hide yes)
					(name "VCC0P9_SVR_ANA"
						(effects
							(font
								(size 1.27 1.27)
							)
						)
					)
					(number "F12"
						(effects
							(font
								(size 1.27 1.27)
							)
						)
					)
				)
				(pin passive line
					(at 54.61 -38.1 180)
					(length 5.08)
					(hide yes)
					(name "VCC0P9_SVR_ANA"
						(effects
							(font
								(size 1.27 1.27)
							)
						)
					)
					(number "F13"
						(effects
							(font
								(size 1.27 1.27)
							)
						)
					)
				)
				(pin passive line
					(at 54.61 -38.1 180)
					(length 5.08)
					(hide yes)
					(name "VCC0P9_SVR_ANA"
						(effects
							(font
								(size 1.27 1.27)
							)
						)
					)
					(number "F15"
						(effects
							(font
								(size 1.27 1.27)
							)
						)
					)
				)
				(pin power_in line
					(at 54.61 -40.64 180)
					(length 5.08)
					(name "VCC0P9_SVR_SENSE"
						(effects
							(font
								(size 1.27 1.27)
							)
						)
					)
					(number "J9"
						(effects
							(font
								(size 1.27 1.27)
							)
						)
					)
				)
				(pin power_out line
					(at 54.61 -53.34 180)
					(length 5.08)
					(name "SVR_IND"
						(effects
							(font
								(size 1.27 1.27)
							)
						)
					)
					(number "C1"
						(effects
							(font
								(size 1.27 1.27)
							)
						)
					)
				)
				(pin passive line
					(at 54.61 -53.34 180)
					(length 5.08)
					(hide yes)
					(name "SVR_IND"
						(effects
							(font
								(size 1.27 1.27)
							)
						)
					)
					(number "C2"
						(effects
							(font
								(size 1.27 1.27)
							)
						)
					)
				)
				(pin passive line
					(at 54.61 -53.34 180)
					(length 5.08)
					(hide yes)
					(name "SVR_IND"
						(effects
							(font
								(size 1.27 1.27)
							)
						)
					)
					(number "D1"
						(effects
							(font
								(size 1.27 1.27)
							)
						)
					)
				)
				(pin power_in line
					(at 54.61 -55.88 180)
					(length 5.08)
					(name "SVR_VSS"
						(effects
							(font
								(size 1.27 1.27)
							)
						)
					)
					(number "A1"
						(effects
							(font
								(size 1.27 1.27)
							)
						)
					)
				)
				(pin passive line
					(at 54.61 -55.88 180)
					(length 5.08)
					(hide yes)
					(name "SVR_VSS"
						(effects
							(font
								(size 1.27 1.27)
							)
						)
					)
					(number "B1"
						(effects
							(font
								(size 1.27 1.27)
							)
						)
					)
				)
				(pin passive line
					(at 54.61 -55.88 180)
					(length 5.08)
					(hide yes)
					(name "SVR_VSS"
						(effects
							(font
								(size 1.27 1.27)
							)
						)
					)
					(number "B2"
						(effects
							(font
								(size 1.27 1.27)
							)
						)
					)
				)
				(pin power_in line
					(at 54.61 -71.12 180)
					(length 5.08)
					(name "VCC0P9_LVR"
						(effects
							(font
								(size 1.27 1.27)
							)
						)
					)
					(number "F18"
						(effects
							(font
								(size 1.27 1.27)
							)
						)
					)
				)
				(pin passive line
					(at 54.61 -71.12 180)
					(length 5.08)
					(hide yes)
					(name "VCC0P9_LVR"
						(effects
							(font
								(size 1.27 1.27)
							)
						)
					)
					(number "H18"
						(effects
							(font
								(size 1.27 1.27)
							)
						)
					)
				)
				(pin passive line
					(at 54.61 -71.12 180)
					(length 5.08)
					(hide yes)
					(name "VCC0P9_LVR"
						(effects
							(font
								(size 1.27 1.27)
							)
						)
					)
					(number "J11"
						(effects
							(font
								(size 1.27 1.27)
							)
						)
					)
				)
				(pin power_in line
					(at 54.61 -73.66 180)
					(length 5.08)
					(name "VCC0P9_LVR_SENSE"
						(effects
							(font
								(size 1.27 1.27)
							)
						)
					)
					(number "H11"
						(effects
							(font
								(size 1.27 1.27)
							)
						)
					)
				)
				(pin passive line
					(at 54.61 -81.28 180)
					(length 5.08)
					(name "VSS"
						(effects
							(font
								(size 1.27 1.27)
							)
						)
					)
					(number "AB1"
						(effects
							(font
								(size 1.27 1.27)
							)
						)
					)
				)
				(pin passive line
					(at 54.61 -81.28 180)
					(length 5.08)
					(hide yes)
					(name "VSS"
						(effects
							(font
								(size 1.27 1.27)
							)
						)
					)
					(number "AC2"
						(effects
							(font
								(size 1.27 1.27)
							)
						)
					)
				)
				(pin passive line
					(at 54.61 -81.28 180)
					(length 5.08)
					(hide yes)
					(name "VSS"
						(effects
							(font
								(size 1.27 1.27)
							)
						)
					)
					(number "D5"
						(effects
							(font
								(size 1.27 1.27)
							)
						)
					)
				)
				(pin passive line
					(at 54.61 -81.28 180)
					(length 5.08)
					(hide yes)
					(name "VSS"
						(effects
							(font
								(size 1.27 1.27)
							)
						)
					)
					(number "E4"
						(effects
							(font
								(size 1.27 1.27)
							)
						)
					)
				)
				(pin passive line
					(at 54.61 -81.28 180)
					(length 5.08)
					(hide yes)
					(name "VSS"
						(effects
							(font
								(size 1.27 1.27)
							)
						)
					)
					(number "E5"
						(effects
							(font
								(size 1.27 1.27)
							)
						)
					)
				)
				(pin passive line
					(at 54.61 -81.28 180)
					(length 5.08)
					(hide yes)
					(name "VSS"
						(effects
							(font
								(size 1.27 1.27)
							)
						)
					)
					(number "E6"
						(effects
							(font
								(size 1.27 1.27)
							)
						)
					)
				)
				(pin passive line
					(at 54.61 -81.28 180)
					(length 5.08)
					(hide yes)
					(name "VSS"
						(effects
							(font
								(size 1.27 1.27)
							)
						)
					)
					(number "F5"
						(effects
							(font
								(size 1.27 1.27)
							)
						)
					)
				)
				(pin passive line
					(at 54.61 -81.28 180)
					(length 5.08)
					(hide yes)
					(name "VSS"
						(effects
							(font
								(size 1.27 1.27)
							)
						)
					)
					(number "F6"
						(effects
							(font
								(size 1.27 1.27)
							)
						)
					)
				)
				(pin passive line
					(at 54.61 -81.28 180)
					(length 5.08)
					(hide yes)
					(name "VSS"
						(effects
							(font
								(size 1.27 1.27)
							)
						)
					)
					(number "H5"
						(effects
							(font
								(size 1.27 1.27)
							)
						)
					)
				)
				(pin passive line
					(at 54.61 -81.28 180)
					(length 5.08)
					(hide yes)
					(name "VSS"
						(effects
							(font
								(size 1.27 1.27)
							)
						)
					)
					(number "H8"
						(effects
							(font
								(size 1.27 1.27)
							)
						)
					)
				)
				(pin passive line
					(at 54.61 -81.28 180)
					(length 5.08)
					(hide yes)
					(name "VSS"
						(effects
							(font
								(size 1.27 1.27)
							)
						)
					)
					(number "J12"
						(effects
							(font
								(size 1.27 1.27)
							)
						)
					)
				)
				(pin passive line
					(at 54.61 -81.28 180)
					(length 5.08)
					(hide yes)
					(name "VSS"
						(effects
							(font
								(size 1.27 1.27)
							)
						)
					)
					(number "J13"
						(effects
							(font
								(size 1.27 1.27)
							)
						)
					)
				)
				(pin passive line
					(at 54.61 -81.28 180)
					(length 5.08)
					(hide yes)
					(name "VSS"
						(effects
							(font
								(size 1.27 1.27)
							)
						)
					)
					(number "J15"
						(effects
							(font
								(size 1.27 1.27)
							)
						)
					)
				)
				(pin passive line
					(at 54.61 -81.28 180)
					(length 5.08)
					(hide yes)
					(name "VSS"
						(effects
							(font
								(size 1.27 1.27)
							)
						)
					)
					(number "J8"
						(effects
							(font
								(size 1.27 1.27)
							)
						)
					)
				)
				(pin passive line
					(at 54.61 -81.28 180)
					(length 5.08)
					(hide yes)
					(name "VSS"
						(effects
							(font
								(size 1.27 1.27)
							)
						)
					)
					(number "L13"
						(effects
							(font
								(size 1.27 1.27)
							)
						)
					)
				)
				(pin passive line
					(at 54.61 -81.28 180)
					(length 5.08)
					(hide yes)
					(name "VSS"
						(effects
							(font
								(size 1.27 1.27)
							)
						)
					)
					(number "M11"
						(effects
							(font
								(size 1.27 1.27)
							)
						)
					)
				)
				(pin passive line
					(at 54.61 -81.28 180)
					(length 5.08)
					(hide yes)
					(name "VSS"
						(effects
							(font
								(size 1.27 1.27)
							)
						)
					)
					(number "M12"
						(effects
							(font
								(size 1.27 1.27)
							)
						)
					)
				)
				(pin passive line
					(at 54.61 -81.28 180)
					(length 5.08)
					(hide yes)
					(name "VSS"
						(effects
							(font
								(size 1.27 1.27)
							)
						)
					)
					(number "N11"
						(effects
							(font
								(size 1.27 1.27)
							)
						)
					)
				)
				(pin passive line
					(at 54.61 -81.28 180)
					(length 5.08)
					(hide yes)
					(name "VSS"
						(effects
							(font
								(size 1.27 1.27)
							)
						)
					)
					(number "N12"
						(effects
							(font
								(size 1.27 1.27)
							)
						)
					)
				)
				(pin passive line
					(at 54.61 -81.28 180)
					(length 5.08)
					(hide yes)
					(name "VSS"
						(effects
							(font
								(size 1.27 1.27)
							)
						)
					)
					(number "N13"
						(effects
							(font
								(size 1.27 1.27)
							)
						)
					)
				)
				(pin passive line
					(at 54.61 -81.28 180)
					(length 5.08)
					(hide yes)
					(name "VSS"
						(effects
							(font
								(size 1.27 1.27)
							)
						)
					)
					(number "N8"
						(effects
							(font
								(size 1.27 1.27)
							)
						)
					)
				)
				(pin passive line
					(at 54.61 -81.28 180)
					(length 5.08)
					(hide yes)
					(name "VSS"
						(effects
							(font
								(size 1.27 1.27)
							)
						)
					)
					(number "N9"
						(effects
							(font
								(size 1.27 1.27)
							)
						)
					)
				)
				(pin passive line
					(at 54.61 -81.28 180)
					(length 5.08)
					(hide yes)
					(name "VSS"
						(effects
							(font
								(size 1.27 1.27)
							)
						)
					)
					(number "T13"
						(effects
							(font
								(size 1.27 1.27)
							)
						)
					)
				)
				(pin passive line
					(at 54.61 -81.28 180)
					(length 5.08)
					(hide yes)
					(name "VSS"
						(effects
							(font
								(size 1.27 1.27)
							)
						)
					)
					(number "T15"
						(effects
							(font
								(size 1.27 1.27)
							)
						)
					)
				)
				(pin passive line
					(at 54.61 -81.28 180)
					(length 5.08)
					(hide yes)
					(name "VSS"
						(effects
							(font
								(size 1.27 1.27)
							)
						)
					)
					(number "T16"
						(effects
							(font
								(size 1.27 1.27)
							)
						)
					)
				)
				(pin passive line
					(at 54.61 -81.28 180)
					(length 5.08)
					(hide yes)
					(name "VSS"
						(effects
							(font
								(size 1.27 1.27)
							)
						)
					)
					(number "T18"
						(effects
							(font
								(size 1.27 1.27)
							)
						)
					)
				)
				(pin passive line
					(at 54.61 -81.28 180)
					(length 5.08)
					(hide yes)
					(name "VSS"
						(effects
							(font
								(size 1.27 1.27)
							)
						)
					)
					(number "T6"
						(effects
							(font
								(size 1.27 1.27)
							)
						)
					)
				)
				(pin passive line
					(at 54.61 -81.28 180)
					(length 5.08)
					(hide yes)
					(name "VSS"
						(effects
							(font
								(size 1.27 1.27)
							)
						)
					)
					(number "T8"
						(effects
							(font
								(size 1.27 1.27)
							)
						)
					)
				)
				(pin passive line
					(at 54.61 -81.28 180)
					(length 5.08)
					(hide yes)
					(name "VSS"
						(effects
							(font
								(size 1.27 1.27)
							)
						)
					)
					(number "T9"
						(effects
							(font
								(size 1.27 1.27)
							)
						)
					)
				)
			)
			(symbol "JHL6340SLLSQ_2_0"
				(text "PCIe Gen3"
					(at 24.13 -17.78 0)
					(effects
						(font
							(size 1.27 1.27)
							(thickness 0.15)
						)
						(justify left bottom)
					)
				)
			)
			(symbol "JHL6340SLLSQ_2_1"
				(rectangle
					(start 5.08 5.08)
					(end 50.8 -40.64)
					(stroke
						(width 0.254)
						(type default)
					)
					(fill
						(type background)
					)
				)
				(pin input line
					(at 0 0 0)
					(length 5.08)
					(name "PCIE_RX0_P"
						(effects
							(font
								(size 1.27 1.27)
							)
						)
					)
					(number "Y23"
						(effects
							(font
								(size 1.27 1.27)
							)
						)
					)
				)
				(pin input line
					(at 0 -2.54 0)
					(length 5.08)
					(name "PCIE_RX0_N"
						(effects
							(font
								(size 1.27 1.27)
							)
						)
					)
					(number "Y22"
						(effects
							(font
								(size 1.27 1.27)
							)
						)
					)
				)
				(pin input line
					(at 0 -7.62 0)
					(length 5.08)
					(name "PCIE_RX1_P"
						(effects
							(font
								(size 1.27 1.27)
							)
						)
					)
					(number "T23"
						(effects
							(font
								(size 1.27 1.27)
							)
						)
					)
				)
				(pin input line
					(at 0 -10.16 0)
					(length 5.08)
					(name "PCIE_RX1_N"
						(effects
							(font
								(size 1.27 1.27)
							)
						)
					)
					(number "T22"
						(effects
							(font
								(size 1.27 1.27)
							)
						)
					)
				)
				(pin input line
					(at 0 -15.24 0)
					(length 5.08)
					(name "PCIE_RX2_P"
						(effects
							(font
								(size 1.27 1.27)
							)
						)
					)
					(number "M23"
						(effects
							(font
								(size 1.27 1.27)
							)
						)
					)
				)
				(pin input line
					(at 0 -17.78 0)
					(length 5.08)
					(name "PCIE_RX2_N"
						(effects
							(font
								(size 1.27 1.27)
							)
						)
					)
					(number "M22"
						(effects
							(font
								(size 1.27 1.27)
							)
						)
					)
				)
				(pin input line
					(at 0 -22.86 0)
					(length 5.08)
					(name "PCIE_RX3_P"
						(effects
							(font
								(size 1.27 1.27)
							)
						)
					)
					(number "H23"
						(effects
							(font
								(size 1.27 1.27)
							)
						)
					)
				)
				(pin input line
					(at 0 -25.4 0)
					(length 5.08)
					(name "PCIE_RX3_N"
						(effects
							(font
								(size 1.27 1.27)
							)
						)
					)
					(number "H22"
						(effects
							(font
								(size 1.27 1.27)
							)
						)
					)
				)
				(pin input line
					(at 0 -30.48 0)
					(length 5.08)
					(name "PCIE_REFCLK_100_IN_P"
						(effects
							(font
								(size 1.27 1.27)
							)
						)
					)
					(number "V19"
						(effects
							(font
								(size 1.27 1.27)
							)
						)
					)
				)
				(pin input line
					(at 0 -33.02 0)
					(length 5.08)
					(name "PCIE_REFCLK_100_IN_N"
						(effects
							(font
								(size 1.27 1.27)
							)
						)
					)
					(number "T19"
						(effects
							(font
								(size 1.27 1.27)
							)
						)
					)
				)
				(pin output line
					(at 0 -38.1 0)
					(length 5.08)
					(name "PCIE_CLKREQ_N"
						(effects
							(font
								(size 1.27 1.27)
							)
						)
					)
					(number "AC5"
						(effects
							(font
								(size 1.27 1.27)
							)
						)
					)
				)
				(pin input line
					(at 55.88 0 180)
					(length 5.08)
					(name "PCIE_TX0_P"
						(effects
							(font
								(size 1.27 1.27)
							)
						)
					)
					(number "V23"
						(effects
							(font
								(size 1.27 1.27)
							)
						)
					)
				)
				(pin input line
					(at 55.88 -2.54 180)
					(length 5.08)
					(name "PCIE_TX0_N"
						(effects
							(font
								(size 1.27 1.27)
							)
						)
					)
					(number "V22"
						(effects
							(font
								(size 1.27 1.27)
							)
						)
					)
				)
				(pin input line
					(at 55.88 -7.62 180)
					(length 5.08)
					(name "PCIE_TX1_P"
						(effects
							(font
								(size 1.27 1.27)
							)
						)
					)
					(number "P23"
						(effects
							(font
								(size 1.27 1.27)
							)
						)
					)
				)
				(pin input line
					(at 55.88 -10.16 180)
					(length 5.08)
					(name "PCIE_TX1_N"
						(effects
							(font
								(size 1.27 1.27)
							)
						)
					)
					(number "P22"
						(effects
							(font
								(size 1.27 1.27)
							)
						)
					)
				)
				(pin input line
					(at 55.88 -15.24 180)
					(length 5.08)
					(name "PCIE_TX2_P"
						(effects
							(font
								(size 1.27 1.27)
							)
						)
					)
					(number "K23"
						(effects
							(font
								(size 1.27 1.27)
							)
						)
					)
				)
				(pin input line
					(at 55.88 -17.78 180)
					(length 5.08)
					(name "PCIE_TX2_N"
						(effects
							(font
								(size 1.27 1.27)
							)
						)
					)
					(number "K22"
						(effects
							(font
								(size 1.27 1.27)
							)
						)
					)
				)
				(pin input line
					(at 55.88 -22.86 180)
					(length 5.08)
					(name "PCIE_TX3_P"
						(effects
							(font
								(size 1.27 1.27)
							)
						)
					)
					(number "F23"
						(effects
							(font
								(size 1.27 1.27)
							)
						)
					)
				)
				(pin input line
					(at 55.88 -25.4 180)
					(length 5.08)
					(name "PCIE_TX3_N"
						(effects
							(font
								(size 1.27 1.27)
							)
						)
					)
					(number "F22"
						(effects
							(font
								(size 1.27 1.27)
							)
						)
					)
				)
				(pin input line
					(at 55.88 -33.02 180)
					(length 5.08)
					(name "PERST_N"
						(effects
							(font
								(size 1.27 1.27)
							)
						)
					)
					(number "L4"
						(effects
							(font
								(size 1.27 1.27)
							)
						)
					)
				)
				(pin input line
					(at 55.88 -38.1 180)
					(length 5.08)
					(name "PCIE_RBIAS"
						(effects
							(font
								(size 1.27 1.27)
							)
						)
					)
					(number "N16"
						(effects
							(font
								(size 1.27 1.27)
							)
						)
					)
				)
			)
			(symbol "JHL6340SLLSQ_3_0"
				(polyline
					(pts
						(xy 15.24 2.54) (xy 24.13 2.54) (xy 24.13 -48.26) (xy 15.24 -48.26)
					)
					(stroke
						(width 0)
						(type default)
					)
					(fill
						(type none)
					)
				)
				(polyline
					(pts
						(xy 15.24 -50.8) (xy 24.13 -50.8) (xy 24.13 -101.6) (xy 15.24 -101.6)
					)
					(stroke
						(width 0)
						(type default)
					)
					(fill
						(type none)
					)
				)
				(polyline
					(pts
						(xy 40.64 2.54) (xy 31.75 2.54) (xy 31.75 -45.72) (xy 40.64 -45.72)
					)
					(stroke
						(width 0)
						(type default)
					)
					(fill
						(type none)
					)
				)
				(polyline
					(pts
						(xy 40.64 -48.26) (xy 31.75 -48.26) (xy 31.75 -73.66) (xy 40.64 -73.66)
					)
					(stroke
						(width 0)
						(type default)
					)
					(fill
						(type none)
					)
				)
				(polyline
					(pts
						(xy 40.64 -76.2) (xy 31.75 -76.2) (xy 31.75 -96.52) (xy 40.64 -96.52)
					)
					(stroke
						(width 0)
						(type default)
					)
					(fill
						(type none)
					)
				)
				(text "SINK PORT 0"
					(at 26.67 -27.94 900)
					(effects
						(font
							(size 1.27 1.27)
							(thickness 0.15)
						)
						(justify left bottom)
					)
				)
				(text "SINK PORT 1"
					(at 26.67 -80.01 900)
					(effects
						(font
							(size 1.27 1.27)
							(thickness 0.15)
						)
						(justify left bottom)
					)
				)
				(text "SOURCE PORT 0"
					(at 30.48 -29.21 900)
					(effects
						(font
							(size 1.27 1.27)
							(thickness 0.15)
						)
						(justify left bottom)
					)
				)
				(text "GPIO"
					(at 30.48 -60.96 900)
					(effects
						(font
							(size 1.27 1.27)
							(thickness 0.15)
						)
						(justify left bottom)
					)
				)
				(text "POC_GPIO"
					(at 30.48 -90.17 900)
					(effects
						(font
							(size 1.27 1.27)
							(thickness 0.15)
						)
						(justify left bottom)
					)
				)
			)
			(symbol "JHL6340SLLSQ_3_1"
				(rectangle
					(start 5.08 3.81)
					(end 50.8 -107.95)
					(stroke
						(width 0.254)
						(type default)
					)
					(fill
						(type background)
					)
				)
				(pin input line
					(at 0 0 0)
					(length 5.08)
					(name "DPSNK0_ML0_P"
						(effects
							(font
								(size 1.27 1.27)
							)
						)
					)
					(number "AB7"
						(effects
							(font
								(size 1.27 1.27)
							)
						)
					)
				)
				(pin input line
					(at 0 -2.54 0)
					(length 5.08)
					(name "DPSNK0_ML0_N"
						(effects
							(font
								(size 1.27 1.27)
							)
						)
					)
					(number "AC7"
						(effects
							(font
								(size 1.27 1.27)
							)
						)
					)
				)
				(pin input line
					(at 0 -7.62 0)
					(length 5.08)
					(name "DPSNK0_ML1_P"
						(effects
							(font
								(size 1.27 1.27)
							)
						)
					)
					(number "AB9"
						(effects
							(font
								(size 1.27 1.27)
							)
						)
					)
				)
				(pin input line
					(at 0 -10.16 0)
					(length 5.08)
					(name "DPSNK0_ML1_N"
						(effects
							(font
								(size 1.27 1.27)
							)
						)
					)
					(number "AC9"
						(effects
							(font
								(size 1.27 1.27)
							)
						)
					)
				)
				(pin input line
					(at 0 -15.24 0)
					(length 5.08)
					(name "DPSNK0_ML2_P"
						(effects
							(font
								(size 1.27 1.27)
							)
						)
					)
					(number "AB11"
						(effects
							(font
								(size 1.27 1.27)
							)
						)
					)
				)
				(pin input line
					(at 0 -17.78 0)
					(length 5.08)
					(name "DPSNK0_ML2_N"
						(effects
							(font
								(size 1.27 1.27)
							)
						)
					)
					(number "AC11"
						(effects
							(font
								(size 1.27 1.27)
							)
						)
					)
				)
				(pin input line
					(at 0 -22.86 0)
					(length 5.08)
					(name "DPSNK0_ML3_P"
						(effects
							(font
								(size 1.27 1.27)
							)
						)
					)
					(number "AB13"
						(effects
							(font
								(size 1.27 1.27)
							)
						)
					)
				)
				(pin input line
					(at 0 -25.4 0)
					(length 5.08)
					(name "DPSNK0_ML3_N"
						(effects
							(font
								(size 1.27 1.27)
							)
						)
					)
					(number "AC13"
						(effects
							(font
								(size 1.27 1.27)
							)
						)
					)
				)
				(pin bidirectional line
					(at 0 -30.48 0)
					(length 5.08)
					(name "DPSNK0_AUXP"
						(effects
							(font
								(size 1.27 1.27)
							)
						)
					)
					(number "Y11"
						(effects
							(font
								(size 1.27 1.27)
							)
						)
					)
				)
				(pin bidirectional line
					(at 0 -33.02 0)
					(length 5.08)
					(name "DPSNK0_AUX_N"
						(effects
							(font
								(size 1.27 1.27)
							)
						)
					)
					(number "W11"
						(effects
							(font
								(size 1.27 1.27)
							)
						)
					)
				)
				(pin passive line
					(at 0 -38.1 0)
					(length 5.08)
					(name "DPSNK0_HPD"
						(effects
							(font
								(size 1.27 1.27)
							)
						)
					)
					(number "AA2"
						(effects
							(font
								(size 1.27 1.27)
							)
						)
					)
				)
				(pin passive line
					(at 0 -43.18 0)
					(length 5.08)
					(name "DPSNK0_DDC_CLK"
						(effects
							(font
								(size 1.27 1.27)
							)
						)
					)
					(number "Y5"
						(effects
							(font
								(size 1.27 1.27)
							)
						)
					)
				)
				(pin passive line
					(at 0 -45.72 0)
					(length 5.08)
					(name "DPSNK0_DDC_DATA"
						(effects
							(font
								(size 1.27 1.27)
							)
						)
					)
					(number "R4"
						(effects
							(font
								(size 1.27 1.27)
							)
						)
					)
				)
				(pin input line
					(at 0 -53.34 0)
					(length 5.08)
					(name "DPSNK1_ML0_P"
						(effects
							(font
								(size 1.27 1.27)
							)
						)
					)
					(number "AB15"
						(effects
							(font
								(size 1.27 1.27)
							)
						)
					)
				)
				(pin input line
					(at 0 -55.88 0)
					(length 5.08)
					(name "DPSNK1_ML0_N"
						(effects
							(font
								(size 1.27 1.27)
							)
						)
					)
					(number "AC15"
						(effects
							(font
								(size 1.27 1.27)
							)
						)
					)
				)
				(pin input line
					(at 0 -60.96 0)
					(length 5.08)
					(name "DPSNK1_ML1_P"
						(effects
							(font
								(size 1.27 1.27)
							)
						)
					)
					(number "AB17"
						(effects
							(font
								(size 1.27 1.27)
							)
						)
					)
				)
				(pin input line
					(at 0 -63.5 0)
					(length 5.08)
					(name "DPSNK1_ML1_N"
						(effects
							(font
								(size 1.27 1.27)
							)
						)
					)
					(number "AC17"
						(effects
							(font
								(size 1.27 1.27)
							)
						)
					)
				)
				(pin input line
					(at 0 -68.58 0)
					(length 5.08)
					(name "DPSNK1_ML2_P"
						(effects
							(font
								(size 1.27 1.27)
							)
						)
					)
					(number "AB19"
						(effects
							(font
								(size 1.27 1.27)
							)
						)
					)
				)
				(pin input line
					(at 0 -71.12 0)
					(length 5.08)
					(name "DPSNK1_ML2_N"
						(effects
							(font
								(size 1.27 1.27)
							)
						)
					)
					(number "AC19"
						(effects
							(font
								(size 1.27 1.27)
							)
						)
					)
				)
				(pin input line
					(at 0 -76.2 0)
					(length 5.08)
					(name "DPSNK1_ML3_P"
						(effects
							(font
								(size 1.27 1.27)
							)
						)
					)
					(number "AB21"
						(effects
							(font
								(size 1.27 1.27)
							)
						)
					)
				)
				(pin input line
					(at 0 -78.74 0)
					(length 5.08)
					(name "DPSNK1_ML3_N"
						(effects
							(font
								(size 1.27 1.27)
							)
						)
					)
					(number "AC21"
						(effects
							(font
								(size 1.27 1.27)
							)
						)
					)
				)
				(pin bidirectional line
					(at 0 -83.82 0)
					(length 5.08)
					(name "DPSNK1_AUXP"
						(effects
							(font
								(size 1.27 1.27)
							)
						)
					)
					(number "Y12"
						(effects
							(font
								(size 1.27 1.27)
							)
						)
					)
				)
				(pin bidirectional line
					(at 0 -86.36 0)
					(length 5.08)
					(name "DPSNK1_AUX_N"
						(effects
							(font
								(size 1.27 1.27)
							)
						)
					)
					(number "W12"
						(effects
							(font
								(size 1.27 1.27)
							)
						)
					)
				)
				(pin passive line
					(at 0 -91.44 0)
					(length 5.08)
					(name "DPSNK1_HPD"
						(effects
							(font
								(size 1.27 1.27)
							)
						)
					)
					(number "Y6"
						(effects
							(font
								(size 1.27 1.27)
							)
						)
					)
				)
				(pin passive line
					(at 0 -96.52 0)
					(length 5.08)
					(name "DPSNK1_DDC_CLK"
						(effects
							(font
								(size 1.27 1.27)
							)
						)
					)
					(number "Y8"
						(effects
							(font
								(size 1.27 1.27)
							)
						)
					)
				)
				(pin passive line
					(at 0 -99.06 0)
					(length 5.08)
					(name "DPSNK1_DDC_DATA"
						(effects
							(font
								(size 1.27 1.27)
							)
						)
					)
					(number "N4"
						(effects
							(font
								(size 1.27 1.27)
							)
						)
					)
				)
				(pin passive line
					(at 0 -104.14 0)
					(length 5.08)
					(name "DPSNK_RBIAS"
						(effects
							(font
								(size 1.27 1.27)
							)
						)
					)
					(number "Y18"
						(effects
							(font
								(size 1.27 1.27)
							)
						)
					)
				)
				(pin output line
					(at 55.88 0 180)
					(length 5.08)
					(name "DPSRC_ML0_P"
						(effects
							(font
								(size 1.27 1.27)
							)
						)
					)
					(number "R2"
						(effects
							(font
								(size 1.27 1.27)
							)
						)
					)
				)
				(pin output line
					(at 55.88 -2.54 180)
					(length 5.08)
					(name "DPSRC_ML0_N"
						(effects
							(font
								(size 1.27 1.27)
							)
						)
					)
					(number "R1"
						(effects
							(font
								(size 1.27 1.27)
							)
						)
					)
				)
				(pin output line
					(at 55.88 -7.62 180)
					(length 5.08)
					(name "DPSRC_ML1_P"
						(effects
							(font
								(size 1.27 1.27)
							)
						)
					)
					(number "N2"
						(effects
							(font
								(size 1.27 1.27)
							)
						)
					)
				)
				(pin output line
					(at 55.88 -10.16 180)
					(length 5.08)
					(name "DPSRC_ML1_N"
						(effects
							(font
								(size 1.27 1.27)
							)
						)
					)
					(number "N1"
						(effects
							(font
								(size 1.27 1.27)
							)
						)
					)
				)
				(pin output line
					(at 55.88 -15.24 180)
					(length 5.08)
					(name "DPSRC_ML2_P"
						(effects
							(font
								(size 1.27 1.27)
							)
						)
					)
					(number "L2"
						(effects
							(font
								(size 1.27 1.27)
							)
						)
					)
				)
				(pin output line
					(at 55.88 -17.78 180)
					(length 5.08)
					(name "DPSRC_ML2_N"
						(effects
							(font
								(size 1.27 1.27)
							)
						)
					)
					(number "L1"
						(effects
							(font
								(size 1.27 1.27)
							)
						)
					)
				)
				(pin output line
					(at 55.88 -22.86 180)
					(length 5.08)
					(name "DPSRC_ML3_P"
						(effects
							(font
								(size 1.27 1.27)
							)
						)
					)
					(number "J2"
						(effects
							(font
								(size 1.27 1.27)
							)
						)
					)
				)
				(pin output line
					(at 55.88 -25.4 180)
					(length 5.08)
					(name "DPSRC_ML3_N"
						(effects
							(font
								(size 1.27 1.27)
							)
						)
					)
					(number "J1"
						(effects
							(font
								(size 1.27 1.27)
							)
						)
					)
				)
				(pin bidirectional line
					(at 55.88 -30.48 180)
					(length 5.08)
					(name "DPSRC_AUX_P"
						(effects
							(font
								(size 1.27 1.27)
							)
						)
					)
					(number "W19"
						(effects
							(font
								(size 1.27 1.27)
							)
						)
					)
				)
				(pin bidirectional line
					(at 55.88 -33.02 180)
					(length 5.08)
					(name "DPSRC_AUX_N"
						(effects
							(font
								(size 1.27 1.27)
							)
						)
					)
					(number "Y19"
						(effects
							(font
								(size 1.27 1.27)
							)
						)
					)
				)
				(pin passive line
					(at 55.88 -38.1 180)
					(length 5.08)
					(name "DPSRC_HPD"
						(effects
							(font
								(size 1.27 1.27)
							)
						)
					)
					(number "G1"
						(effects
							(font
								(size 1.27 1.27)
							)
						)
					)
				)
				(pin passive line
					(at 55.88 -43.18 180)
					(length 5.08)
					(name "DPSRC_RBIAS"
						(effects
							(font
								(size 1.27 1.27)
							)
						)
					)
					(number "N6"
						(effects
							(font
								(size 1.27 1.27)
							)
						)
					)
				)
				(pin bidirectional line
					(at 55.88 -50.8 180)
					(length 5.08)
					(name "GPIO_0"
						(effects
							(font
								(size 1.27 1.27)
							)
						)
					)
					(number "U1"
						(effects
							(font
								(size 1.27 1.27)
							)
						)
					)
				)
				(pin bidirectional line
					(at 55.88 -53.34 180)
					(length 5.08)
					(name "GPIO_1"
						(effects
							(font
								(size 1.27 1.27)
							)
						)
					)
					(number "U2"
						(effects
							(font
								(size 1.27 1.27)
							)
						)
					)
				)
				(pin bidirectional line
					(at 55.88 -55.88 180)
					(length 5.08)
					(name "GPIO_2"
						(effects
							(font
								(size 1.27 1.27)
							)
						)
					)
					(number "V1"
						(effects
							(font
								(size 1.27 1.27)
							)
						)
					)
				)
				(pin bidirectional line
					(at 55.88 -58.42 180)
					(length 5.08)
					(name "GPIO_3"
						(effects
							(font
								(size 1.27 1.27)
							)
						)
					)
					(number "V2"
						(effects
							(font
								(size 1.27 1.27)
							)
						)
					)
				)
				(pin bidirectional line
					(at 55.88 -60.96 180)
					(length 5.08)
					(name "GPIO_4"
						(effects
							(font
								(size 1.27 1.27)
							)
						)
					)
					(number "W1"
						(effects
							(font
								(size 1.27 1.27)
							)
						)
					)
				)
				(pin bidirectional line
					(at 55.88 -63.5 180)
					(length 5.08)
					(name "GPIO_5"
						(effects
							(font
								(size 1.27 1.27)
							)
						)
					)
					(number "W2"
						(effects
							(font
								(size 1.27 1.27)
							)
						)
					)
				)
				(pin bidirectional line
					(at 55.88 -66.04 180)
					(length 5.08)
					(name "GPIO_6"
						(effects
							(font
								(size 1.27 1.27)
							)
						)
					)
					(number "Y1"
						(effects
							(font
								(size 1.27 1.27)
							)
						)
					)
				)
				(pin bidirectional line
					(at 55.88 -68.58 180)
					(length 5.08)
					(name "GPIO_7"
						(effects
							(font
								(size 1.27 1.27)
							)
						)
					)
					(number "Y2"
						(effects
							(font
								(size 1.27 1.27)
							)
						)
					)
				)
				(pin bidirectional line
					(at 55.88 -71.12 180)
					(length 5.08)
					(name "GPIO_8"
						(effects
							(font
								(size 1.27 1.27)
							)
						)
					)
					(number "AA1"
						(effects
							(font
								(size 1.27 1.27)
							)
						)
					)
				)
				(pin bidirectional line
					(at 55.88 -78.74 180)
					(length 5.08)
					(name "POC_GPIO_0"
						(effects
							(font
								(size 1.27 1.27)
							)
						)
					)
					(number "J4"
						(effects
							(font
								(size 1.27 1.27)
							)
						)
					)
				)
				(pin bidirectional line
					(at 55.88 -81.28 180)
					(length 5.08)
					(name "POC_GPIO_1"
						(effects
							(font
								(size 1.27 1.27)
							)
						)
					)
					(number "E2"
						(effects
							(font
								(size 1.27 1.27)
							)
						)
					)
				)
				(pin bidirectional line
					(at 55.88 -83.82 180)
					(length 5.08)
					(name "POC_GPIO_2"
						(effects
							(font
								(size 1.27 1.27)
							)
						)
					)
					(number "D4"
						(effects
							(font
								(size 1.27 1.27)
							)
						)
					)
				)
				(pin bidirectional line
					(at 55.88 -86.36 180)
					(length 5.08)
					(name "POC_GPIO_3"
						(effects
							(font
								(size 1.27 1.27)
							)
						)
					)
					(number "H4"
						(effects
							(font
								(size 1.27 1.27)
							)
						)
					)
				)
				(pin bidirectional line
					(at 55.88 -88.9 180)
					(length 5.08)
					(name "POC_GPIO_4"
						(effects
							(font
								(size 1.27 1.27)
							)
						)
					)
					(number "F2"
						(effects
							(font
								(size 1.27 1.27)
							)
						)
					)
				)
				(pin bidirectional line
					(at 55.88 -91.44 180)
					(length 5.08)
					(name "POC_GPIO_5"
						(effects
							(font
								(size 1.27 1.27)
							)
						)
					)
					(number "D2"
						(effects
							(font
								(size 1.27 1.27)
							)
						)
					)
				)
				(pin bidirectional line
					(at 55.88 -93.98 180)
					(length 5.08)
					(name "POC_GPIO_6"
						(effects
							(font
								(size 1.27 1.27)
							)
						)
					)
					(number "F1"
						(effects
							(font
								(size 1.27 1.27)
							)
						)
					)
				)
			)
			(symbol "JHL6340SLLSQ_4_0"
				(text "MISCELLANEOUS"
					(at 20.32 -13.97 0)
					(effects
						(font
							(size 1.27 1.27)
							(thickness 0.15)
						)
						(justify left bottom)
					)
				)
			)
			(symbol "JHL6340SLLSQ_4_1"
				(rectangle
					(start 5.08 3.81)
					(end 50.8 -29.21)
					(stroke
						(width 0.254)
						(type default)
					)
					(fill
						(type background)
					)
				)
				(pin input line
					(at 0 0 0)
					(length 5.08)
					(name "TDI"
						(effects
							(font
								(size 1.27 1.27)
							)
						)
					)
					(number "Y4"
						(effects
							(font
								(size 1.27 1.27)
							)
						)
					)
				)
				(pin input line
					(at 0 -2.54 0)
					(length 5.08)
					(name "TMS"
						(effects
							(font
								(size 1.27 1.27)
							)
						)
					)
					(number "V4"
						(effects
							(font
								(size 1.27 1.27)
							)
						)
					)
				)
				(pin input line
					(at 0 -5.08 0)
					(length 5.08)
					(name "TCK"
						(effects
							(font
								(size 1.27 1.27)
							)
						)
					)
					(number "T4"
						(effects
							(font
								(size 1.27 1.27)
							)
						)
					)
				)
				(pin output line
					(at 0 -7.62 0)
					(length 5.08)
					(name "TDO"
						(effects
							(font
								(size 1.27 1.27)
							)
						)
					)
					(number "W4"
						(effects
							(font
								(size 1.27 1.27)
							)
						)
					)
				)
				(pin passive line
					(at 0 -12.7 0)
					(length 5.08)
					(name "RBIAS"
						(effects
							(font
								(size 1.27 1.27)
							)
						)
					)
					(number "H6"
						(effects
							(font
								(size 1.27 1.27)
							)
						)
					)
				)
				(pin passive line
					(at 0 -25.4 0)
					(length 5.08)
					(name "RSENSE"
						(effects
							(font
								(size 1.27 1.27)
							)
						)
					)
					(number "J6"
						(effects
							(font
								(size 1.27 1.27)
							)
						)
					)
				)
				(pin input line
					(at 55.88 0 180)
					(length 5.08)
					(name "TEST_EN"
						(effects
							(font
								(size 1.27 1.27)
							)
						)
					)
					(number "E1"
						(effects
							(font
								(size 1.27 1.27)
							)
						)
					)
				)
				(pin input line
					(at 55.88 -2.54 180)
					(length 5.08)
					(name "TEST_PWR_GOOD"
						(effects
							(font
								(size 1.27 1.27)
							)
						)
					)
					(number "AB5"
						(effects
							(font
								(size 1.27 1.27)
							)
						)
					)
				)
				(pin input line
					(at 55.88 -5.08 180)
					(length 5.08)
					(name "RESET_N"
						(effects
							(font
								(size 1.27 1.27)
							)
						)
					)
					(number "F4"
						(effects
							(font
								(size 1.27 1.27)
							)
						)
					)
				)
				(pin input line
					(at 55.88 -10.16 180)
					(length 5.08)
					(name "XTAL_25_IN"
						(effects
							(font
								(size 1.27 1.27)
							)
						)
					)
					(number "D22"
						(effects
							(font
								(size 1.27 1.27)
							)
						)
					)
				)
				(pin input line
					(at 55.88 -12.7 180)
					(length 5.08)
					(name "XTAL_25_OUT"
						(effects
							(font
								(size 1.27 1.27)
							)
						)
					)
					(number "D23"
						(effects
							(font
								(size 1.27 1.27)
							)
						)
					)
				)
				(pin output line
					(at 55.88 -17.78 180)
					(length 5.08)
					(name "EE_DI"
						(effects
							(font
								(size 1.27 1.27)
							)
						)
					)
					(number "AB3"
						(effects
							(font
								(size 1.27 1.27)
							)
						)
					)
				)
				(pin input line
					(at 55.88 -20.32 180)
					(length 5.08)
					(name "EE_D0"
						(effects
							(font
								(size 1.27 1.27)
							)
						)
					)
					(number "AC4"
						(effects
							(font
								(size 1.27 1.27)
							)
						)
					)
				)
				(pin output line
					(at 55.88 -22.86 180)
					(length 5.08)
					(name "EE_CS_N"
						(effects
							(font
								(size 1.27 1.27)
							)
						)
					)
					(number "AC3"
						(effects
							(font
								(size 1.27 1.27)
							)
						)
					)
				)
				(pin output line
					(at 55.88 -25.4 180)
					(length 5.08)
					(name "EE_CLK"
						(effects
							(font
								(size 1.27 1.27)
							)
						)
					)
					(number "AB4"
						(effects
							(font
								(size 1.27 1.27)
							)
						)
					)
				)
			)
			(symbol "JHL6340SLLSQ_5_0"
				(polyline
					(pts
						(xy 15.24 2.54) (xy 24.13 2.54) (xy 24.13 -58.42) (xy 13.97 -58.42)
					)
					(stroke
						(width 0)
						(type default)
					)
					(fill
						(type none)
					)
				)
				(polyline
					(pts
						(xy 40.64 2.54) (xy 31.75 2.54) (xy 31.75 -58.42) (xy 41.91 -58.42)
					)
					(stroke
						(width 0)
						(type default)
					)
					(fill
						(type none)
					)
				)
				(text "TBT PORT A"
					(at 26.67 -31.75 900)
					(effects
						(font
							(size 1.27 1.27)
							(thickness 0.15)
						)
						(justify left bottom)
					)
				)
				(text "TBT PORT B"
					(at 31.115 -31.75 900)
					(effects
						(font
							(size 1.27 1.27)
							(thickness 0.15)
						)
						(justify left bottom)
					)
				)
			)
			(symbol "JHL6340SLLSQ_5_1"
				(rectangle
					(start 5.08 3.81)
					(end 50.8 -59.69)
					(stroke
						(width 0.254)
						(type default)
					)
					(fill
						(type background)
					)
				)
				(pin input line
					(at 0 0 0)
					(length 5.08)
					(name "PA_RX0_P"
						(effects
							(font
								(size 1.27 1.27)
							)
						)
					)
					(number "B21"
						(effects
							(font
								(size 1.27 1.27)
							)
						)
					)
				)
				(pin input line
					(at 0 -2.54 0)
					(length 5.08)
					(name "PA_RX0_N"
						(effects
							(font
								(size 1.27 1.27)
							)
						)
					)
					(number "A21"
						(effects
							(font
								(size 1.27 1.27)
							)
						)
					)
				)
				(pin input line
					(at 0 -7.62 0)
					(length 5.08)
					(name "PA_RX1_P"
						(effects
							(font
								(size 1.27 1.27)
							)
						)
					)
					(number "A15"
						(effects
							(font
								(size 1.27 1.27)
							)
						)
					)
				)
				(pin input line
					(at 0 -10.16 0)
					(length 5.08)
					(name "PA_RX1_N"
						(effects
							(font
								(size 1.27 1.27)
							)
						)
					)
					(number "B15"
						(effects
							(font
								(size 1.27 1.27)
							)
						)
					)
				)
				(pin output line
					(at 0 -15.24 0)
					(length 5.08)
					(name "PA_TX0_P"
						(effects
							(font
								(size 1.27 1.27)
							)
						)
					)
					(number "A19"
						(effects
							(font
								(size 1.27 1.27)
							)
						)
					)
				)
				(pin output line
					(at 0 -17.78 0)
					(length 5.08)
					(name "PA_TX0_N"
						(effects
							(font
								(size 1.27 1.27)
							)
						)
					)
					(number "B19"
						(effects
							(font
								(size 1.27 1.27)
							)
						)
					)
				)
				(pin output line
					(at 0 -22.86 0)
					(length 5.08)
					(name "PA_TX1_P"
						(effects
							(font
								(size 1.27 1.27)
							)
						)
					)
					(number "A17"
						(effects
							(font
								(size 1.27 1.27)
							)
						)
					)
				)
				(pin output line
					(at 0 -25.4 0)
					(length 5.08)
					(name "PA_TX1_N"
						(effects
							(font
								(size 1.27 1.27)
							)
						)
					)
					(number "B17"
						(effects
							(font
								(size 1.27 1.27)
							)
						)
					)
				)
				(pin bidirectional line
					(at 0 -30.48 0)
					(length 5.08)
					(name "PA_DPSRC_AUX_P"
						(effects
							(font
								(size 1.27 1.27)
							)
						)
					)
					(number "Y15"
						(effects
							(font
								(size 1.27 1.27)
							)
						)
					)
				)
				(pin bidirectional line
					(at 0 -33.02 0)
					(length 5.08)
					(name "PA_DPSRC_AUX_N"
						(effects
							(font
								(size 1.27 1.27)
							)
						)
					)
					(number "W15"
						(effects
							(font
								(size 1.27 1.27)
							)
						)
					)
				)
				(pin bidirectional line
					(at 0 -38.1 0)
					(length 5.08)
					(name "PA_USB2_D_P"
						(effects
							(font
								(size 1.27 1.27)
							)
						)
					)
					(number "E20"
						(effects
							(font
								(size 1.27 1.27)
							)
						)
					)
				)
				(pin bidirectional line
					(at 0 -40.64 0)
					(length 5.08)
					(name "PA_USB2_D_N"
						(effects
							(font
								(size 1.27 1.27)
							)
						)
					)
					(number "D20"
						(effects
							(font
								(size 1.27 1.27)
							)
						)
					)
				)
				(pin output line
					(at 0 -45.72 0)
					(length 5.08)
					(name "PA_LSTX"
						(effects
							(font
								(size 1.27 1.27)
							)
						)
					)
					(number "A5"
						(effects
							(font
								(size 1.27 1.27)
							)
						)
					)
				)
				(pin input line
					(at 0 -48.26 0)
					(length 5.08)
					(name "PA_LSRX"
						(effects
							(font
								(size 1.27 1.27)
							)
						)
					)
					(number "A4"
						(effects
							(font
								(size 1.27 1.27)
							)
						)
					)
				)
				(pin input line
					(at 0 -50.8 0)
					(length 5.08)
					(name "PA_DPSRC_HPD"
						(effects
							(font
								(size 1.27 1.27)
							)
						)
					)
					(number "M4"
						(effects
							(font
								(size 1.27 1.27)
							)
						)
					)
				)
				(pin passive line
					(at 0 -55.88 0)
					(length 5.08)
					(name "PA_USB2_RBIAS"
						(effects
							(font
								(size 1.27 1.27)
							)
						)
					)
					(number "H19"
						(effects
							(font
								(size 1.27 1.27)
							)
						)
					)
				)
				(pin input line
					(at 55.88 0 180)
					(length 5.08)
					(name "PB_RX0_P"
						(effects
							(font
								(size 1.27 1.27)
							)
						)
					)
					(number "A13"
						(effects
							(font
								(size 1.27 1.27)
							)
						)
					)
				)
				(pin input line
					(at 55.88 -2.54 180)
					(length 5.08)
					(name "PB_RX0_N"
						(effects
							(font
								(size 1.27 1.27)
							)
						)
					)
					(number "B13"
						(effects
							(font
								(size 1.27 1.27)
							)
						)
					)
				)
				(pin input line
					(at 55.88 -7.62 180)
					(length 5.08)
					(name "PB_RX1_P"
						(effects
							(font
								(size 1.27 1.27)
							)
						)
					)
					(number "B7"
						(effects
							(font
								(size 1.27 1.27)
							)
						)
					)
				)
				(pin input line
					(at 55.88 -10.16 180)
					(length 5.08)
					(name "PB_RX1_N"
						(effects
							(font
								(size 1.27 1.27)
							)
						)
					)
					(number "A7"
						(effects
							(font
								(size 1.27 1.27)
							)
						)
					)
				)
				(pin output line
					(at 55.88 -15.24 180)
					(length 5.08)
					(name "PB_TX0_P"
						(effects
							(font
								(size 1.27 1.27)
							)
						)
					)
					(number "A11"
						(effects
							(font
								(size 1.27 1.27)
							)
						)
					)
				)
				(pin output line
					(at 55.88 -17.78 180)
					(length 5.08)
					(name "PB_TX0_N"
						(effects
							(font
								(size 1.27 1.27)
							)
						)
					)
					(number "B11"
						(effects
							(font
								(size 1.27 1.27)
							)
						)
					)
				)
				(pin output line
					(at 55.88 -22.86 180)
					(length 5.08)
					(name "PB_TX1_P"
						(effects
							(font
								(size 1.27 1.27)
							)
						)
					)
					(number "A9"
						(effects
							(font
								(size 1.27 1.27)
							)
						)
					)
				)
				(pin output line
					(at 55.88 -25.4 180)
					(length 5.08)
					(name "PB_TX1_N"
						(effects
							(font
								(size 1.27 1.27)
							)
						)
					)
					(number "B9"
						(effects
							(font
								(size 1.27 1.27)
							)
						)
					)
				)
				(pin bidirectional line
					(at 55.88 -30.48 180)
					(length 5.08)
					(name "PB_DPSRC_AUX_P"
						(effects
							(font
								(size 1.27 1.27)
							)
						)
					)
					(number "Y16"
						(effects
							(font
								(size 1.27 1.27)
							)
						)
					)
				)
				(pin bidirectional line
					(at 55.88 -33.02 180)
					(length 5.08)
					(name "PB_DPSRC_AUX_N"
						(effects
							(font
								(size 1.27 1.27)
							)
						)
					)
					(number "W16"
						(effects
							(font
								(size 1.27 1.27)
							)
						)
					)
				)
				(pin bidirectional line
					(at 55.88 -38.1 180)
					(length 5.08)
					(name "PB_USB2_D_P"
						(effects
							(font
								(size 1.27 1.27)
							)
						)
					)
					(number "E19"
						(effects
							(font
								(size 1.27 1.27)
							)
						)
					)
				)
				(pin bidirectional line
					(at 55.88 -40.64 180)
					(length 5.08)
					(name "PB_USB2_D_N"
						(effects
							(font
								(size 1.27 1.27)
							)
						)
					)
					(number "D19"
						(effects
							(font
								(size 1.27 1.27)
							)
						)
					)
				)
				(pin output line
					(at 55.88 -45.72 180)
					(length 5.08)
					(name "PB_LSTX"
						(effects
							(font
								(size 1.27 1.27)
							)
						)
					)
					(number "B4"
						(effects
							(font
								(size 1.27 1.27)
							)
						)
					)
				)
				(pin input line
					(at 55.88 -48.26 180)
					(length 5.08)
					(name "PB_LSRX"
						(effects
							(font
								(size 1.27 1.27)
							)
						)
					)
					(number "B5"
						(effects
							(font
								(size 1.27 1.27)
							)
						)
					)
				)
				(pin input line
					(at 55.88 -50.8 180)
					(length 5.08)
					(name "PB_DPSRC_HPD"
						(effects
							(font
								(size 1.27 1.27)
							)
						)
					)
					(number "G2"
						(effects
							(font
								(size 1.27 1.27)
							)
						)
					)
				)
				(pin passive line
					(at 55.88 -55.88 180)
					(length 5.08)
					(name "PB_USB2_RBIAS"
						(effects
							(font
								(size 1.27 1.27)
							)
						)
					)
					(number "F19"
						(effects
							(font
								(size 1.27 1.27)
							)
						)
					)
				)
			)
			(symbol "JHL6340SLLSQ_6_0"
				(text "DEBUG"
					(at 24.13 -15.24 0)
					(effects
						(font
							(size 1.27 1.27)
							(thickness 0.15)
						)
						(justify left bottom)
					)
				)
			)
			(symbol "JHL6340SLLSQ_6_1"
				(rectangle
					(start 5.08 3.81)
					(end 50.8 -31.75)
					(stroke
						(width 0.254)
						(type default)
					)
					(fill
						(type background)
					)
				)
				(pin passive line
					(at 0 0 0)
					(length 5.08)
					(name "THERMDA2"
						(effects
							(font
								(size 1.27 1.27)
							)
						)
					)
					(number "AB23"
						(effects
							(font
								(size 1.27 1.27)
							)
						)
					)
				)
				(pin passive line
					(at 0 -2.54 0)
					(length 5.08)
					(name "THERMDA1"
						(effects
							(font
								(size 1.27 1.27)
							)
						)
					)
					(number "AC23"
						(effects
							(font
								(size 1.27 1.27)
							)
						)
					)
				)
				(pin passive line
					(at 0 -7.62 0)
					(length 5.08)
					(name "PCIE_ATEST"
						(effects
							(font
								(size 1.27 1.27)
							)
						)
					)
					(number "V18"
						(effects
							(font
								(size 1.27 1.27)
							)
						)
					)
				)
				(pin passive line
					(at 0 -12.7 0)
					(length 5.08)
					(name "TEST_EDM"
						(effects
							(font
								(size 1.27 1.27)
							)
						)
					)
					(number "AC1"
						(effects
							(font
								(size 1.27 1.27)
							)
						)
					)
				)
				(pin passive line
					(at 0 -17.78 0)
					(length 5.08)
					(name "FUSE_VQPS_64"
						(effects
							(font
								(size 1.27 1.27)
							)
						)
					)
					(number "L15"
						(effects
							(font
								(size 1.27 1.27)
							)
						)
					)
				)
				(pin passive line
					(at 0 -20.32 0)
					(length 5.08)
					(name "FUSE_VQPS_128"
						(effects
							(font
								(size 1.27 1.27)
							)
						)
					)
					(number "N15"
						(effects
							(font
								(size 1.27 1.27)
							)
						)
					)
				)
				(pin passive line
					(at 0 -25.4 0)
					(length 5.08)
					(name "MONDC_CIO_0"
						(effects
							(font
								(size 1.27 1.27)
							)
						)
					)
					(number "C23"
						(effects
							(font
								(size 1.27 1.27)
							)
						)
					)
				)
				(pin passive line
					(at 0 -27.94 0)
					(length 5.08)
					(name "MONDC_CIO_1"
						(effects
							(font
								(size 1.27 1.27)
							)
						)
					)
					(number "C22"
						(effects
							(font
								(size 1.27 1.27)
							)
						)
					)
				)
				(pin passive line
					(at 55.88 0 180)
					(length 5.08)
					(name "MONDC_SVR"
						(effects
							(font
								(size 1.27 1.27)
							)
						)
					)
					(number "D6"
						(effects
							(font
								(size 1.27 1.27)
							)
						)
					)
				)
				(pin passive line
					(at 55.88 -5.08 180)
					(length 5.08)
					(name "ATEST_P"
						(effects
							(font
								(size 1.27 1.27)
							)
						)
					)
					(number "A23"
						(effects
							(font
								(size 1.27 1.27)
							)
						)
					)
				)
				(pin passive line
					(at 55.88 -7.62 180)
					(length 5.08)
					(name "ATEST_N"
						(effects
							(font
								(size 1.27 1.27)
							)
						)
					)
					(number "B23"
						(effects
							(font
								(size 1.27 1.27)
							)
						)
					)
				)
				(pin passive line
					(at 55.88 -12.7 180)
					(length 5.08)
					(name "USB2_ATEST"
						(effects
							(font
								(size 1.27 1.27)
							)
						)
					)
					(number "E18"
						(effects
							(font
								(size 1.27 1.27)
							)
						)
					)
				)
				(pin passive line
					(at 55.88 -17.78 180)
					(length 5.08)
					(name "MONDC_DPSNK_0"
						(effects
							(font
								(size 1.27 1.27)
							)
						)
					)
					(number "W13"
						(effects
							(font
								(size 1.27 1.27)
							)
						)
					)
				)
				(pin passive line
					(at 55.88 -20.32 180)
					(length 5.08)
					(name "MONDC_DPSNK_1"
						(effects
							(font
								(size 1.27 1.27)
							)
						)
					)
					(number "W18"
						(effects
							(font
								(size 1.27 1.27)
							)
						)
					)
				)
				(pin passive line
					(at 55.88 -25.4 180)
					(length 5.08)
					(name "MONDC_DPSRC"
						(effects
							(font
								(size 1.27 1.27)
							)
						)
					)
					(number "AB2"
						(effects
							(font
								(size 1.27 1.27)
							)
						)
					)
				)
			)
		)
	(symbol "antmicroInterfaceControllers:TPS65983BAZBHR"
			(exclude_from_sim no)
			(in_bom yes)
			(on_board yes)
			(property "Reference" "U"
				(at 73.66 2.54 0)
				(effects
					(font
						(size 1.27 1.27)
						(thickness 0.15)
					)
					(justify left bottom)
				)
			)
			(property "Value" "TPS65983BAZBHR"
				(at 73.66 0 0)
				(effects
					(font
						(size 1.27 1.27)
						(thickness 0.15)
					)
					(justify left bottom)
					(hide yes)
				)
			)
			(property "Footprint" "antmicro-footprints:IC_TPS65983BAZBHR"
				(at 73.66 -2.54 0)
				(effects
					(font
						(size 1.27 1.27)
						(thickness 0.15)
					)
					(justify left bottom)
					(hide yes)
				)
			)
			(property "Datasheet" "https://www.ti.com/lit/ds/symlink/tps65983b.pdf?ts=1678712702533&ref_url=https%253A%252F%252Fwww.ti.com%252Fproduct%252FTPS65983B"
				(at 73.66 -5.08 0)
				(effects
					(font
						(size 1.27 1.27)
						(thickness 0.15)
					)
					(justify left bottom)
					(hide yes)
				)
			)
			(property "Description" "USB Interface IC Universal USB Type-C and Power Delivery (PD) 3.0 controller 96-NFBGA -10°C to 85"
				(at 73.66 -17.78 0)
				(effects
					(font
						(size 1.27 1.27)
					)
					(justify left bottom)
					(hide yes)
				)
			)
			(property "MPN" "TPS65983BAZBHR"
				(at 73.66 -7.62 0)
				(effects
					(font
						(size 1.27 1.27)
						(thickness 0.15)
					)
					(justify left bottom)
				)
			)
			(property "Manufacturer" "Texas Instruments"
				(at 73.66 -10.16 0)
				(effects
					(font
						(size 1.27 1.27)
						(thickness 0.15)
					)
					(justify left bottom)
					(hide yes)
				)
			)
			(property "Author" "Antmicro"
				(at 73.66 -12.7 0)
				(effects
					(font
						(size 1.27 1.27)
						(thickness 0.15)
					)
					(justify left bottom)
					(hide yes)
				)
			)
			(property "License" "Apache-2.0"
				(at 73.66 -15.24 0)
				(effects
					(font
						(size 1.27 1.27)
						(thickness 0.15)
					)
					(justify left bottom)
					(hide yes)
				)
			)
			(property "ki_keywords" "IC"
				(at 0 0 0)
				(effects
					(font
						(size 1.27 1.27)
					)
					(hide yes)
				)
			)
			(symbol "TPS65983BAZBHR_0_1"
				(rectangle
					(start 3.81 5.08)
					(end 54.61 -129.54)
					(stroke
						(width 0)
						(type default)
					)
					(fill
						(type background)
					)
				)
			)
			(symbol "TPS65983BAZBHR_1_1"
				(pin input line
					(at 0 2.54 0)
					(length 3.81)
					(name "SENSEP"
						(effects
							(font
								(size 1.27 1.27)
							)
						)
					)
					(number "B10"
						(effects
							(font
								(size 1.27 1.27)
							)
						)
					)
				)
				(pin input line
					(at 0 0 0)
					(length 3.81)
					(name "SENSEN"
						(effects
							(font
								(size 1.27 1.27)
							)
						)
					)
					(number "A10"
						(effects
							(font
								(size 1.27 1.27)
							)
						)
					)
				)
				(pin power_in line
					(at 0 -5.08 0)
					(length 3.81)
					(name "PP_HV"
						(effects
							(font
								(size 1.27 1.27)
							)
						)
					)
					(number "A6"
						(effects
							(font
								(size 1.27 1.27)
							)
						)
					)
				)
				(pin power_in line
					(at 0 -5.08 0)
					(length 3.81)
					(hide yes)
					(name "PP_HV"
						(effects
							(font
								(size 1.27 1.27)
							)
						)
					)
					(number "A7"
						(effects
							(font
								(size 1.27 1.27)
							)
						)
					)
				)
				(pin power_in line
					(at 0 -5.08 0)
					(length 3.81)
					(hide yes)
					(name "PP_HV"
						(effects
							(font
								(size 1.27 1.27)
							)
						)
					)
					(number "A8"
						(effects
							(font
								(size 1.27 1.27)
							)
						)
					)
				)
				(pin power_in line
					(at 0 -5.08 0)
					(length 3.81)
					(hide yes)
					(name "PP_HV"
						(effects
							(font
								(size 1.27 1.27)
							)
						)
					)
					(number "B7"
						(effects
							(font
								(size 1.27 1.27)
							)
						)
					)
				)
				(pin power_in line
					(at 0 -10.16 0)
					(length 3.81)
					(name "PP_5V0"
						(effects
							(font
								(size 1.27 1.27)
							)
						)
					)
					(number "A11"
						(effects
							(font
								(size 1.27 1.27)
							)
						)
					)
				)
				(pin power_in line
					(at 0 -10.16 0)
					(length 3.81)
					(hide yes)
					(name "PP_5V0"
						(effects
							(font
								(size 1.27 1.27)
							)
						)
					)
					(number "B11"
						(effects
							(font
								(size 1.27 1.27)
							)
						)
					)
				)
				(pin power_in line
					(at 0 -10.16 0)
					(length 3.81)
					(hide yes)
					(name "PP_5V0"
						(effects
							(font
								(size 1.27 1.27)
							)
						)
					)
					(number "C11"
						(effects
							(font
								(size 1.27 1.27)
							)
						)
					)
				)
				(pin power_in line
					(at 0 -10.16 0)
					(length 3.81)
					(hide yes)
					(name "PP_5V0"
						(effects
							(font
								(size 1.27 1.27)
							)
						)
					)
					(number "D11"
						(effects
							(font
								(size 1.27 1.27)
							)
						)
					)
				)
				(pin power_in line
					(at 0 -15.24 0)
					(length 3.81)
					(name "PP_CABLE"
						(effects
							(font
								(size 1.27 1.27)
							)
						)
					)
					(number "H10"
						(effects
							(font
								(size 1.27 1.27)
							)
						)
					)
				)
				(pin power_in line
					(at 0 -20.32 0)
					(length 3.81)
					(name "VDDIO"
						(effects
							(font
								(size 1.27 1.27)
							)
						)
					)
					(number "B1"
						(effects
							(font
								(size 1.27 1.27)
							)
						)
					)
				)
				(pin power_in line
					(at 0 -25.4 0)
					(length 3.81)
					(name "VIN_3V3"
						(effects
							(font
								(size 1.27 1.27)
							)
						)
					)
					(number "H1"
						(effects
							(font
								(size 1.27 1.27)
							)
						)
					)
				)
				(pin bidirectional line
					(at 0 -30.48 0)
					(length 3.81)
					(name "I2C_SDA1"
						(effects
							(font
								(size 1.27 1.27)
							)
						)
					)
					(number "D1"
						(effects
							(font
								(size 1.27 1.27)
							)
						)
					)
				)
				(pin bidirectional line
					(at 0 -33.02 0)
					(length 3.81)
					(name "I2C_SCL1"
						(effects
							(font
								(size 1.27 1.27)
							)
						)
					)
					(number "D2"
						(effects
							(font
								(size 1.27 1.27)
							)
						)
					)
				)
				(pin output line
					(at 0 -35.56 0)
					(length 3.81)
					(name "I2C_IRQ1Z"
						(effects
							(font
								(size 1.27 1.27)
							)
						)
					)
					(number "C1"
						(effects
							(font
								(size 1.27 1.27)
							)
						)
					)
				)
				(pin bidirectional line
					(at 0 -40.64 0)
					(length 3.81)
					(name "I2C_SDA2"
						(effects
							(font
								(size 1.27 1.27)
							)
						)
					)
					(number "A5"
						(effects
							(font
								(size 1.27 1.27)
							)
						)
					)
				)
				(pin bidirectional line
					(at 0 -43.18 0)
					(length 3.81)
					(name "I2C_SCL2"
						(effects
							(font
								(size 1.27 1.27)
							)
						)
					)
					(number "B5"
						(effects
							(font
								(size 1.27 1.27)
							)
						)
					)
				)
				(pin output line
					(at 0 -45.72 0)
					(length 3.81)
					(name "I2C_IRQ2Z"
						(effects
							(font
								(size 1.27 1.27)
							)
						)
					)
					(number "B6"
						(effects
							(font
								(size 1.27 1.27)
							)
						)
					)
				)
				(pin bidirectional line
					(at 0 -50.8 0)
					(length 3.81)
					(name "GPIO0(HD3_AMSEL)"
						(effects
							(font
								(size 1.27 1.27)
							)
						)
					)
					(number "B2"
						(effects
							(font
								(size 1.27 1.27)
							)
						)
					)
				)
				(pin bidirectional line
					(at 0 -53.34 0)
					(length 3.81)
					(name "GPIO1(CONFIG0)"
						(effects
							(font
								(size 1.27 1.27)
							)
						)
					)
					(number "C2"
						(effects
							(font
								(size 1.27 1.27)
							)
						)
					)
				)
				(pin bidirectional line
					(at 0 -55.88 0)
					(length 3.81)
					(name "GPIO2"
						(effects
							(font
								(size 1.27 1.27)
							)
						)
					)
					(number "D10"
						(effects
							(font
								(size 1.27 1.27)
							)
						)
					)
				)
				(pin bidirectional line
					(at 0 -58.42 0)
					(length 3.81)
					(name "GPIO3(HD3_EN)"
						(effects
							(font
								(size 1.27 1.27)
							)
						)
					)
					(number "G11"
						(effects
							(font
								(size 1.27 1.27)
							)
						)
					)
				)
				(pin bidirectional line
					(at 0 -60.96 0)
					(length 3.81)
					(name "GPIO4(HPD_TXRX)"
						(effects
							(font
								(size 1.27 1.27)
							)
						)
					)
					(number "C10"
						(effects
							(font
								(size 1.27 1.27)
							)
						)
					)
				)
				(pin bidirectional line
					(at 0 -63.5 0)
					(length 3.81)
					(name "GPIO5(HPD_RX)"
						(effects
							(font
								(size 1.27 1.27)
							)
						)
					)
					(number "E10"
						(effects
							(font
								(size 1.27 1.27)
							)
						)
					)
				)
				(pin bidirectional line
					(at 0 -66.04 0)
					(length 3.81)
					(name "GPIO6"
						(effects
							(font
								(size 1.27 1.27)
							)
						)
					)
					(number "G10"
						(effects
							(font
								(size 1.27 1.27)
							)
						)
					)
				)
				(pin bidirectional line
					(at 0 -68.58 0)
					(length 3.81)
					(name "GPIO7"
						(effects
							(font
								(size 1.27 1.27)
							)
						)
					)
					(number "D7"
						(effects
							(font
								(size 1.27 1.27)
							)
						)
					)
				)
				(pin bidirectional line
					(at 0 -71.12 0)
					(length 3.81)
					(name "GPIO8"
						(effects
							(font
								(size 1.27 1.27)
							)
						)
					)
					(number "H6"
						(effects
							(font
								(size 1.27 1.27)
							)
						)
					)
				)
				(pin output line
					(at 0 -76.2 0)
					(length 3.81)
					(name "SPI_CLK"
						(effects
							(font
								(size 1.27 1.27)
							)
						)
					)
					(number "A3"
						(effects
							(font
								(size 1.27 1.27)
							)
						)
					)
				)
				(pin output line
					(at 0 -78.74 0)
					(length 3.81)
					(name "SPI_PICO"
						(effects
							(font
								(size 1.27 1.27)
							)
						)
					)
					(number "B4"
						(effects
							(font
								(size 1.27 1.27)
							)
						)
					)
				)
				(pin input line
					(at 0 -81.28 0)
					(length 3.81)
					(name "SPI_POCI"
						(effects
							(font
								(size 1.27 1.27)
							)
						)
					)
					(number "A4"
						(effects
							(font
								(size 1.27 1.27)
							)
						)
					)
				)
				(pin output line
					(at 0 -83.82 0)
					(length 3.81)
					(name "SPI_CSZ"
						(effects
							(font
								(size 1.27 1.27)
							)
						)
					)
					(number "B3"
						(effects
							(font
								(size 1.27 1.27)
							)
						)
					)
				)
				(pin bidirectional line
					(at 0 -88.9 0)
					(length 3.81)
					(name "SWD_DATA"
						(effects
							(font
								(size 1.27 1.27)
							)
						)
					)
					(number "F4"
						(effects
							(font
								(size 1.27 1.27)
							)
						)
					)
				)
				(pin input line
					(at 0 -91.44 0)
					(length 3.81)
					(name "SWD_CLK"
						(effects
							(font
								(size 1.27 1.27)
							)
						)
					)
					(number "G4"
						(effects
							(font
								(size 1.27 1.27)
							)
						)
					)
				)
				(pin input line
					(at 0 -96.52 0)
					(length 3.81)
					(name "UART_RX"
						(effects
							(font
								(size 1.27 1.27)
							)
						)
					)
					(number "F2"
						(effects
							(font
								(size 1.27 1.27)
							)
						)
					)
				)
				(pin output line
					(at 0 -99.06 0)
					(length 3.81)
					(name "UART_TX"
						(effects
							(font
								(size 1.27 1.27)
							)
						)
					)
					(number "E2"
						(effects
							(font
								(size 1.27 1.27)
							)
						)
					)
				)
				(pin input line
					(at 0 -104.14 0)
					(length 3.81)
					(name "LSX_R2P"
						(effects
							(font
								(size 1.27 1.27)
							)
						)
					)
					(number "L4"
						(effects
							(font
								(size 1.27 1.27)
							)
						)
					)
				)
				(pin output line
					(at 0 -106.68 0)
					(length 3.81)
					(name "LSX_P2R"
						(effects
							(font
								(size 1.27 1.27)
							)
						)
					)
					(number "K4"
						(effects
							(font
								(size 1.27 1.27)
							)
						)
					)
				)
				(pin bidirectional line
					(at 0 -111.76 0)
					(length 3.81)
					(name "AUX_P"
						(effects
							(font
								(size 1.27 1.27)
							)
						)
					)
					(number "J1"
						(effects
							(font
								(size 1.27 1.27)
							)
						)
					)
				)
				(pin bidirectional line
					(at 0 -114.3 0)
					(length 3.81)
					(name "AUX_N"
						(effects
							(font
								(size 1.27 1.27)
							)
						)
					)
					(number "J2"
						(effects
							(font
								(size 1.27 1.27)
							)
						)
					)
				)
				(pin bidirectional line
					(at 0 -119.38 0)
					(length 3.81)
					(name "USB_RP_P"
						(effects
							(font
								(size 1.27 1.27)
							)
						)
					)
					(number "L5"
						(effects
							(font
								(size 1.27 1.27)
							)
						)
					)
				)
				(pin bidirectional line
					(at 0 -121.92 0)
					(length 3.81)
					(name "USB_RP_N"
						(effects
							(font
								(size 1.27 1.27)
							)
						)
					)
					(number "K5"
						(effects
							(font
								(size 1.27 1.27)
							)
						)
					)
				)
				(pin power_in line
					(at 0 -127 0)
					(length 3.81)
					(name "GND"
						(effects
							(font
								(size 1.27 1.27)
							)
						)
					)
					(number "A1"
						(effects
							(font
								(size 1.27 1.27)
							)
						)
					)
				)
				(pin power_in line
					(at 0 -127 0)
					(length 3.81)
					(hide yes)
					(name "GND"
						(effects
							(font
								(size 1.27 1.27)
							)
						)
					)
					(number "B8"
						(effects
							(font
								(size 1.27 1.27)
							)
						)
					)
				)
				(pin power_in line
					(at 0 -127 0)
					(length 3.81)
					(hide yes)
					(name "GND"
						(effects
							(font
								(size 1.27 1.27)
							)
						)
					)
					(number "D8"
						(effects
							(font
								(size 1.27 1.27)
							)
						)
					)
				)
				(pin power_in line
					(at 0 -127 0)
					(length 3.81)
					(hide yes)
					(name "GND"
						(effects
							(font
								(size 1.27 1.27)
							)
						)
					)
					(number "E5"
						(effects
							(font
								(size 1.27 1.27)
							)
						)
					)
				)
				(pin power_in line
					(at 0 -127 0)
					(length 3.81)
					(hide yes)
					(name "GND"
						(effects
							(font
								(size 1.27 1.27)
							)
						)
					)
					(number "E6"
						(effects
							(font
								(size 1.27 1.27)
							)
						)
					)
				)
				(pin power_in line
					(at 0 -127 0)
					(length 3.81)
					(hide yes)
					(name "GND"
						(effects
							(font
								(size 1.27 1.27)
							)
						)
					)
					(number "E7"
						(effects
							(font
								(size 1.27 1.27)
							)
						)
					)
				)
				(pin power_in line
					(at 0 -127 0)
					(length 3.81)
					(hide yes)
					(name "GND"
						(effects
							(font
								(size 1.27 1.27)
							)
						)
					)
					(number "E8"
						(effects
							(font
								(size 1.27 1.27)
							)
						)
					)
				)
				(pin power_in line
					(at 0 -127 0)
					(length 3.81)
					(hide yes)
					(name "GND"
						(effects
							(font
								(size 1.27 1.27)
							)
						)
					)
					(number "F5"
						(effects
							(font
								(size 1.27 1.27)
							)
						)
					)
				)
				(pin power_in line
					(at 0 -127 0)
					(length 3.81)
					(hide yes)
					(name "GND"
						(effects
							(font
								(size 1.27 1.27)
							)
						)
					)
					(number "F6"
						(effects
							(font
								(size 1.27 1.27)
							)
						)
					)
				)
				(pin power_in line
					(at 0 -127 0)
					(length 3.81)
					(hide yes)
					(name "GND"
						(effects
							(font
								(size 1.27 1.27)
							)
						)
					)
					(number "F7"
						(effects
							(font
								(size 1.27 1.27)
							)
						)
					)
				)
				(pin power_in line
					(at 0 -127 0)
					(length 3.81)
					(hide yes)
					(name "GND"
						(effects
							(font
								(size 1.27 1.27)
							)
						)
					)
					(number "F8"
						(effects
							(font
								(size 1.27 1.27)
							)
						)
					)
				)
				(pin power_in line
					(at 0 -127 0)
					(length 3.81)
					(hide yes)
					(name "GND"
						(effects
							(font
								(size 1.27 1.27)
							)
						)
					)
					(number "G5"
						(effects
							(font
								(size 1.27 1.27)
							)
						)
					)
				)
				(pin power_in line
					(at 0 -127 0)
					(length 3.81)
					(hide yes)
					(name "GND"
						(effects
							(font
								(size 1.27 1.27)
							)
						)
					)
					(number "G6"
						(effects
							(font
								(size 1.27 1.27)
							)
						)
					)
				)
				(pin power_in line
					(at 0 -127 0)
					(length 3.81)
					(hide yes)
					(name "GND"
						(effects
							(font
								(size 1.27 1.27)
							)
						)
					)
					(number "G7"
						(effects
							(font
								(size 1.27 1.27)
							)
						)
					)
				)
				(pin power_in line
					(at 0 -127 0)
					(length 3.81)
					(hide yes)
					(name "GND"
						(effects
							(font
								(size 1.27 1.27)
							)
						)
					)
					(number "G8"
						(effects
							(font
								(size 1.27 1.27)
							)
						)
					)
				)
				(pin power_in line
					(at 0 -127 0)
					(length 3.81)
					(hide yes)
					(name "GND"
						(effects
							(font
								(size 1.27 1.27)
							)
						)
					)
					(number "H4"
						(effects
							(font
								(size 1.27 1.27)
							)
						)
					)
				)
				(pin power_in line
					(at 0 -127 0)
					(length 3.81)
					(hide yes)
					(name "GND"
						(effects
							(font
								(size 1.27 1.27)
							)
						)
					)
					(number "H5"
						(effects
							(font
								(size 1.27 1.27)
							)
						)
					)
				)
				(pin power_in line
					(at 0 -127 0)
					(length 3.81)
					(hide yes)
					(name "GND"
						(effects
							(font
								(size 1.27 1.27)
							)
						)
					)
					(number "H8"
						(effects
							(font
								(size 1.27 1.27)
							)
						)
					)
				)
				(pin power_in line
					(at 0 -127 0)
					(length 3.81)
					(hide yes)
					(name "GND"
						(effects
							(font
								(size 1.27 1.27)
							)
						)
					)
					(number "L1"
						(effects
							(font
								(size 1.27 1.27)
							)
						)
					)
				)
				(pin no_connect line
					(at 3.81 -123.19 0)
					(length 3.81)
					(hide yes)
					(name "NC"
						(effects
							(font
								(size 1.27 1.27)
							)
						)
					)
					(number "L11"
						(effects
							(font
								(size 1.27 1.27)
							)
						)
					)
				)
				(pin output line
					(at 58.42 2.54 180)
					(length 3.81)
					(name "HV_GATE1"
						(effects
							(font
								(size 1.27 1.27)
							)
						)
					)
					(number "B9"
						(effects
							(font
								(size 1.27 1.27)
							)
						)
					)
				)
				(pin output line
					(at 58.42 0 180)
					(length 3.81)
					(name "HV_GATE2"
						(effects
							(font
								(size 1.27 1.27)
							)
						)
					)
					(number "A9"
						(effects
							(font
								(size 1.27 1.27)
							)
						)
					)
				)
				(pin power_in line
					(at 58.42 -5.08 180)
					(length 3.81)
					(name "VBUS"
						(effects
							(font
								(size 1.27 1.27)
							)
						)
					)
					(number "H11"
						(effects
							(font
								(size 1.27 1.27)
							)
						)
					)
				)
				(pin power_in line
					(at 58.42 -5.08 180)
					(length 3.81)
					(hide yes)
					(name "VBUS"
						(effects
							(font
								(size 1.27 1.27)
							)
						)
					)
					(number "J10"
						(effects
							(font
								(size 1.27 1.27)
							)
						)
					)
				)
				(pin power_in line
					(at 58.42 -5.08 180)
					(length 3.81)
					(hide yes)
					(name "VBUS"
						(effects
							(font
								(size 1.27 1.27)
							)
						)
					)
					(number "J11"
						(effects
							(font
								(size 1.27 1.27)
							)
						)
					)
				)
				(pin power_in line
					(at 58.42 -5.08 180)
					(length 3.81)
					(hide yes)
					(name "VBUS"
						(effects
							(font
								(size 1.27 1.27)
							)
						)
					)
					(number "K11"
						(effects
							(font
								(size 1.27 1.27)
							)
						)
					)
				)
				(pin power_out line
					(at 58.42 -7.62 180)
					(length 3.81)
					(name "VOUT_3V3"
						(effects
							(font
								(size 1.27 1.27)
							)
						)
					)
					(number "H2"
						(effects
							(font
								(size 1.27 1.27)
							)
						)
					)
				)
				(pin power_out line
					(at 58.42 -12.7 180)
					(length 3.81)
					(name "LDO_3V3"
						(effects
							(font
								(size 1.27 1.27)
							)
						)
					)
					(number "G1"
						(effects
							(font
								(size 1.27 1.27)
							)
						)
					)
				)
				(pin power_out line
					(at 58.42 -17.78 180)
					(length 3.81)
					(name "LDO_1V8A"
						(effects
							(font
								(size 1.27 1.27)
							)
						)
					)
					(number "K1"
						(effects
							(font
								(size 1.27 1.27)
							)
						)
					)
				)
				(pin power_out line
					(at 58.42 -22.86 180)
					(length 3.81)
					(name "LDO_1V8D"
						(effects
							(font
								(size 1.27 1.27)
							)
						)
					)
					(number "A2"
						(effects
							(font
								(size 1.27 1.27)
							)
						)
					)
				)
				(pin power_out line
					(at 58.42 -27.94 180)
					(length 3.81)
					(name "LDO_BMC"
						(effects
							(font
								(size 1.27 1.27)
							)
						)
					)
					(number "E1"
						(effects
							(font
								(size 1.27 1.27)
							)
						)
					)
				)
				(pin bidirectional line
					(at 58.42 -33.02 180)
					(length 3.81)
					(name "C_CC1"
						(effects
							(font
								(size 1.27 1.27)
							)
						)
					)
					(number "L9"
						(effects
							(font
								(size 1.27 1.27)
							)
						)
					)
				)
				(pin bidirectional line
					(at 58.42 -35.56 180)
					(length 3.81)
					(name "C_CC2"
						(effects
							(font
								(size 1.27 1.27)
							)
						)
					)
					(number "L10"
						(effects
							(font
								(size 1.27 1.27)
							)
						)
					)
				)
				(pin bidirectional line
					(at 58.42 -40.64 180)
					(length 3.81)
					(name "RPD_G1"
						(effects
							(font
								(size 1.27 1.27)
							)
						)
					)
					(number "K9"
						(effects
							(font
								(size 1.27 1.27)
							)
						)
					)
				)
				(pin bidirectional line
					(at 58.42 -43.18 180)
					(length 3.81)
					(name "RPD_G2"
						(effects
							(font
								(size 1.27 1.27)
							)
						)
					)
					(number "K10"
						(effects
							(font
								(size 1.27 1.27)
							)
						)
					)
				)
				(pin bidirectional line
					(at 58.42 -48.26 180)
					(length 3.81)
					(name "C_USB_TP"
						(effects
							(font
								(size 1.27 1.27)
							)
						)
					)
					(number "K6"
						(effects
							(font
								(size 1.27 1.27)
							)
						)
					)
				)
				(pin bidirectional line
					(at 58.42 -50.8 180)
					(length 3.81)
					(name "C_USB_TN"
						(effects
							(font
								(size 1.27 1.27)
							)
						)
					)
					(number "L6"
						(effects
							(font
								(size 1.27 1.27)
							)
						)
					)
				)
				(pin bidirectional line
					(at 58.42 -55.88 180)
					(length 3.81)
					(name "C_USB_BP"
						(effects
							(font
								(size 1.27 1.27)
							)
						)
					)
					(number "K7"
						(effects
							(font
								(size 1.27 1.27)
							)
						)
					)
				)
				(pin bidirectional line
					(at 58.42 -58.42 180)
					(length 3.81)
					(name "C_USB_BN"
						(effects
							(font
								(size 1.27 1.27)
							)
						)
					)
					(number "L7"
						(effects
							(font
								(size 1.27 1.27)
							)
						)
					)
				)
				(pin bidirectional line
					(at 58.42 -63.5 180)
					(length 3.81)
					(name "C_SBU1"
						(effects
							(font
								(size 1.27 1.27)
							)
						)
					)
					(number "K8"
						(effects
							(font
								(size 1.27 1.27)
							)
						)
					)
				)
				(pin bidirectional line
					(at 58.42 -66.04 180)
					(length 3.81)
					(name "C_SBU2"
						(effects
							(font
								(size 1.27 1.27)
							)
						)
					)
					(number "L8"
						(effects
							(font
								(size 1.27 1.27)
							)
						)
					)
				)
				(pin bidirectional line
					(at 58.42 -71.12 180)
					(length 3.81)
					(name "DEBUG4(GPIO12,CONFIG2)"
						(effects
							(font
								(size 1.27 1.27)
							)
						)
					)
					(number "K3"
						(effects
							(font
								(size 1.27 1.27)
							)
						)
					)
				)
				(pin bidirectional line
					(at 58.42 -73.66 180)
					(length 3.81)
					(name "DEBUG3(GPIO13,CONFIG1)"
						(effects
							(font
								(size 1.27 1.27)
							)
						)
					)
					(number "L3"
						(effects
							(font
								(size 1.27 1.27)
							)
						)
					)
				)
				(pin bidirectional line
					(at 58.42 -76.2 180)
					(length 3.81)
					(name "DEBUG2(GPIO14,HD3POL)"
						(effects
							(font
								(size 1.27 1.27)
							)
						)
					)
					(number "K2"
						(effects
							(font
								(size 1.27 1.27)
							)
						)
					)
				)
				(pin bidirectional line
					(at 58.42 -78.74 180)
					(length 3.81)
					(name "DEBUG1(GPIO15)"
						(effects
							(font
								(size 1.27 1.27)
							)
						)
					)
					(number "L2"
						(effects
							(font
								(size 1.27 1.27)
							)
						)
					)
				)
				(pin bidirectional line
					(at 58.42 -83.82 180)
					(length 3.81)
					(name "DEBUG_CTL2(GPIO17,_I2CADDR_B5)"
						(effects
							(font
								(size 1.27 1.27)
							)
						)
					)
					(number "D5"
						(effects
							(font
								(size 1.27 1.27)
							)
						)
					)
				)
				(pin bidirectional line
					(at 58.42 -86.36 180)
					(length 3.81)
					(name "DEBUG_CTL1(GPIO16,_I2CADDR_B4)"
						(effects
							(font
								(size 1.27 1.27)
							)
						)
					)
					(number "E4"
						(effects
							(font
								(size 1.27 1.27)
							)
						)
					)
				)
				(pin bidirectional line
					(at 58.42 -91.44 180)
					(length 3.81)
					(name "I2C_ADDR"
						(effects
							(font
								(size 1.27 1.27)
							)
						)
					)
					(number "F1"
						(effects
							(font
								(size 1.27 1.27)
							)
						)
					)
				)
				(pin bidirectional line
					(at 58.42 -96.52 180)
					(length 3.81)
					(name "RESETZ(GPIO9)"
						(effects
							(font
								(size 1.27 1.27)
							)
						)
					)
					(number "F11"
						(effects
							(font
								(size 1.27 1.27)
							)
						)
					)
				)
				(pin bidirectional line
					(at 58.42 -101.6 180)
					(length 3.81)
					(name "MRESET(GPIO11)"
						(effects
							(font
								(size 1.27 1.27)
							)
						)
					)
					(number "E11"
						(effects
							(font
								(size 1.27 1.27)
							)
						)
					)
				)
				(pin input line
					(at 58.42 -106.68 180)
					(length 3.81)
					(name "HRESET"
						(effects
							(font
								(size 1.27 1.27)
							)
						)
					)
					(number "D6"
						(effects
							(font
								(size 1.27 1.27)
							)
						)
					)
				)
				(pin bidirectional line
					(at 58.42 -111.76 180)
					(length 3.81)
					(name "BUSPOWERZ(GPIO10)"
						(effects
							(font
								(size 1.27 1.27)
							)
						)
					)
					(number "F10"
						(effects
							(font
								(size 1.27 1.27)
							)
						)
					)
				)
				(pin bidirectional line
					(at 58.42 -116.84 180)
					(length 3.81)
					(name "R_OSC"
						(effects
							(font
								(size 1.27 1.27)
							)
						)
					)
					(number "G2"
						(effects
							(font
								(size 1.27 1.27)
							)
						)
					)
				)
				(pin output line
					(at 58.42 -121.92 180)
					(length 3.81)
					(name "SS"
						(effects
							(font
								(size 1.27 1.27)
							)
						)
					)
					(number "H7"
						(effects
							(font
								(size 1.27 1.27)
							)
						)
					)
				)
			)
		)
	(symbol "antmicroLEDIndicationDiscrete:LED_G_0603_KP-1608CGCK"
			(pin_numbers
				(hide yes)
			)
			(pin_names
				(hide yes)
			)
			(exclude_from_sim no)
			(in_bom yes)
			(on_board yes)
			(property "Reference" "D"
				(at 22.86 -2.54 0)
				(effects
					(font
						(size 1.27 1.27)
						(thickness 0.15)
					)
					(justify left bottom)
				)
			)
			(property "Value" "LED_G_0603_KP-1608CGCK"
				(at 22.86 -7.62 0)
				(effects
					(font
						(size 1.27 1.27)
						(thickness 0.15)
					)
					(justify left bottom)
					(hide yes)
				)
			)
			(property "Footprint" "antmicro-footprints:LED_0603_1608Metric_G"
				(at 22.86 -10.16 0)
				(effects
					(font
						(size 1.27 1.27)
						(thickness 0.15)
					)
					(justify left bottom)
					(hide yes)
				)
			)
			(property "Datasheet" "http://www.kingbright.com/attachments/file/psearch//000/00/00/KP-1608CGCK(Ver.23B).pdf"
				(at 22.86 -12.7 0)
				(effects
					(font
						(size 1.27 1.27)
						(thickness 0.15)
					)
					(justify left bottom)
					(hide yes)
				)
			)
			(property "Description" "LED, Green, SMD, 0603, 20 mA, 2.1 V, 570 nm"
				(at 22.86 -25.4 0)
				(effects
					(font
						(size 1.27 1.27)
					)
					(justify left bottom)
					(hide yes)
				)
			)
			(property "MPN" "KP-1608CGCK"
				(at 22.86 -15.24 0)
				(effects
					(font
						(size 1.27 1.27)
						(thickness 0.15)
					)
					(justify left bottom)
					(hide yes)
				)
			)
			(property "Manufacturer" "Kingbright"
				(at 22.86 -17.78 0)
				(effects
					(font
						(size 1.27 1.27)
						(thickness 0.15)
					)
					(justify left bottom)
					(hide yes)
				)
			)
			(property "Color" "Green"
				(at 22.86 -5.08 0)
				(effects
					(font
						(size 1.27 1.27)
					)
					(justify left bottom)
				)
			)
			(property "Author" "Antmicro"
				(at 22.86 -20.32 0)
				(effects
					(font
						(size 1.27 1.27)
						(thickness 0.15)
					)
					(justify left bottom)
					(hide yes)
				)
			)
			(property "License" "Apache-2.0"
				(at 22.86 -22.86 0)
				(effects
					(font
						(size 1.27 1.27)
						(thickness 0.15)
					)
					(justify left bottom)
					(hide yes)
				)
			)
			(property "ki_keywords" "SMT, DIODE, SEMICONDUCTOR, LED"
				(at 0 0 0)
				(effects
					(font
						(size 1.27 1.27)
					)
					(hide yes)
				)
			)
			(symbol "LED_G_0603_KP-1608CGCK_0_1"
				(polyline
					(pts
						(xy 1.905 0) (xy 0.635 0)
					)
					(stroke
						(width 0)
						(type default)
					)
					(fill
						(type none)
					)
				)
				(polyline
					(pts
						(xy 4.445 0) (xy 3.175 0)
					)
					(stroke
						(width 0)
						(type default)
					)
					(fill
						(type none)
					)
				)
			)
			(symbol "LED_G_0603_KP-1608CGCK_1_1"
				(polyline
					(pts
						(xy 1.143 2.286) (xy 1.143 1.778) (xy 1.143 2.286) (xy 1.651 2.286) (xy 1.143 2.286) (xy 2.159 1.27)
					)
					(stroke
						(width 0.254)
						(type default)
					)
					(fill
						(type none)
					)
				)
				(polyline
					(pts
						(xy 1.778 1.016) (xy 1.778 -1.016)
					)
					(stroke
						(width 0.254)
						(type default)
					)
					(fill
						(type none)
					)
				)
				(polyline
					(pts
						(xy 2.159 2.54) (xy 2.159 2.032) (xy 2.159 2.54) (xy 2.667 2.54) (xy 2.159 2.54) (xy 3.048 1.651)
					)
					(stroke
						(width 0.254)
						(type default)
					)
					(fill
						(type none)
					)
				)
				(polyline
					(pts
						(xy 3.302 1.016) (xy 3.302 -1.016) (xy 1.778 0) (xy 3.302 1.016)
					)
					(stroke
						(width 0.254)
						(type default)
					)
					(fill
						(type outline)
					)
				)
				(pin passive line
					(at 0 0 0)
					(length 0.635)
					(name "C"
						(effects
							(font
								(size 1.27 1.27)
							)
						)
					)
					(number "1"
						(effects
							(font
								(size 1.27 1.27)
							)
						)
					)
				)
				(pin passive line
					(at 5.08 0 180)
					(length 0.635)
					(name "A"
						(effects
							(font
								(size 1.27 1.27)
							)
						)
					)
					(number "2"
						(effects
							(font
								(size 1.27 1.27)
							)
						)
					)
				)
			)
		)
	(symbol "antmicroLEDIndicationDiscrete:LED_G_0603_LG_L29K-G2J1-24-Z"
			(pin_numbers
				(hide yes)
			)
			(pin_names
				(hide yes)
			)
			(exclude_from_sim no)
			(in_bom yes)
			(on_board yes)
			(property "Reference" "D"
				(at 20.32 -2.54 0)
				(effects
					(font
						(size 1.27 1.27)
						(thickness 0.15)
					)
					(justify left bottom)
				)
			)
			(property "Value" "LED_G_0603_LG_L29K-G2J1-24-Z"
				(at 20.32 -7.62 0)
				(effects
					(font
						(size 1.27 1.27)
						(thickness 0.15)
					)
					(justify left bottom)
					(hide yes)
				)
			)
			(property "Footprint" "antmicro-footprints:LED_0603_1608Metric_G"
				(at 20.32 -10.16 0)
				(effects
					(font
						(size 1.27 1.27)
						(thickness 0.15)
					)
					(justify left bottom)
					(hide yes)
				)
			)
			(property "Datasheet" "https://look.ams-osram.com/m/19ee86b3ae0ee95b/original/LG-L29K.pdf"
				(at 20.32 -12.7 0)
				(effects
					(font
						(size 1.27 1.27)
						(thickness 0.15)
					)
					(justify left bottom)
					(hide yes)
				)
			)
			(property "Description" "LED, Green, SMD, 0603, 20 mA, 1.7 V, 570 nm"
				(at 20.32 -25.4 0)
				(effects
					(font
						(size 1.27 1.27)
					)
					(justify left bottom)
					(hide yes)
				)
			)
			(property "MPN" "LG L29K-G2J1-24-Z"
				(at 20.32 -15.24 0)
				(effects
					(font
						(size 1.27 1.27)
						(thickness 0.15)
					)
					(justify left bottom)
					(hide yes)
				)
			)
			(property "Manufacturer" "OSRAM"
				(at 20.32 -17.78 0)
				(effects
					(font
						(size 1.27 1.27)
						(thickness 0.15)
					)
					(justify left bottom)
					(hide yes)
				)
			)
			(property "Color" "Green"
				(at 20.32 -5.08 0)
				(effects
					(font
						(size 1.27 1.27)
					)
					(justify left bottom)
				)
			)
			(property "Author" "Antmicro"
				(at 20.32 -20.32 0)
				(effects
					(font
						(size 1.27 1.27)
						(thickness 0.15)
					)
					(justify left bottom)
					(hide yes)
				)
			)
			(property "License" "Apache-2.0"
				(at 20.32 -22.86 0)
				(effects
					(font
						(size 1.27 1.27)
						(thickness 0.15)
					)
					(justify left bottom)
					(hide yes)
				)
			)
			(property "ki_keywords" "SMT, DIODE, SEMICONDUCTOR, LED"
				(at 0 0 0)
				(effects
					(font
						(size 1.27 1.27)
					)
					(hide yes)
				)
			)
			(symbol "LED_G_0603_LG_L29K-G2J1-24-Z_0_1"
				(polyline
					(pts
						(xy 1.905 0) (xy 0.635 0)
					)
					(stroke
						(width 0)
						(type default)
					)
					(fill
						(type none)
					)
				)
				(polyline
					(pts
						(xy 4.445 0) (xy 3.175 0)
					)
					(stroke
						(width 0)
						(type default)
					)
					(fill
						(type none)
					)
				)
			)
			(symbol "LED_G_0603_LG_L29K-G2J1-24-Z_1_1"
				(polyline
					(pts
						(xy 1.143 2.286) (xy 1.143 1.778) (xy 1.143 2.286) (xy 1.651 2.286) (xy 1.143 2.286) (xy 2.159 1.27)
					)
					(stroke
						(width 0.254)
						(type default)
					)
					(fill
						(type none)
					)
				)
				(polyline
					(pts
						(xy 1.778 1.016) (xy 1.778 -1.016)
					)
					(stroke
						(width 0.254)
						(type default)
					)
					(fill
						(type none)
					)
				)
				(polyline
					(pts
						(xy 2.159 2.54) (xy 2.159 2.032) (xy 2.159 2.54) (xy 2.667 2.54) (xy 2.159 2.54) (xy 3.048 1.651)
					)
					(stroke
						(width 0.254)
						(type default)
					)
					(fill
						(type none)
					)
				)
				(polyline
					(pts
						(xy 3.302 1.016) (xy 3.302 -1.016) (xy 1.778 0) (xy 3.302 1.016)
					)
					(stroke
						(width 0.254)
						(type default)
					)
					(fill
						(type outline)
					)
				)
				(pin passive line
					(at 0 0 0)
					(length 0.635)
					(name "C"
						(effects
							(font
								(size 1.27 1.27)
							)
						)
					)
					(number "1"
						(effects
							(font
								(size 1.27 1.27)
							)
						)
					)
				)
				(pin passive line
					(at 5.08 0 180)
					(length 0.635)
					(name "A"
						(effects
							(font
								(size 1.27 1.27)
							)
						)
					)
					(number "2"
						(effects
							(font
								(size 1.27 1.27)
							)
						)
					)
				)
			)
		)
	(symbol "antmicroLEDIndicationDiscrete:LED_G_0603_LTST-C190GKT"
			(pin_numbers
				(hide yes)
			)
			(pin_names
				(hide yes)
			)
			(exclude_from_sim no)
			(in_bom yes)
			(on_board yes)
			(property "Reference" "D"
				(at 22.86 -2.54 0)
				(effects
					(font
						(size 1.27 1.27)
						(thickness 0.15)
					)
					(justify left bottom)
				)
			)
			(property "Value" "LED_G_0603_LTST-C190GKT"
				(at 22.86 -7.62 0)
				(effects
					(font
						(size 1.27 1.27)
						(thickness 0.15)
					)
					(justify left bottom)
					(hide yes)
				)
			)
			(property "Footprint" "antmicro-footprints:LED_0603_1608Metric_G"
				(at 22.86 -10.16 0)
				(effects
					(font
						(size 1.27 1.27)
						(thickness 0.15)
					)
					(justify left bottom)
					(hide yes)
				)
			)
			(property "Datasheet" "https://media.digikey.com/pdf/Data%20Sheets/Lite-On%20PDFs/LTST-C190GKT.pdf"
				(at 22.86 -12.7 0)
				(effects
					(font
						(size 1.27 1.27)
						(thickness 0.15)
					)
					(justify left bottom)
					(hide yes)
				)
			)
			(property "Description" "LED, Green, SMD, 0603, 20 mA, 2.1 V, 569 nm"
				(at 22.86 -25.4 0)
				(effects
					(font
						(size 1.27 1.27)
					)
					(justify left bottom)
					(hide yes)
				)
			)
			(property "MPN" "LTST-C190GKT"
				(at 22.86 -15.24 0)
				(effects
					(font
						(size 1.27 1.27)
						(thickness 0.15)
					)
					(justify left bottom)
					(hide yes)
				)
			)
			(property "Manufacturer" "Lite-On"
				(at 22.86 -17.78 0)
				(effects
					(font
						(size 1.27 1.27)
						(thickness 0.15)
					)
					(justify left bottom)
					(hide yes)
				)
			)
			(property "Color" "Green"
				(at 22.86 -5.08 0)
				(effects
					(font
						(size 1.27 1.27)
					)
					(justify left bottom)
				)
			)
			(property "Author" "Antmicro"
				(at 22.86 -20.32 0)
				(effects
					(font
						(size 1.27 1.27)
						(thickness 0.15)
					)
					(justify left bottom)
					(hide yes)
				)
			)
			(property "License" "Apache-2.0"
				(at 22.86 -22.86 0)
				(effects
					(font
						(size 1.27 1.27)
						(thickness 0.15)
					)
					(justify left bottom)
					(hide yes)
				)
			)
			(property "ki_keywords" "SMT, DIODE, SEMICONDUCTOR, LED"
				(at 0 0 0)
				(effects
					(font
						(size 1.27 1.27)
					)
					(hide yes)
				)
			)
			(symbol "LED_G_0603_LTST-C190GKT_0_1"
				(polyline
					(pts
						(xy 1.905 0) (xy 0.635 0)
					)
					(stroke
						(width 0)
						(type default)
					)
					(fill
						(type none)
					)
				)
				(polyline
					(pts
						(xy 4.445 0) (xy 3.175 0)
					)
					(stroke
						(width 0)
						(type default)
					)
					(fill
						(type none)
					)
				)
			)
			(symbol "LED_G_0603_LTST-C190GKT_1_1"
				(polyline
					(pts
						(xy 1.143 2.286) (xy 1.143 1.778) (xy 1.143 2.286) (xy 1.651 2.286) (xy 1.143 2.286) (xy 2.159 1.27)
					)
					(stroke
						(width 0.254)
						(type default)
					)
					(fill
						(type none)
					)
				)
				(polyline
					(pts
						(xy 1.778 1.016) (xy 1.778 -1.016)
					)
					(stroke
						(width 0.254)
						(type default)
					)
					(fill
						(type none)
					)
				)
				(polyline
					(pts
						(xy 2.159 2.54) (xy 2.159 2.032) (xy 2.159 2.54) (xy 2.667 2.54) (xy 2.159 2.54) (xy 3.048 1.651)
					)
					(stroke
						(width 0.254)
						(type default)
					)
					(fill
						(type none)
					)
				)
				(polyline
					(pts
						(xy 3.302 1.016) (xy 3.302 -1.016) (xy 1.778 0) (xy 3.302 1.016)
					)
					(stroke
						(width 0.254)
						(type default)
					)
					(fill
						(type outline)
					)
				)
				(pin passive line
					(at 0 0 0)
					(length 0.635)
					(name "C"
						(effects
							(font
								(size 1.27 1.27)
							)
						)
					)
					(number "1"
						(effects
							(font
								(size 1.27 1.27)
							)
						)
					)
				)
				(pin passive line
					(at 5.08 0 180)
					(length 0.635)
					(name "A"
						(effects
							(font
								(size 1.27 1.27)
							)
						)
					)
					(number "2"
						(effects
							(font
								(size 1.27 1.27)
							)
						)
					)
				)
			)
		)
	(symbol "antmicroLogicBuffersDriversReceiversTransceivers:74LVC1G07_SOT-753"
			(exclude_from_sim no)
			(in_bom yes)
			(on_board yes)
			(property "Reference" "U"
				(at 30.48 2.54 0)
				(effects
					(font
						(size 1.27 1.27)
						(thickness 0.15)
					)
					(justify left bottom)
				)
			)
			(property "Value" "74LVC1G07_SOT-753"
				(at 30.48 0 0)
				(effects
					(font
						(size 1.27 1.27)
						(thickness 0.15)
					)
					(justify left bottom)
					(hide yes)
				)
			)
			(property "Footprint" "antmicro-footprints:SOT-753"
				(at 30.48 -2.54 0)
				(effects
					(font
						(size 1.27 1.27)
						(thickness 0.15)
					)
					(justify left bottom)
					(hide yes)
				)
			)
			(property "Datasheet" "https://www.mouser.com/datasheet/2/916/74LVC1G07-1529858.pdf"
				(at 30.48 -5.08 0)
				(effects
					(font
						(size 1.27 1.27)
						(thickness 0.15)
					)
					(justify left bottom)
					(hide yes)
				)
			)
			(property "Description" "Buffer, 74LVC1G07, 1.65 V to 5.5 V, SC-74A-5"
				(at 30.48 -17.78 0)
				(effects
					(font
						(size 1.27 1.27)
					)
					(justify left bottom)
					(hide yes)
				)
			)
			(property "MPN" "74LVC1G07GV,125"
				(at 30.48 -7.62 0)
				(effects
					(font
						(size 1.27 1.27)
						(thickness 0.15)
					)
					(justify left bottom)
				)
			)
			(property "Manufacturer" "Nexperia"
				(at 30.48 -10.16 0)
				(effects
					(font
						(size 1.27 1.27)
						(thickness 0.15)
					)
					(justify left bottom)
					(hide yes)
				)
			)
			(property "Author" "Antmicro"
				(at 30.48 -12.7 0)
				(effects
					(font
						(size 1.27 1.27)
						(thickness 0.15)
					)
					(justify left bottom)
					(hide yes)
				)
			)
			(property "License" "Apache-2.0"
				(at 30.48 -15.24 0)
				(effects
					(font
						(size 1.27 1.27)
						(thickness 0.15)
					)
					(justify left bottom)
					(hide yes)
				)
			)
			(property "ki_keywords" "BUFFER"
				(at 0 0 0)
				(effects
					(font
						(size 1.27 1.27)
					)
					(hide yes)
				)
			)
			(symbol "74LVC1G07_SOT-753_1_1"
				(rectangle
					(start 2.54 2.54)
					(end 15.24 -8.89)
					(stroke
						(width 0.254)
						(type default)
					)
					(fill
						(type background)
					)
				)
				(polyline
					(pts
						(xy 6.35 -1.27) (xy 6.35 -6.35) (xy 11.43 -3.81) (xy 6.35 -1.27)
					)
					(stroke
						(width 0.254)
						(type default)
					)
					(fill
						(type background)
					)
				)
				(polyline
					(pts
						(xy 6.35 -3.81) (xy 5.08 -3.81)
					)
					(stroke
						(width 0.254)
						(type default)
					)
					(fill
						(type background)
					)
				)
				(polyline
					(pts
						(xy 6.985 -4.445) (xy 8.255 -4.445)
					)
					(stroke
						(width 0.254)
						(type default)
					)
					(fill
						(type background)
					)
				)
				(polyline
					(pts
						(xy 7.62 -3.175) (xy 6.985 -3.81) (xy 7.62 -4.445) (xy 8.255 -3.81) (xy 7.62 -3.175)
					)
					(stroke
						(width 0.254)
						(type default)
					)
					(fill
						(type background)
					)
				)
				(polyline
					(pts
						(xy 11.43 -3.81) (xy 12.7 -3.81)
					)
					(stroke
						(width 0.254)
						(type default)
					)
					(fill
						(type background)
					)
				)
				(pin power_in line
					(at 0 0 0)
					(length 2.54)
					(name "VCC"
						(effects
							(font
								(size 1.27 1.27)
							)
						)
					)
					(number "5"
						(effects
							(font
								(size 1.27 1.27)
							)
						)
					)
				)
				(pin input line
					(at 0 -3.81 0)
					(length 2.54)
					(name "A"
						(effects
							(font
								(size 1.27 1.27)
							)
						)
					)
					(number "2"
						(effects
							(font
								(size 1.27 1.27)
							)
						)
					)
				)
				(pin no_connect line
					(at 2.54 -6.35 0)
					(length 2.54)
					(hide yes)
					(name "NC"
						(effects
							(font
								(size 1.27 1.27)
							)
						)
					)
					(number "1"
						(effects
							(font
								(size 1.27 1.27)
							)
						)
					)
				)
				(pin output line
					(at 17.78 -3.81 180)
					(length 2.54)
					(name "Y"
						(effects
							(font
								(size 1.27 1.27)
							)
						)
					)
					(number "4"
						(effects
							(font
								(size 1.27 1.27)
							)
						)
					)
				)
				(pin power_in line
					(at 17.78 -6.35 180)
					(length 2.54)
					(name "GND"
						(effects
							(font
								(size 1.27 1.27)
							)
						)
					)
					(number "3"
						(effects
							(font
								(size 1.27 1.27)
							)
						)
					)
				)
			)
		)
	(symbol "antmicroLogicTranslatorsLevelShifters:NTS0102_TSSOP"
			(exclude_from_sim no)
			(in_bom yes)
			(on_board yes)
			(property "Reference" "U"
				(at 35.56 -3.81 0)
				(effects
					(font
						(size 1.27 1.27)
						(thickness 0.15)
					)
					(justify left bottom)
				)
			)
			(property "Value" "NTS0102_TSSOP"
				(at 35.56 -6.35 0)
				(effects
					(font
						(size 1.27 1.27)
						(thickness 0.15)
					)
					(justify left bottom)
					(hide yes)
				)
			)
			(property "Footprint" "antmicro-footprints:TSSOP-8_3x3mm_P0.65mm"
				(at 35.56 -8.89 0)
				(effects
					(font
						(size 1.27 1.27)
						(thickness 0.15)
					)
					(justify left bottom)
					(hide yes)
				)
			)
			(property "Datasheet" "https://www.mouser.com/datasheet/2/302/NTS0102-1127324.pdf"
				(at 35.56 -11.43 0)
				(effects
					(font
						(size 1.27 1.27)
						(thickness 0.15)
					)
					(justify left bottom)
					(hide yes)
				)
			)
			(property "Description" "Transceiver, 1.65 V to 3.6 V, TSSOP-8"
				(at 35.56 -24.13 0)
				(effects
					(font
						(size 1.27 1.27)
					)
					(justify left bottom)
					(hide yes)
				)
			)
			(property "MPN" "NTS0102DP"
				(at 35.56 -13.97 0)
				(effects
					(font
						(size 1.27 1.27)
						(thickness 0.15)
					)
					(justify left bottom)
				)
			)
			(property "Manufacturer" "NXP"
				(at 35.56 -16.51 0)
				(effects
					(font
						(size 1.27 1.27)
						(thickness 0.15)
					)
					(justify left bottom)
					(hide yes)
				)
			)
			(property "Author" "Antmicro"
				(at 35.56 -19.05 0)
				(effects
					(font
						(size 1.27 1.27)
						(thickness 0.15)
					)
					(justify left bottom)
					(hide yes)
				)
			)
			(property "License" "Apache-2.0"
				(at 35.56 -21.59 0)
				(effects
					(font
						(size 1.27 1.27)
						(thickness 0.15)
					)
					(justify left bottom)
					(hide yes)
				)
			)
			(property "ki_keywords" "SMT, LEVEL-SHIFTER, IC, LOGIC"
				(at 0 0 0)
				(effects
					(font
						(size 1.27 1.27)
					)
					(hide yes)
				)
			)
			(symbol "NTS0102_TSSOP_1_1"
				(rectangle
					(start 2.54 2.54)
					(end 17.78 -10.16)
					(stroke
						(width 0.254)
						(type default)
					)
					(fill
						(type background)
					)
				)
				(pin power_in line
					(at 0 0 0)
					(length 2.54)
					(name "VCC_{A}"
						(effects
							(font
								(size 1.27 1.27)
							)
						)
					)
					(number "3"
						(effects
							(font
								(size 1.27 1.27)
							)
						)
					)
				)
				(pin bidirectional line
					(at 0 -2.54 0)
					(length 2.54)
					(name "A_{1}"
						(effects
							(font
								(size 1.27 1.27)
							)
						)
					)
					(number "5"
						(effects
							(font
								(size 1.27 1.27)
							)
						)
					)
				)
				(pin bidirectional line
					(at 0 -5.08 0)
					(length 2.54)
					(name "A_{2}"
						(effects
							(font
								(size 1.27 1.27)
							)
						)
					)
					(number "4"
						(effects
							(font
								(size 1.27 1.27)
							)
						)
					)
				)
				(pin input line
					(at 0 -7.62 0)
					(length 2.54)
					(name "OE"
						(effects
							(font
								(size 1.27 1.27)
							)
						)
					)
					(number "6"
						(effects
							(font
								(size 1.27 1.27)
							)
						)
					)
				)
				(pin power_in line
					(at 20.32 0 180)
					(length 2.54)
					(name "VCC_{B}"
						(effects
							(font
								(size 1.27 1.27)
							)
						)
					)
					(number "7"
						(effects
							(font
								(size 1.27 1.27)
							)
						)
					)
				)
				(pin bidirectional line
					(at 20.32 -2.54 180)
					(length 2.54)
					(name "B_{1}"
						(effects
							(font
								(size 1.27 1.27)
							)
						)
					)
					(number "8"
						(effects
							(font
								(size 1.27 1.27)
							)
						)
					)
				)
				(pin bidirectional line
					(at 20.32 -5.08 180)
					(length 2.54)
					(name "B_{2}"
						(effects
							(font
								(size 1.27 1.27)
							)
						)
					)
					(number "1"
						(effects
							(font
								(size 1.27 1.27)
							)
						)
					)
				)
				(pin power_in line
					(at 20.32 -7.62 180)
					(length 2.54)
					(name "GND"
						(effects
							(font
								(size 1.27 1.27)
							)
						)
					)
					(number "2"
						(effects
							(font
								(size 1.27 1.27)
							)
						)
					)
				)
			)
		)
	(symbol "antmicroMechanicalParts:Heatsink_ATS-61500R-C2-R0"
			(pin_names
				(hide yes)
			)
			(exclude_from_sim no)
			(in_bom yes)
			(on_board yes)
			(property "Reference" "H"
				(at 17.78 -2.54 0)
				(effects
					(font
						(size 1.27 1.27)
						(thickness 0.15)
					)
					(justify left bottom)
				)
			)
			(property "Value" "Heatsink_ATS-61500R-C2-R0"
				(at 17.78 -5.08 0)
				(effects
					(font
						(size 1.27 1.27)
						(thickness 0.15)
					)
					(justify left bottom)
					(hide yes)
				)
			)
			(property "Footprint" "antmicro-footprints:Heatsink_ATS-61500R-C2-R0"
				(at 17.78 -7.62 0)
				(effects
					(font
						(size 1.27 1.27)
						(thickness 0.15)
					)
					(justify left bottom)
					(hide yes)
				)
			)
			(property "Datasheet" "https://www.qats.com/DataSheet/ATS-61500-Series-C2-R0"
				(at 17.78 -10.16 0)
				(effects
					(font
						(size 1.27 1.27)
						(thickness 0.15)
					)
					(justify left bottom)
					(hide yes)
				)
			)
			(property "Description" "Heat Sinks fanSINK Assembly with Mounting Hardware"
				(at 17.78 -22.86 0)
				(effects
					(font
						(size 1.27 1.27)
					)
					(justify left bottom)
					(hide yes)
				)
			)
			(property "MPN" "ATS-61500R-C2-R0"
				(at 17.78 -12.7 0)
				(effects
					(font
						(size 1.27 1.27)
						(thickness 0.15)
					)
					(justify left bottom)
				)
			)
			(property "Manufacturer" "Advanced Thermal Solutions"
				(at 17.78 -15.24 0)
				(effects
					(font
						(size 1.27 1.27)
						(thickness 0.15)
					)
					(justify left bottom)
					(hide yes)
				)
			)
			(property "Author" "Antmicro"
				(at 17.78 -17.78 0)
				(effects
					(font
						(size 1.27 1.27)
						(thickness 0.15)
					)
					(justify left bottom)
					(hide yes)
				)
			)
			(property "License" "Apache-2.0"
				(at 17.78 -20.32 0)
				(effects
					(font
						(size 1.27 1.27)
						(thickness 0.15)
					)
					(justify left bottom)
					(hide yes)
				)
			)
			(property "ki_keywords" "HEATSINK"
				(at 0 0 0)
				(effects
					(font
						(size 1.27 1.27)
					)
					(hide yes)
				)
			)
			(property "ki_fp_filters" "Heatsink_*"
				(at 0 0 0)
				(effects
					(font
						(size 1.27 1.27)
					)
					(hide yes)
				)
			)
			(symbol "Heatsink_ATS-61500R-C2-R0_0_1"
				(polyline
					(pts
						(xy 0 0) (xy 0.635 0) (xy 0.635 -3.175) (xy 1.27 -3.175) (xy 1.27 0) (xy 1.905 0) (xy 1.905 -3.175)
						(xy 2.54 -3.175) (xy 2.54 0) (xy 3.175 0) (xy 3.175 -3.175) (xy 3.81 -3.175) (xy 3.81 0) (xy 4.445 0)
						(xy 4.445 -3.175) (xy 5.08 -3.175) (xy 5.08 0) (xy 5.715 0) (xy 5.715 -4.445) (xy 0 -4.445) (xy 0 0)
					)
					(stroke
						(width 0)
						(type default)
					)
					(fill
						(type background)
					)
				)
			)
		)
	(symbol "antmicroMechanicalParts:Lightpipe_Mentor_1271.1001"
			(pin_names
				(hide yes)
			)
			(exclude_from_sim no)
			(in_bom yes)
			(on_board yes)
			(property "Reference" "H"
				(at 20.32 -2.54 0)
				(effects
					(font
						(size 1.27 1.27)
						(thickness 0.15)
					)
					(justify left bottom)
				)
			)
			(property "Value" "Lightpipe_Mentor_1271.1001"
				(at 20.32 -7.62 0)
				(effects
					(font
						(size 1.27 1.27)
						(thickness 0.15)
					)
					(justify left bottom)
					(hide yes)
				)
			)
			(property "Footprint" "antmicro-footprints:Mech_Lightpipe_Mentor_1271.1001"
				(at 20.32 -10.16 0)
				(effects
					(font
						(size 1.27 1.27)
						(thickness 0.15)
					)
					(justify left bottom)
					(hide yes)
				)
			)
			(property "Datasheet" "https://www.mentor.de.com/productpdfs/ll/ll14-20.pdf"
				(at 20.32 -12.7 0)
				(effects
					(font
						(size 1.27 1.27)
						(thickness 0.15)
					)
					(justify left bottom)
					(hide yes)
				)
			)
			(property "Description" "Light Pipe, 14.45 mm, 1 Pipe, Circular, PC Board, Transparent"
				(at 20.32 -22.86 0)
				(effects
					(font
						(size 1.27 1.27)
					)
					(justify left bottom)
					(hide yes)
				)
			)
			(property "MPN" "1271.1001"
				(at 20.32 -5.08 0)
				(effects
					(font
						(size 1.27 1.27)
						(thickness 0.15)
					)
					(justify left bottom)
				)
			)
			(property "Manufacturer" "Mentor Worldwide"
				(at 20.32 -15.24 0)
				(effects
					(font
						(size 1.27 1.27)
						(thickness 0.15)
					)
					(justify left bottom)
					(hide yes)
				)
			)
			(property "Author" "Antmicro"
				(at 20.32 -17.78 0)
				(effects
					(font
						(size 1.27 1.27)
						(thickness 0.15)
					)
					(justify left bottom)
					(hide yes)
				)
			)
			(property "License" "Apache-2.0"
				(at 20.32 -20.32 0)
				(effects
					(font
						(size 1.27 1.27)
						(thickness 0.15)
					)
					(justify left bottom)
					(hide yes)
				)
			)
			(property "ki_keywords" "HORIZONTAL, THT, MECHANICAL"
				(at 0 0 0)
				(effects
					(font
						(size 1.27 1.27)
					)
					(hide yes)
				)
			)
			(symbol "Lightpipe_Mentor_1271.1001_1_1"
				(rectangle
					(start 5.08 -2.54)
					(end -5.08 3.81)
					(stroke
						(width 0.254)
						(type default)
					)
					(fill
						(type background)
					)
				)
				(text "Horizontal"
					(at -5.08 1.524 0)
					(effects
						(font
							(size 1.27 1.27)
							(thickness 0.15)
						)
						(justify left bottom)
					)
				)
				(text "lightguide"
					(at -4.826 -0.508 0)
					(effects
						(font
							(size 1.27 1.27)
							(thickness 0.15)
						)
						(justify left bottom)
					)
				)
				(text "1x1"
					(at -1.905 -2.54 0)
					(effects
						(font
							(size 1.27 1.27)
							(thickness 0.15)
						)
						(justify left bottom)
					)
				)
			)
		)
	(symbol "antmicroMechanicalParts:MP_Pad6mm_Drill3.2mm"
			(pin_names
				(hide yes)
			)
			(exclude_from_sim no)
			(in_bom no)
			(on_board yes)
			(property "Reference" "MP"
				(at 20.32 -2.54 0)
				(effects
					(font
						(size 1.27 1.27)
						(thickness 0.15)
					)
					(justify left bottom)
				)
			)
			(property "Value" "MP_Pad6mm_Drill3.2mm"
				(at 20.32 -5.08 0)
				(effects
					(font
						(size 1.27 1.27)
						(thickness 0.15)
					)
					(justify left bottom)
				)
			)
			(property "Footprint" "antmicro-footprints:MP_Pad6mm_Drill3.2mm"
				(at 20.32 -7.62 0)
				(effects
					(font
						(size 1.27 1.27)
						(thickness 0.15)
					)
					(justify left bottom)
					(hide yes)
				)
			)
			(property "Datasheet" ""
				(at 16.84 -15.57 0)
				(effects
					(font
						(size 1.27 1.27)
						(thickness 0.15)
					)
					(justify left bottom)
					(hide yes)
				)
			)
			(property "Description" "Mechanical part"
				(at 20.32 -15.24 0)
				(effects
					(font
						(size 1.27 1.27)
					)
					(justify left bottom)
					(hide yes)
				)
			)
			(property "Author" "Antmicro"
				(at 20.32 -10.16 0)
				(effects
					(font
						(size 1.27 1.27)
						(thickness 0.15)
					)
					(justify left bottom)
					(hide yes)
				)
			)
			(property "License" "Apache-2.0"
				(at 20.32 -12.7 0)
				(effects
					(font
						(size 1.27 1.27)
						(thickness 0.15)
					)
					(justify left bottom)
					(hide yes)
				)
			)
			(property "ki_keywords" "MECHANICAL"
				(at 0 0 0)
				(effects
					(font
						(size 1.27 1.27)
					)
					(hide yes)
				)
			)
			(symbol "MP_Pad6mm_Drill3.2mm_1_1"
				(circle
					(center 5.08 0)
					(radius 1.27)
					(stroke
						(width 0.254)
						(type default)
					)
					(fill
						(type background)
					)
				)
				(circle
					(center 5.08 0)
					(radius 2.54)
					(stroke
						(width 0.254)
						(type default)
					)
					(fill
						(type background)
					)
				)
				(pin passive line
					(at 0 0 0)
					(length 2.54)
					(name "~"
						(effects
							(font
								(size 1.27 1.27)
							)
						)
					)
					(number "1"
						(effects
							(font
								(size 1.27 1.27)
							)
						)
					)
				)
			)
		)
	(symbol "antmicroMemory:AT25DF641A-SH"
			(exclude_from_sim no)
			(in_bom yes)
			(on_board yes)
			(property "Reference" "U"
				(at 33.02 -2.54 0)
				(effects
					(font
						(size 1.27 1.27)
						(thickness 0.15)
					)
					(justify left bottom)
				)
			)
			(property "Value" "AT25DF641A-SH"
				(at 33.02 -7.62 0)
				(effects
					(font
						(size 1.27 1.27)
						(thickness 0.15)
					)
					(justify left bottom)
					(hide yes)
				)
			)
			(property "Footprint" "antmicro-footprints:SOIC-8_5.3x5.3x2mm_P1.27mm"
				(at 33.02 -10.16 0)
				(effects
					(font
						(size 1.27 1.27)
						(thickness 0.15)
					)
					(justify left bottom)
					(hide yes)
				)
			)
			(property "Datasheet" "https://eu.mouser.com/datasheet/3/1166/1/REN_DS-AT25DF641A-8693G-022022_unsecure_DST_20220220_1.pdf"
				(at 33.02 -12.7 0)
				(effects
					(font
						(size 1.27 1.27)
						(thickness 0.15)
					)
					(justify left bottom)
					(hide yes)
				)
			)
			(property "Description" "NOR Flash 64 Mbit, 3.0V (2.7V to 3.6V), -40C to 85C, SOIC-W 208mil (Tape & Reel), Single, Dual SPI NOR flash"
				(at 33.02 -15.24 0)
				(effects
					(font
						(size 1.27 1.27)
						(thickness 0.15)
					)
					(justify left bottom)
					(hide yes)
				)
			)
			(property "MPN" "AT25DF641A-SH-T "
				(at 33.02 -5.08 0)
				(effects
					(font
						(size 1.27 1.27)
						(thickness 0.15)
					)
					(justify left bottom)
				)
			)
			(property "Manufacturer" "Renesas"
				(at 33.02 -17.78 0)
				(effects
					(font
						(size 1.27 1.27)
						(thickness 0.15)
					)
					(justify left bottom)
					(hide yes)
				)
			)
			(property "Author" "Antmicro"
				(at 33.02 -20.32 0)
				(effects
					(font
						(size 1.27 1.27)
						(thickness 0.15)
					)
					(justify left bottom)
					(hide yes)
				)
			)
			(property "License" "Apache-2.0"
				(at 33.02 -22.86 0)
				(effects
					(font
						(size 1.27 1.27)
						(thickness 0.15)
					)
					(justify left bottom)
					(hide yes)
				)
			)
			(property "ki_keywords" "FLASH, SPI, MEMORY"
				(at 0 0 0)
				(effects
					(font
						(size 1.27 1.27)
					)
					(hide yes)
				)
			)
			(symbol "AT25DF641A-SH_1_1"
				(rectangle
					(start 2.54 2.54)
					(end 16.51 -15.24)
					(stroke
						(width 0.254)
						(type default)
					)
					(fill
						(type background)
					)
				)
				(pin bidirectional line
					(at 0 0 0)
					(length 2.54)
					(name "SI"
						(effects
							(font
								(size 1.27 1.27)
							)
						)
					)
					(number "5"
						(effects
							(font
								(size 1.27 1.27)
							)
						)
					)
				)
				(pin bidirectional line
					(at 0 -2.54 0)
					(length 2.54)
					(name "SO"
						(effects
							(font
								(size 1.27 1.27)
							)
						)
					)
					(number "2"
						(effects
							(font
								(size 1.27 1.27)
							)
						)
					)
				)
				(pin bidirectional line
					(at 0 -5.08 0)
					(length 2.54)
					(name "~{WP}"
						(effects
							(font
								(size 1.27 1.27)
							)
						)
					)
					(number "3"
						(effects
							(font
								(size 1.27 1.27)
							)
						)
					)
				)
				(pin bidirectional line
					(at 0 -7.62 0)
					(length 2.54)
					(name "~{HOLD}"
						(effects
							(font
								(size 1.27 1.27)
							)
						)
					)
					(number "7"
						(effects
							(font
								(size 1.27 1.27)
							)
						)
					)
				)
				(pin input line
					(at 0 -10.16 0)
					(length 2.54)
					(name "SCK"
						(effects
							(font
								(size 1.27 1.27)
							)
						)
					)
					(number "6"
						(effects
							(font
								(size 1.27 1.27)
							)
						)
					)
				)
				(pin input line
					(at 0 -12.7 0)
					(length 2.54)
					(name "~{CS}"
						(effects
							(font
								(size 1.27 1.27)
							)
						)
					)
					(number "1"
						(effects
							(font
								(size 1.27 1.27)
							)
						)
					)
				)
				(pin power_in line
					(at 19.05 0 180)
					(length 2.54)
					(name "VCC"
						(effects
							(font
								(size 1.27 1.27)
							)
						)
					)
					(number "8"
						(effects
							(font
								(size 1.27 1.27)
							)
						)
					)
				)
				(pin power_in line
					(at 19.05 -12.7 180)
					(length 2.54)
					(name "GND"
						(effects
							(font
								(size 1.27 1.27)
							)
						)
					)
					(number "4"
						(effects
							(font
								(size 1.27 1.27)
							)
						)
					)
				)
			)
		)
	(symbol "antmicroMemory:MX25L8006EM1I-12G"
			(exclude_from_sim no)
			(in_bom yes)
			(on_board yes)
			(property "Reference" "U"
				(at 35.56 0 0)
				(effects
					(font
						(size 1.27 1.27)
						(thickness 0.15)
					)
					(justify left bottom)
				)
			)
			(property "Value" "MX25L8006EM1I-12G"
				(at 35.56 -2.54 0)
				(effects
					(font
						(size 1.27 1.27)
						(thickness 0.15)
					)
					(justify left bottom)
					(hide yes)
				)
			)
			(property "Footprint" "antmicro-footprints:SOIC-8_3.9x4.9x1.75mm_P1.27mm"
				(at 35.56 -5.08 0)
				(effects
					(font
						(size 1.27 1.27)
						(thickness 0.15)
					)
					(justify left bottom)
					(hide yes)
				)
			)
			(property "Datasheet" "https://www.macronix.com/Lists/Datasheet/Attachments/8680/MX25L8006E,%203V,%208Mb,%20v1.6.pdf"
				(at 35.56 -7.62 0)
				(effects
					(font
						(size 1.27 1.27)
						(thickness 0.15)
					)
					(justify left bottom)
					(hide yes)
				)
			)
			(property "Description" "FLASH - NOR Memory IC 8Mbit SPI 86 MHz 8-SOP"
				(at 35.56 -20.32 0)
				(effects
					(font
						(size 1.27 1.27)
					)
					(justify left bottom)
					(hide yes)
				)
			)
			(property "MPN" "MX25L8006EM1I-12G"
				(at 35.56 -10.16 0)
				(effects
					(font
						(size 1.27 1.27)
						(thickness 0.15)
					)
					(justify left bottom)
				)
			)
			(property "Manufacturer" "Macronix"
				(at 35.56 -12.7 0)
				(effects
					(font
						(size 1.27 1.27)
						(thickness 0.15)
					)
					(justify left bottom)
					(hide yes)
				)
			)
			(property "Author" "Antmicro"
				(at 35.56 -15.24 0)
				(effects
					(font
						(size 1.27 1.27)
						(thickness 0.15)
					)
					(justify left bottom)
					(hide yes)
				)
			)
			(property "License" "Apache-2.0"
				(at 35.56 -17.78 0)
				(effects
					(font
						(size 1.27 1.27)
						(thickness 0.15)
					)
					(justify left bottom)
					(hide yes)
				)
			)
			(property "ki_keywords" "SMT, MEMORY, IC, FLASH"
				(at 0 0 0)
				(effects
					(font
						(size 1.27 1.27)
					)
					(hide yes)
				)
			)
			(symbol "MX25L8006EM1I-12G_0_1"
				(rectangle
					(start 2.54 2.54)
					(end 22.86 -13.97)
					(stroke
						(width 0.254)
						(type default)
					)
					(fill
						(type background)
					)
				)
			)
			(symbol "MX25L8006EM1I-12G_1_1"
				(pin input line
					(at 0 0 0)
					(length 2.54)
					(name "SI/IO0"
						(effects
							(font
								(size 1.27 1.27)
							)
						)
					)
					(number "5"
						(effects
							(font
								(size 1.27 1.27)
							)
						)
					)
				)
				(pin input line
					(at 0 -2.54 0)
					(length 2.54)
					(name "SO/IO1"
						(effects
							(font
								(size 1.27 1.27)
							)
						)
					)
					(number "2"
						(effects
							(font
								(size 1.27 1.27)
							)
						)
					)
				)
				(pin input line
					(at 0 -5.08 0)
					(length 2.54)
					(name "~{WP}"
						(effects
							(font
								(size 1.27 1.27)
							)
						)
					)
					(number "3"
						(effects
							(font
								(size 1.27 1.27)
							)
						)
					)
				)
				(pin input line
					(at 0 -7.62 0)
					(length 2.54)
					(name "~{HOLD}"
						(effects
							(font
								(size 1.27 1.27)
							)
						)
					)
					(number "7"
						(effects
							(font
								(size 1.27 1.27)
							)
						)
					)
				)
				(pin input line
					(at 0 -10.16 0)
					(length 2.54)
					(name "SCLK"
						(effects
							(font
								(size 1.27 1.27)
							)
						)
					)
					(number "6"
						(effects
							(font
								(size 1.27 1.27)
							)
						)
					)
				)
				(pin input line
					(at 0 -12.7 0)
					(length 2.54)
					(name "~{CS}"
						(effects
							(font
								(size 1.27 1.27)
							)
						)
					)
					(number "1"
						(effects
							(font
								(size 1.27 1.27)
							)
						)
					)
				)
				(pin power_in line
					(at 25.4 -1.27 180)
					(length 2.54)
					(name "VCC"
						(effects
							(font
								(size 1.27 1.27)
							)
						)
					)
					(number "8"
						(effects
							(font
								(size 1.27 1.27)
							)
						)
					)
				)
				(pin power_in line
					(at 25.4 -10.16 180)
					(length 2.54)
					(name "GND"
						(effects
							(font
								(size 1.27 1.27)
							)
						)
					)
					(number "4"
						(effects
							(font
								(size 1.27 1.27)
							)
						)
					)
				)
			)
		)
	(symbol "antmicroMemory:MX25L8006EM2I-12G"
			(exclude_from_sim no)
			(in_bom yes)
			(on_board yes)
			(property "Reference" "U"
				(at 35.56 0 0)
				(effects
					(font
						(size 1.27 1.27)
						(thickness 0.15)
					)
					(justify left bottom)
				)
			)
			(property "Value" "MX25L8006EM2I-12G"
				(at 35.56 -2.54 0)
				(effects
					(font
						(size 1.27 1.27)
						(thickness 0.15)
					)
					(justify left bottom)
					(hide yes)
				)
			)
			(property "Footprint" "antmicro-footprints:SOIC-8_5.3x5.3x2mm_P1.27mm"
				(at 35.56 -5.08 0)
				(effects
					(font
						(size 1.27 1.27)
						(thickness 0.15)
					)
					(justify left bottom)
					(hide yes)
				)
			)
			(property "Datasheet" "https://www.macronix.com/Lists/Datasheet/Attachments/8680/MX25L8006E,%203V,%208Mb,%20v1.6.pdf"
				(at 35.56 -7.62 0)
				(effects
					(font
						(size 1.27 1.27)
						(thickness 0.15)
					)
					(justify left bottom)
					(hide yes)
				)
			)
			(property "Description" "FLASH - NOR Memory IC 8Mbit SPI 86 MHz 8-SOP"
				(at 35.56 -20.32 0)
				(effects
					(font
						(size 1.27 1.27)
					)
					(justify left bottom)
					(hide yes)
				)
			)
			(property "MPN" "MX25L8006EM2I-12G"
				(at 35.56 -10.16 0)
				(effects
					(font
						(size 1.27 1.27)
						(thickness 0.15)
					)
					(justify left bottom)
				)
			)
			(property "Manufacturer" "Macronix"
				(at 35.56 -12.7 0)
				(effects
					(font
						(size 1.27 1.27)
						(thickness 0.15)
					)
					(justify left bottom)
					(hide yes)
				)
			)
			(property "Author" "Antmicro"
				(at 35.56 -15.24 0)
				(effects
					(font
						(size 1.27 1.27)
						(thickness 0.15)
					)
					(justify left bottom)
					(hide yes)
				)
			)
			(property "License" "Apache-2.0"
				(at 35.56 -17.78 0)
				(effects
					(font
						(size 1.27 1.27)
						(thickness 0.15)
					)
					(justify left bottom)
					(hide yes)
				)
			)
			(property "ki_keywords" "SMT, MEMORY, IC, FLASH, SPI"
				(at 0 0 0)
				(effects
					(font
						(size 1.27 1.27)
					)
					(hide yes)
				)
			)
			(symbol "MX25L8006EM2I-12G_0_1"
				(rectangle
					(start 2.54 2.54)
					(end 22.86 -13.97)
					(stroke
						(width 0.254)
						(type default)
					)
					(fill
						(type background)
					)
				)
			)
			(symbol "MX25L8006EM2I-12G_1_1"
				(pin input line
					(at 0 0 0)
					(length 2.54)
					(name "SI/IO0"
						(effects
							(font
								(size 1.27 1.27)
							)
						)
					)
					(number "5"
						(effects
							(font
								(size 1.27 1.27)
							)
						)
					)
				)
				(pin input line
					(at 0 -2.54 0)
					(length 2.54)
					(name "SO/IO1"
						(effects
							(font
								(size 1.27 1.27)
							)
						)
					)
					(number "2"
						(effects
							(font
								(size 1.27 1.27)
							)
						)
					)
				)
				(pin input line
					(at 0 -5.08 0)
					(length 2.54)
					(name "~{WP}"
						(effects
							(font
								(size 1.27 1.27)
							)
						)
					)
					(number "3"
						(effects
							(font
								(size 1.27 1.27)
							)
						)
					)
				)
				(pin input line
					(at 0 -7.62 0)
					(length 2.54)
					(name "~{HOLD}"
						(effects
							(font
								(size 1.27 1.27)
							)
						)
					)
					(number "7"
						(effects
							(font
								(size 1.27 1.27)
							)
						)
					)
				)
				(pin input line
					(at 0 -10.16 0)
					(length 2.54)
					(name "SCLK"
						(effects
							(font
								(size 1.27 1.27)
							)
						)
					)
					(number "6"
						(effects
							(font
								(size 1.27 1.27)
							)
						)
					)
				)
				(pin input line
					(at 0 -12.7 0)
					(length 2.54)
					(name "~{CS}"
						(effects
							(font
								(size 1.27 1.27)
							)
						)
					)
					(number "1"
						(effects
							(font
								(size 1.27 1.27)
							)
						)
					)
				)
				(pin power_in line
					(at 25.4 -1.27 180)
					(length 2.54)
					(name "VCC"
						(effects
							(font
								(size 1.27 1.27)
							)
						)
					)
					(number "8"
						(effects
							(font
								(size 1.27 1.27)
							)
						)
					)
				)
				(pin power_in line
					(at 25.4 -10.16 180)
					(length 2.54)
					(name "GND"
						(effects
							(font
								(size 1.27 1.27)
							)
						)
					)
					(number "4"
						(effects
							(font
								(size 1.27 1.27)
							)
						)
					)
				)
			)
		)
	(symbol "antmicroModularConnectorsJacksWithMagnetics:Bus_RJ45_JTH-0024NL"
			(exclude_from_sim no)
			(in_bom yes)
			(on_board yes)
			(property "Reference" "J"
				(at 35.56 -2.54 0)
				(effects
					(font
						(size 1.27 1.27)
						(thickness 0.15)
					)
					(justify left bottom)
				)
			)
			(property "Value" "Bus_RJ45_JTH-0024NL"
				(at 35.56 -5.08 0)
				(effects
					(font
						(size 1.27 1.27)
						(thickness 0.15)
					)
					(justify left bottom)
					(hide yes)
				)
			)
			(property "Footprint" "antmicro-footprints:RJ45_JTH-0024NL"
				(at 35.56 -7.62 0)
				(effects
					(font
						(size 1.27 1.27)
						(thickness 0.15)
					)
					(justify left bottom)
					(hide yes)
				)
			)
			(property "Datasheet" "https://www.mouser.com/datasheet/2/447/JTH_0024NL-3072047.pdf"
				(at 35.56 -10.16 0)
				(effects
					(font
						(size 1.27 1.27)
						(thickness 0.15)
					)
					(justify left bottom)
					(hide yes)
				)
			)
			(property "Description" "Modular Connectors / Ethernet Connectors 1X1 TAB DOWN W/LED'S ETHERNET (NON PoE)"
				(at 35.56 -22.86 0)
				(effects
					(font
						(size 1.27 1.27)
					)
					(justify left bottom)
					(hide yes)
				)
			)
			(property "MPN" "JTH-0024NL"
				(at 35.56 -12.7 0)
				(effects
					(font
						(size 1.27 1.27)
						(thickness 0.15)
					)
					(justify left bottom)
				)
			)
			(property "Manufacturer" "Pulse Electronics"
				(at 35.56 -15.24 0)
				(effects
					(font
						(size 1.27 1.27)
						(thickness 0.15)
					)
					(justify left bottom)
					(hide yes)
				)
			)
			(property "Author" "Antmicro"
				(at 35.56 -17.78 0)
				(effects
					(font
						(size 1.27 1.27)
						(thickness 0.15)
					)
					(justify left bottom)
					(hide yes)
				)
			)
			(property "License" "Apache-2.0"
				(at 35.56 -20.32 0)
				(effects
					(font
						(size 1.27 1.27)
						(thickness 0.15)
					)
					(justify left bottom)
					(hide yes)
				)
			)
			(property "ki_keywords" "RJ45, HORIZONTAL, THT, ETHERNET, CONNECTOR, FEMALE"
				(at 0 0 0)
				(effects
					(font
						(size 1.27 1.27)
					)
					(hide yes)
				)
			)
			(property "ki_fp_filters" "CONN18_5-2337992-8_TEC"
				(at 0 0 0)
				(effects
					(font
						(size 1.27 1.27)
					)
					(hide yes)
				)
			)
			(symbol "Bus_RJ45_JTH-0024NL_1_1"
				(rectangle
					(start 2.54 2.54)
					(end 19.05 -38.1)
					(stroke
						(width 0.254)
						(type default)
					)
					(fill
						(type background)
					)
				)
				(polyline
					(pts
						(xy 8.89 -1.27) (xy 8.89 -13.97)
					)
					(stroke
						(width 0.254)
						(type default)
					)
					(fill
						(type background)
					)
				)
				(polyline
					(pts
						(xy 8.89 -1.27) (xy 13.97 -1.27)
					)
					(stroke
						(width 0.254)
						(type default)
					)
					(fill
						(type background)
					)
				)
				(polyline
					(pts
						(xy 8.89 -13.97) (xy 13.97 -13.97)
					)
					(stroke
						(width 0.254)
						(type default)
					)
					(fill
						(type background)
					)
				)
				(polyline
					(pts
						(xy 13.97 -1.27) (xy 13.97 -2.54)
					)
					(stroke
						(width 0.254)
						(type default)
					)
					(fill
						(type background)
					)
				)
				(polyline
					(pts
						(xy 13.97 -2.54) (xy 15.24 -2.54)
					)
					(stroke
						(width 0.254)
						(type default)
					)
					(fill
						(type background)
					)
				)
				(polyline
					(pts
						(xy 13.97 -12.7) (xy 15.24 -12.7)
					)
					(stroke
						(width 0.254)
						(type default)
					)
					(fill
						(type background)
					)
				)
				(polyline
					(pts
						(xy 13.97 -13.97) (xy 13.97 -12.7)
					)
					(stroke
						(width 0.254)
						(type default)
					)
					(fill
						(type background)
					)
				)
				(polyline
					(pts
						(xy 15.24 -2.54) (xy 15.24 -3.81)
					)
					(stroke
						(width 0.254)
						(type default)
					)
					(fill
						(type background)
					)
				)
				(polyline
					(pts
						(xy 15.24 -3.81) (xy 16.51 -3.81)
					)
					(stroke
						(width 0.254)
						(type default)
					)
					(fill
						(type background)
					)
				)
				(polyline
					(pts
						(xy 15.24 -11.43) (xy 16.51 -11.43)
					)
					(stroke
						(width 0.254)
						(type default)
					)
					(fill
						(type background)
					)
				)
				(polyline
					(pts
						(xy 15.24 -12.7) (xy 15.24 -11.43)
					)
					(stroke
						(width 0.254)
						(type default)
					)
					(fill
						(type background)
					)
				)
				(polyline
					(pts
						(xy 16.51 -3.81) (xy 16.51 -11.43)
					)
					(stroke
						(width 0.254)
						(type default)
					)
					(fill
						(type background)
					)
				)
				(pin bidirectional line
					(at 0 0 0)
					(length 2.54)
					(name "T1+"
						(effects
							(font
								(size 1.27 1.27)
							)
						)
					)
					(number "8"
						(effects
							(font
								(size 1.27 1.27)
							)
						)
					)
				)
				(pin bidirectional line
					(at 0 -2.54 0)
					(length 2.54)
					(name "T1-"
						(effects
							(font
								(size 1.27 1.27)
							)
						)
					)
					(number "9"
						(effects
							(font
								(size 1.27 1.27)
							)
						)
					)
				)
				(pin bidirectional line
					(at 0 -5.08 0)
					(length 2.54)
					(name "T2+"
						(effects
							(font
								(size 1.27 1.27)
							)
						)
					)
					(number "3"
						(effects
							(font
								(size 1.27 1.27)
							)
						)
					)
				)
				(pin bidirectional line
					(at 0 -7.62 0)
					(length 2.54)
					(name "T2-"
						(effects
							(font
								(size 1.27 1.27)
							)
						)
					)
					(number "2"
						(effects
							(font
								(size 1.27 1.27)
							)
						)
					)
				)
				(pin bidirectional line
					(at 0 -10.16 0)
					(length 2.54)
					(name "T3+"
						(effects
							(font
								(size 1.27 1.27)
							)
						)
					)
					(number "4"
						(effects
							(font
								(size 1.27 1.27)
							)
						)
					)
				)
				(pin bidirectional line
					(at 0 -12.7 0)
					(length 2.54)
					(name "T3-"
						(effects
							(font
								(size 1.27 1.27)
							)
						)
					)
					(number "5"
						(effects
							(font
								(size 1.27 1.27)
							)
						)
					)
				)
				(pin bidirectional line
					(at 0 -15.24 0)
					(length 2.54)
					(name "T4+"
						(effects
							(font
								(size 1.27 1.27)
							)
						)
					)
					(number "11"
						(effects
							(font
								(size 1.27 1.27)
							)
						)
					)
				)
				(pin bidirectional line
					(at 0 -17.78 0)
					(length 2.54)
					(name "T4-"
						(effects
							(font
								(size 1.27 1.27)
							)
						)
					)
					(number "10"
						(effects
							(font
								(size 1.27 1.27)
							)
						)
					)
				)
				(pin bidirectional line
					(at 0 -27.94 0)
					(length 2.54)
					(name "CT1"
						(effects
							(font
								(size 1.27 1.27)
							)
						)
					)
					(number "12"
						(effects
							(font
								(size 1.27 1.27)
							)
						)
					)
				)
				(pin bidirectional line
					(at 0 -30.48 0)
					(length 2.54)
					(name "CT2"
						(effects
							(font
								(size 1.27 1.27)
							)
						)
					)
					(number "6"
						(effects
							(font
								(size 1.27 1.27)
							)
						)
					)
				)
				(pin bidirectional line
					(at 0 -33.02 0)
					(length 2.54)
					(name "CT3"
						(effects
							(font
								(size 1.27 1.27)
							)
						)
					)
					(number "1"
						(effects
							(font
								(size 1.27 1.27)
							)
						)
					)
				)
				(pin bidirectional line
					(at 0 -35.56 0)
					(length 2.54)
					(name "CT4"
						(effects
							(font
								(size 1.27 1.27)
							)
						)
					)
					(number "7"
						(effects
							(font
								(size 1.27 1.27)
							)
						)
					)
				)
				(pin passive line
					(at 21.59 -17.78 180)
					(length 2.54)
					(name "LED_COM+"
						(effects
							(font
								(size 1.27 1.27)
							)
						)
					)
					(number "16"
						(effects
							(font
								(size 1.27 1.27)
							)
						)
					)
				)
				(pin passive line
					(at 21.59 -20.32 180)
					(length 2.54)
					(name "LED_YG_Y-"
						(effects
							(font
								(size 1.27 1.27)
							)
						)
					)
					(number "15"
						(effects
							(font
								(size 1.27 1.27)
							)
						)
					)
				)
				(pin passive line
					(at 21.59 -22.86 180)
					(length 2.54)
					(name "LED_YG_G-"
						(effects
							(font
								(size 1.27 1.27)
							)
						)
					)
					(number "17"
						(effects
							(font
								(size 1.27 1.27)
							)
						)
					)
				)
				(pin passive line
					(at 21.59 -27.94 180)
					(length 2.54)
					(name "LED_GRN+"
						(effects
							(font
								(size 1.27 1.27)
							)
						)
					)
					(number "14"
						(effects
							(font
								(size 1.27 1.27)
							)
						)
					)
				)
				(pin passive line
					(at 21.59 -30.48 180)
					(length 2.54)
					(name "LED_GRN-"
						(effects
							(font
								(size 1.27 1.27)
							)
						)
					)
					(number "13"
						(effects
							(font
								(size 1.27 1.27)
							)
						)
					)
				)
				(pin passive line
					(at 21.59 -35.56 180)
					(length 2.54)
					(name "SHIELD"
						(effects
							(font
								(size 1.27 1.27)
							)
						)
					)
					(number "SH"
						(effects
							(font
								(size 1.27 1.27)
							)
						)
					)
				)
			)
		)
	(symbol "antmicroOperationalAmplifiers:MCP6541_SOT23-5"
			(exclude_from_sim no)
			(in_bom yes)
			(on_board yes)
			(property "Reference" "U"
				(at 25.4 -5.08 0)
				(effects
					(font
						(size 1.27 1.27)
						(thickness 0.15)
					)
					(justify left bottom)
				)
			)
			(property "Value" "MCP6541_SOT23-5"
				(at 25.4 -10.16 0)
				(effects
					(font
						(size 1.27 1.27)
						(thickness 0.15)
					)
					(justify left bottom)
					(hide yes)
				)
			)
			(property "Footprint" "antmicro-footprints:SOT-23-5"
				(at 25.4 -12.7 0)
				(effects
					(font
						(size 1.27 1.27)
						(thickness 0.15)
					)
					(justify left bottom)
					(hide yes)
				)
			)
			(property "Datasheet" "https://www.farnell.com/datasheets/1641674.pdf"
				(at 25.4 -15.24 0)
				(effects
					(font
						(size 1.27 1.27)
						(thickness 0.15)
					)
					(justify left bottom)
					(hide yes)
				)
			)
			(property "Description" "Push-Pull Output Comparator, 1,6V to 5.5V, SOT-23-5"
				(at 25.4 -25.4 0)
				(effects
					(font
						(size 1.27 1.27)
					)
					(justify left bottom)
					(hide yes)
				)
			)
			(property "MPN" "MCP6541T-E/OT"
				(at 25.4 -7.62 0)
				(effects
					(font
						(size 1.27 1.27)
						(thickness 0.15)
					)
					(justify left bottom)
				)
			)
			(property "Manufacturer" "Microchip Technology"
				(at 25.4 -17.78 0)
				(effects
					(font
						(size 1.27 1.27)
						(thickness 0.15)
					)
					(justify left bottom)
					(hide yes)
				)
			)
			(property "Author" "Antmicro"
				(at 25.4 -20.32 0)
				(effects
					(font
						(size 1.27 1.27)
						(thickness 0.15)
					)
					(justify left bottom)
					(hide yes)
				)
			)
			(property "License" "Apache-2.0"
				(at 25.4 -22.86 0)
				(effects
					(font
						(size 1.27 1.27)
						(thickness 0.15)
					)
					(justify left bottom)
					(hide yes)
				)
			)
			(property "ki_locked" ""
				(at 0 0 0)
				(effects
					(font
						(size 1.27 1.27)
					)
				)
			)
			(property "ki_keywords" "SMT,  IC"
				(at 0 0 0)
				(effects
					(font
						(size 1.27 1.27)
					)
					(hide yes)
				)
			)
			(symbol "MCP6541_SOT23-5_1_1"
				(polyline
					(pts
						(xy 2.54 1.27) (xy 7.62 -1.27) (xy 2.54 -3.81) (xy 2.54 1.27)
					)
					(stroke
						(width 0.254)
						(type default)
					)
					(fill
						(type background)
					)
				)
				(polyline
					(pts
						(xy 4.826 -1.778) (xy 5.207 -1.778) (xy 5.461 -0.762) (xy 5.842 -0.762)
					)
					(stroke
						(width 0.127)
						(type default)
					)
					(fill
						(type background)
					)
				)
				(polyline
					(pts
						(xy 4.953 -1.27) (xy 4.826 -1.27)
					)
					(stroke
						(width 0.127)
						(type default)
					)
					(fill
						(type background)
					)
				)
				(polyline
					(pts
						(xy 5.461 -1.27) (xy 5.207 -1.27)
					)
					(stroke
						(width 0.127)
						(type default)
					)
					(fill
						(type background)
					)
				)
				(polyline
					(pts
						(xy 5.842 -1.27) (xy 5.715 -1.27)
					)
					(stroke
						(width 0.127)
						(type default)
					)
					(fill
						(type background)
					)
				)
				(text "+"
					(at 2.54 -1.016 0)
					(effects
						(font
							(size 1.27 1.27)
							(thickness 0.15)
						)
						(justify left bottom)
					)
				)
				(text "-"
					(at 2.54 -3.302 0)
					(effects
						(font
							(size 1.27 1.27)
							(thickness 0.15)
						)
						(justify left bottom)
					)
				)
				(pin input line
					(at 0 0 0)
					(length 2.54)
					(name ""
						(effects
							(font
								(size 1.27 1.27)
							)
						)
					)
					(number "3"
						(effects
							(font
								(size 1.27 1.27)
							)
						)
					)
				)
				(pin input line
					(at 0 -2.54 0)
					(length 2.54)
					(name ""
						(effects
							(font
								(size 1.27 1.27)
							)
						)
					)
					(number "4"
						(effects
							(font
								(size 1.27 1.27)
							)
						)
					)
				)
				(pin output line
					(at 10.16 -1.27 180)
					(length 2.54)
					(name ""
						(effects
							(font
								(size 1.27 1.27)
							)
						)
					)
					(number "1"
						(effects
							(font
								(size 1.27 1.27)
							)
						)
					)
				)
			)
			(symbol "MCP6541_SOT23-5_2_1"
				(rectangle
					(start 2.54 1.27)
					(end 7.62 -3.81)
					(stroke
						(width 0.254)
						(type default)
					)
					(fill
						(type background)
					)
				)
				(pin power_in line
					(at 0 0 0)
					(length 2.54)
					(name "VDD"
						(effects
							(font
								(size 1.27 1.27)
							)
						)
					)
					(number "5"
						(effects
							(font
								(size 1.27 1.27)
							)
						)
					)
				)
				(pin power_in line
					(at 0 -2.54 0)
					(length 2.54)
					(name "VSS"
						(effects
							(font
								(size 1.27 1.27)
							)
						)
					)
					(number "2"
						(effects
							(font
								(size 1.27 1.27)
							)
						)
					)
				)
			)
		)
	(symbol "antmicroOscillators:Oscillator_25MHz_511ABA25M0000BAGR"
			(exclude_from_sim no)
			(in_bom yes)
			(on_board yes)
			(property "Reference" "Y"
				(at 28.575 -1.905 0)
				(effects
					(font
						(size 1.27 1.27)
						(thickness 0.15)
					)
					(justify left bottom)
				)
			)
			(property "Value" "Oscillator_25MHz_511ABA25M0000BAGR"
				(at 28.575 -12.065 0)
				(effects
					(font
						(size 1.27 1.27)
						(thickness 0.15)
					)
					(justify left bottom)
					(hide yes)
				)
			)
			(property "Footprint" "antmicro-footprints:Oscillator_SMD_Skyworks_SI511_5x3.2x1.17mm"
				(at 28.575 -14.605 0)
				(effects
					(font
						(size 1.27 1.27)
						(thickness 0.15)
					)
					(justify left bottom)
					(hide yes)
				)
			)
			(property "Datasheet" "https://www.mouser.com/datasheet/2/472/si510_11-2507765.pdf"
				(at 28.575 -17.145 0)
				(effects
					(font
						(size 1.27 1.27)
						(thickness 0.15)
					)
					(justify left bottom)
					(hide yes)
				)
			)
			(property "Description" "25 MHz XO (Standard) LVPECL Oscillator 3.3V Enable/Disable 6-SMD, No Lead"
				(at 28.575 -24.765 0)
				(effects
					(font
						(size 1.27 1.27)
					)
					(justify left bottom)
					(hide yes)
				)
			)
			(property "Manufacturer" "Skyworks Solutions"
				(at 28.575 -4.445 0)
				(effects
					(font
						(size 1.27 1.27)
						(thickness 0.15)
					)
					(justify left bottom)
					(hide yes)
				)
			)
			(property "MPN" "511ABA25M0000BAGR"
				(at 28.575 -6.985 0)
				(effects
					(font
						(size 1.27 1.27)
						(thickness 0.15)
					)
					(justify left bottom)
				)
			)
			(property "Val" "25 MHz"
				(at 28.575 -9.525 0)
				(effects
					(font
						(size 1.27 1.27)
						(thickness 0.15)
					)
					(justify left bottom)
				)
			)
			(property "Author" "Antmicro"
				(at 28.575 -19.685 0)
				(effects
					(font
						(size 1.27 1.27)
						(thickness 0.15)
					)
					(justify left bottom)
					(hide yes)
				)
			)
			(property "License" "Apache-2.0"
				(at 28.575 -22.225 0)
				(effects
					(font
						(size 1.27 1.27)
						(thickness 0.15)
					)
					(justify left bottom)
					(hide yes)
				)
			)
			(property "ki_keywords" "OSCILLATOR, SMT"
				(at 0 0 0)
				(effects
					(font
						(size 1.27 1.27)
					)
					(hide yes)
				)
			)
			(symbol "Oscillator_25MHz_511ABA25M0000BAGR_1_1"
				(rectangle
					(start 2.54 2.54)
					(end 16.51 -7.62)
					(stroke
						(width 0.254)
						(type default)
					)
					(fill
						(type background)
					)
				)
				(polyline
					(pts
						(xy 7.62 -1.27) (xy 8.255 -1.27) (xy 8.255 0) (xy 8.89 0) (xy 8.89 -1.27) (xy 9.525 -1.27) (xy 9.525 0)
						(xy 10.16 0) (xy 10.16 -1.27)
					)
					(stroke
						(width 0.254)
						(type default)
					)
					(fill
						(type background)
					)
				)
				(pin power_in line
					(at 0 0 0)
					(length 2.54)
					(name "VCC"
						(effects
							(font
								(size 1.27 1.27)
							)
						)
					)
					(number "6"
						(effects
							(font
								(size 1.27 1.27)
							)
						)
					)
				)
				(pin input line
					(at 0 -2.54 0)
					(length 2.54)
					(name "EN"
						(effects
							(font
								(size 1.27 1.27)
							)
						)
					)
					(number "1"
						(effects
							(font
								(size 1.27 1.27)
							)
						)
					)
				)
				(pin power_in line
					(at 0 -5.08 0)
					(length 2.54)
					(name "GND"
						(effects
							(font
								(size 1.27 1.27)
							)
						)
					)
					(number "3"
						(effects
							(font
								(size 1.27 1.27)
							)
						)
					)
				)
				(pin no_connect line
					(at 16.51 -5.08 180)
					(length 2.54)
					(hide yes)
					(name "NC"
						(effects
							(font
								(size 1.27 1.27)
							)
						)
					)
					(number "2"
						(effects
							(font
								(size 1.27 1.27)
							)
						)
					)
				)
				(pin output line
					(at 19.05 0 180)
					(length 2.54)
					(name "OUT+"
						(effects
							(font
								(size 1.27 1.27)
							)
						)
					)
					(number "4"
						(effects
							(font
								(size 1.27 1.27)
							)
						)
					)
				)
				(pin output line
					(at 19.05 -2.54 180)
					(length 2.54)
					(name "OUT-"
						(effects
							(font
								(size 1.27 1.27)
							)
						)
					)
					(number "5"
						(effects
							(font
								(size 1.27 1.27)
							)
						)
					)
				)
			)
		)
	(symbol "antmicroPMICORControllersIdealDiodes:LTC4412IS6"
			(exclude_from_sim no)
			(in_bom yes)
			(on_board yes)
			(property "Reference" "U"
				(at 31.75 -2.54 0)
				(effects
					(font
						(size 1.27 1.27)
						(thickness 0.15)
					)
					(justify left bottom)
				)
			)
			(property "Value" "LTC4412IS6"
				(at 31.75 -5.08 0)
				(effects
					(font
						(size 1.27 1.27)
						(thickness 0.15)
					)
					(justify left bottom)
					(hide yes)
				)
			)
			(property "Footprint" "antmicro-footprints:SOT-23-6"
				(at 31.75 -7.62 0)
				(effects
					(font
						(size 1.27 1.27)
						(thickness 0.15)
					)
					(justify left bottom)
					(hide yes)
				)
			)
			(property "Datasheet" "https://www.analog.com/media/en/technical-documentation/data-sheets/4412fb.pdf"
				(at 31.75 -10.16 0)
				(effects
					(font
						(size 1.27 1.27)
						(thickness 0.15)
					)
					(justify left bottom)
					(hide yes)
				)
			)
			(property "Description" "Ideal diode controller"
				(at 31.75 -22.86 0)
				(effects
					(font
						(size 1.27 1.27)
					)
					(justify left bottom)
					(hide yes)
				)
			)
			(property "MPN" "LTC4412IS6#TRMPBF"
				(at 31.75 -12.7 0)
				(effects
					(font
						(size 1.27 1.27)
						(thickness 0.15)
					)
					(justify left bottom)
				)
			)
			(property "Manufacturer" "Analog Devices"
				(at 31.75 -15.24 0)
				(effects
					(font
						(size 1.27 1.27)
						(thickness 0.15)
					)
					(justify left bottom)
					(hide yes)
				)
			)
			(property "Author" "Antmicro"
				(at 31.75 -17.78 0)
				(effects
					(font
						(size 1.27 1.27)
						(thickness 0.15)
					)
					(justify left bottom)
					(hide yes)
				)
			)
			(property "License" "Apache-2.0"
				(at 31.75 -20.32 0)
				(effects
					(font
						(size 1.27 1.27)
						(thickness 0.15)
					)
					(justify left bottom)
					(hide yes)
				)
			)
			(property "ki_keywords" "SMT, CONTROLLER, IC, DIODE"
				(at 0 0 0)
				(effects
					(font
						(size 1.27 1.27)
					)
					(hide yes)
				)
			)
			(symbol "LTC4412IS6_1_1"
				(rectangle
					(start 2.54 2.54)
					(end 15.24 -7.62)
					(stroke
						(width 0.254)
						(type default)
					)
					(fill
						(type background)
					)
				)
				(pin power_in line
					(at 0 0 0)
					(length 2.54)
					(name "IN"
						(effects
							(font
								(size 1.27 1.27)
							)
						)
					)
					(number "1"
						(effects
							(font
								(size 1.27 1.27)
							)
						)
					)
				)
				(pin input line
					(at 0 -2.54 0)
					(length 2.54)
					(name "CTL"
						(effects
							(font
								(size 1.27 1.27)
							)
						)
					)
					(number "3"
						(effects
							(font
								(size 1.27 1.27)
							)
						)
					)
				)
				(pin power_in line
					(at 0 -5.08 0)
					(length 2.54)
					(name "GND"
						(effects
							(font
								(size 1.27 1.27)
							)
						)
					)
					(number "2"
						(effects
							(font
								(size 1.27 1.27)
							)
						)
					)
				)
				(pin input line
					(at 17.78 0 180)
					(length 2.54)
					(name "SENSE"
						(effects
							(font
								(size 1.27 1.27)
							)
						)
					)
					(number "6"
						(effects
							(font
								(size 1.27 1.27)
							)
						)
					)
				)
				(pin output line
					(at 17.78 -2.54 180)
					(length 2.54)
					(name "GATE"
						(effects
							(font
								(size 1.27 1.27)
							)
						)
					)
					(number "5"
						(effects
							(font
								(size 1.27 1.27)
							)
						)
					)
				)
				(pin output line
					(at 17.78 -5.08 180)
					(length 2.54)
					(name "STAT"
						(effects
							(font
								(size 1.27 1.27)
							)
						)
					)
					(number "4"
						(effects
							(font
								(size 1.27 1.27)
							)
						)
					)
				)
			)
		)
	(symbol "antmicroPMICPowerDistributionSwitchesLoadDrivers:AP22615A_TSOT26"
			(exclude_from_sim no)
			(in_bom yes)
			(on_board yes)
			(property "Reference" "U"
				(at 30.48 -2.54 0)
				(effects
					(font
						(size 1.27 1.27)
						(thickness 0.15)
					)
					(justify left bottom)
				)
			)
			(property "Value" "AP22615A_TSOT26"
				(at 30.48 -5.08 0)
				(effects
					(font
						(size 1.27 1.27)
						(thickness 0.15)
					)
					(justify left bottom)
					(hide yes)
				)
			)
			(property "Footprint" "antmicro-footprints:TSOT23-6"
				(at 30.48 -7.62 0)
				(effects
					(font
						(size 1.27 1.27)
						(thickness 0.15)
					)
					(justify left bottom)
					(hide yes)
				)
			)
			(property "Datasheet" "https://www.mouser.com/datasheet/2/115/DIOD_S_A0008958405_1-2543193.pdf"
				(at 30.48 -10.16 0)
				(effects
					(font
						(size 1.27 1.27)
						(thickness 0.15)
					)
					(justify left bottom)
					(hide yes)
				)
			)
			(property "Description" "Power Load Distribution Switch, High Side, Active High, 1 Output, 5.5 V, 3.6 A, 0.04 ohm, TSOT-26-6"
				(at 30.48 -22.86 0)
				(effects
					(font
						(size 1.27 1.27)
					)
					(justify left bottom)
					(hide yes)
				)
			)
			(property "MPN" "AP22615AWU-7"
				(at 30.48 -12.7 0)
				(effects
					(font
						(size 1.27 1.27)
						(thickness 0.15)
					)
					(justify left bottom)
				)
			)
			(property "Manufacturer" "Diodes Incorporated"
				(at 30.48 -15.24 0)
				(effects
					(font
						(size 1.27 1.27)
						(thickness 0.15)
					)
					(justify left bottom)
					(hide yes)
				)
			)
			(property "Author" "Antmicro"
				(at 30.48 -17.78 0)
				(effects
					(font
						(size 1.27 1.27)
						(thickness 0.15)
					)
					(justify left bottom)
					(hide yes)
				)
			)
			(property "License" "Apache-2.0"
				(at 30.48 -20.32 0)
				(effects
					(font
						(size 1.27 1.27)
						(thickness 0.15)
					)
					(justify left bottom)
					(hide yes)
				)
			)
			(property "ki_keywords" "SMT, PMIC, IC, VOLTAGE"
				(at 0 0 0)
				(effects
					(font
						(size 1.27 1.27)
					)
					(hide yes)
				)
			)
			(symbol "AP22615A_TSOT26_1_1"
				(rectangle
					(start 2.54 2.54)
					(end 12.7 -7.62)
					(stroke
						(width 0.254)
						(type default)
					)
					(fill
						(type background)
					)
				)
				(pin power_in line
					(at 0 0 0)
					(length 2.54)
					(name "IN"
						(effects
							(font
								(size 1.27 1.27)
							)
						)
					)
					(number "6"
						(effects
							(font
								(size 1.27 1.27)
							)
						)
					)
				)
				(pin output line
					(at 0 -2.54 0)
					(length 2.54)
					(name "FLG"
						(effects
							(font
								(size 1.27 1.27)
							)
						)
					)
					(number "3"
						(effects
							(font
								(size 1.27 1.27)
							)
						)
					)
				)
				(pin input line
					(at 0 -5.08 0)
					(length 2.54)
					(name "EN"
						(effects
							(font
								(size 1.27 1.27)
							)
						)
					)
					(number "4"
						(effects
							(font
								(size 1.27 1.27)
							)
						)
					)
				)
				(pin power_out line
					(at 15.24 0 180)
					(length 2.54)
					(name "OUT"
						(effects
							(font
								(size 1.27 1.27)
							)
						)
					)
					(number "1"
						(effects
							(font
								(size 1.27 1.27)
							)
						)
					)
				)
				(pin passive line
					(at 15.24 -2.54 180)
					(length 2.54)
					(name "ISET"
						(effects
							(font
								(size 1.27 1.27)
							)
						)
					)
					(number "5"
						(effects
							(font
								(size 1.27 1.27)
							)
						)
					)
				)
				(pin power_in line
					(at 15.24 -5.08 180)
					(length 2.54)
					(name "GND"
						(effects
							(font
								(size 1.27 1.27)
							)
						)
					)
					(number "2"
						(effects
							(font
								(size 1.27 1.27)
							)
						)
					)
				)
			)
		)
	(symbol "antmicroResistors0402:R_0R_0402"
			(pin_numbers
				(hide yes)
			)
			(pin_names
				(hide yes)
			)
			(exclude_from_sim no)
			(in_bom yes)
			(on_board yes)
			(property "Reference" "R"
				(at 20.32 -5.08 0)
				(effects
					(font
						(size 1.27 1.27)
						(thickness 0.15)
					)
					(justify left bottom)
				)
			)
			(property "Value" "R_0R_0402"
				(at 20.32 -12.7 0)
				(effects
					(font
						(size 1.27 1.27)
						(thickness 0.15)
					)
					(justify left bottom)
					(hide yes)
				)
			)
			(property "Footprint" "antmicro-footprints:R_0402_1005Metric"
				(at 20.32 -15.24 0)
				(effects
					(font
						(size 1.27 1.27)
						(thickness 0.15)
					)
					(justify left bottom)
					(hide yes)
				)
			)
			(property "Datasheet" "https://industrial.panasonic.com/cdbs/www-data/pdf/RDA0000/AOA0000C301.pdf"
				(at 20.32 -17.78 0)
				(effects
					(font
						(size 1.27 1.27)
						(thickness 0.15)
					)
					(justify left bottom)
					(hide yes)
				)
			)
			(property "Description" "SMD Chip Resistor, Jumper, 0 ohm, 100 mW, 0402 [1005 Metric], Thick Film, General Purpose"
				(at 20.32 -33.02 0)
				(effects
					(font
						(size 1.27 1.27)
					)
					(justify left bottom)
					(hide yes)
				)
			)
			(property "MPN" "ERJ2GE0R00X"
				(at 20.32 -20.32 0)
				(effects
					(font
						(size 1.27 1.27)
						(thickness 0.15)
					)
					(justify left bottom)
					(hide yes)
				)
			)
			(property "Manufacturer" "Panasonic"
				(at 20.32 -22.86 0)
				(effects
					(font
						(size 1.27 1.27)
						(thickness 0.15)
					)
					(justify left bottom)
					(hide yes)
				)
			)
			(property "License" "Apache-2.0"
				(at 20.32 -25.4 0)
				(effects
					(font
						(size 1.27 1.27)
						(thickness 0.15)
					)
					(justify left bottom)
					(hide yes)
				)
			)
			(property "Author" "Antmicro"
				(at 20.32 -27.94 0)
				(effects
					(font
						(size 1.27 1.27)
						(thickness 0.15)
					)
					(justify left bottom)
					(hide yes)
				)
			)
			(property "Val" "0R"
				(at 20.32 -7.62 0)
				(effects
					(font
						(size 1.27 1.27)
						(thickness 0.15)
					)
					(justify left bottom)
				)
			)
			(property "Tolerance" "~"
				(at 20.32 -10.16 0)
				(effects
					(font
						(size 1.27 1.27)
					)
					(justify left bottom)
					(hide yes)
				)
			)
			(property "Current" "1A"
				(at 20.32 -30.48 0)
				(effects
					(font
						(size 1.27 1.27)
						(thickness 0.15)
					)
					(justify left bottom)
					(hide yes)
				)
			)
			(property "ki_keywords" "0402, SMT, RESISTOR, PASSIVE"
				(at 0 0 0)
				(effects
					(font
						(size 1.27 1.27)
					)
					(hide yes)
				)
			)
			(symbol "R_0R_0402_0_1"
				(rectangle
					(start 0.635 0.889)
					(end 4.445 -0.889)
					(stroke
						(width 0.254)
						(type default)
					)
					(fill
						(type none)
					)
				)
			)
			(symbol "R_0R_0402_1_1"
				(pin passive line
					(at 0 0 0)
					(length 0.635)
					(name "~"
						(effects
							(font
								(size 1.27 1.27)
							)
						)
					)
					(number "1"
						(effects
							(font
								(size 1.27 1.27)
							)
						)
					)
				)
				(pin passive line
					(at 5.08 0 180)
					(length 0.635)
					(name "~"
						(effects
							(font
								(size 1.27 1.27)
							)
						)
					)
					(number "2"
						(effects
							(font
								(size 1.27 1.27)
							)
						)
					)
				)
			)
		)
	(symbol "antmicroResistors0402:R_100R_0402"
			(pin_numbers
				(hide yes)
			)
			(pin_names
				(hide yes)
			)
			(exclude_from_sim no)
			(in_bom yes)
			(on_board yes)
			(property "Reference" "R"
				(at 20.32 -5.08 0)
				(effects
					(font
						(size 1.27 1.27)
						(thickness 0.15)
					)
					(justify left bottom)
				)
			)
			(property "Value" "R_100R_0402"
				(at 20.32 -12.7 0)
				(effects
					(font
						(size 1.27 1.27)
						(thickness 0.15)
					)
					(justify left bottom)
					(hide yes)
				)
			)
			(property "Footprint" "antmicro-footprints:R_0402_1005Metric"
				(at 20.32 -15.24 0)
				(effects
					(font
						(size 1.27 1.27)
						(thickness 0.15)
					)
					(justify left bottom)
					(hide yes)
				)
			)
			(property "Datasheet" "https://www.bourns.com/docs/product-datasheets/cr.pdf"
				(at 20.32 -17.78 0)
				(effects
					(font
						(size 1.27 1.27)
						(thickness 0.15)
					)
					(justify left bottom)
					(hide yes)
				)
			)
			(property "Description" "SMD Chip Resistor, 100 ohm, ± 1%, 62.5 mW, 0402 [1005 Metric], Thick Film, General Purpose"
				(at 20.32 -30.48 0)
				(effects
					(font
						(size 1.27 1.27)
					)
					(justify left bottom)
					(hide yes)
				)
			)
			(property "MPN" "CR0402-FX-1000GLF"
				(at 20.32 -20.32 0)
				(effects
					(font
						(size 1.27 1.27)
						(thickness 0.15)
					)
					(justify left bottom)
					(hide yes)
				)
			)
			(property "Manufacturer" "Bourns"
				(at 20.32 -22.86 0)
				(effects
					(font
						(size 1.27 1.27)
						(thickness 0.15)
					)
					(justify left bottom)
					(hide yes)
				)
			)
			(property "License" "Apache-2.0"
				(at 20.32 -25.4 0)
				(effects
					(font
						(size 1.27 1.27)
						(thickness 0.15)
					)
					(justify left bottom)
					(hide yes)
				)
			)
			(property "Author" "Antmicro"
				(at 20.32 -27.94 0)
				(effects
					(font
						(size 1.27 1.27)
						(thickness 0.15)
					)
					(justify left bottom)
					(hide yes)
				)
			)
			(property "Val" "100R"
				(at 20.32 -7.62 0)
				(effects
					(font
						(size 1.27 1.27)
						(thickness 0.15)
					)
					(justify left bottom)
				)
			)
			(property "Tolerance" "1%"
				(at 20.32 -10.16 0)
				(effects
					(font
						(size 1.27 1.27)
					)
					(justify left bottom)
					(hide yes)
				)
			)
			(property "ki_keywords" "0402, SMT, RESISTOR, PASSIVE"
				(at 0 0 0)
				(effects
					(font
						(size 1.27 1.27)
					)
					(hide yes)
				)
			)
			(symbol "R_100R_0402_0_1"
				(rectangle
					(start 0.635 0.889)
					(end 4.445 -0.889)
					(stroke
						(width 0.254)
						(type default)
					)
					(fill
						(type none)
					)
				)
			)
			(symbol "R_100R_0402_1_1"
				(pin passive line
					(at 0 0 0)
					(length 0.635)
					(name "~"
						(effects
							(font
								(size 1.27 1.27)
							)
						)
					)
					(number "1"
						(effects
							(font
								(size 1.27 1.27)
							)
						)
					)
				)
				(pin passive line
					(at 5.08 0 180)
					(length 0.635)
					(name "~"
						(effects
							(font
								(size 1.27 1.27)
							)
						)
					)
					(number "2"
						(effects
							(font
								(size 1.27 1.27)
							)
						)
					)
				)
			)
		)
	(symbol "antmicroResistors0402:R_100k_0402"
			(pin_numbers
				(hide yes)
			)
			(pin_names
				(hide yes)
			)
			(exclude_from_sim no)
			(in_bom yes)
			(on_board yes)
			(property "Reference" "R"
				(at 20.32 -5.08 0)
				(effects
					(font
						(size 1.27 1.27)
						(thickness 0.15)
					)
					(justify left bottom)
				)
			)
			(property "Value" "R_100k_0402"
				(at 20.32 -12.7 0)
				(effects
					(font
						(size 1.27 1.27)
						(thickness 0.15)
					)
					(justify left bottom)
					(hide yes)
				)
			)
			(property "Footprint" "antmicro-footprints:R_0402_1005Metric"
				(at 20.32 -15.24 0)
				(effects
					(font
						(size 1.27 1.27)
						(thickness 0.15)
					)
					(justify left bottom)
					(hide yes)
				)
			)
			(property "Datasheet" "https://www.bourns.com/docs/product-datasheets/cr.pdf"
				(at 20.32 -17.78 0)
				(effects
					(font
						(size 1.27 1.27)
						(thickness 0.15)
					)
					(justify left bottom)
					(hide yes)
				)
			)
			(property "Description" "SMD Chip Resistor, 100 kohm, ± 1%, 62.5 mW, 0402 [1005 Metric], Thick Film, General Purpose"
				(at 20.32 -30.48 0)
				(effects
					(font
						(size 1.27 1.27)
					)
					(justify left bottom)
					(hide yes)
				)
			)
			(property "MPN" "CR0402-FX-1003GLF"
				(at 20.32 -20.32 0)
				(effects
					(font
						(size 1.27 1.27)
						(thickness 0.15)
					)
					(justify left bottom)
					(hide yes)
				)
			)
			(property "Manufacturer" "Bourns"
				(at 20.32 -22.86 0)
				(effects
					(font
						(size 1.27 1.27)
						(thickness 0.15)
					)
					(justify left bottom)
					(hide yes)
				)
			)
			(property "License" "Apache-2.0"
				(at 20.32 -25.4 0)
				(effects
					(font
						(size 1.27 1.27)
						(thickness 0.15)
					)
					(justify left bottom)
					(hide yes)
				)
			)
			(property "Author" "Antmicro"
				(at 20.32 -27.94 0)
				(effects
					(font
						(size 1.27 1.27)
						(thickness 0.15)
					)
					(justify left bottom)
					(hide yes)
				)
			)
			(property "Val" "100k"
				(at 20.32 -7.62 0)
				(effects
					(font
						(size 1.27 1.27)
						(thickness 0.15)
					)
					(justify left bottom)
				)
			)
			(property "Tolerance" "1%"
				(at 20.32 -10.16 0)
				(effects
					(font
						(size 1.27 1.27)
					)
					(justify left bottom)
					(hide yes)
				)
			)
			(property "ki_keywords" "0402, SMT, RESISTOR, PASSIVE"
				(at 0 0 0)
				(effects
					(font
						(size 1.27 1.27)
					)
					(hide yes)
				)
			)
			(symbol "R_100k_0402_0_1"
				(rectangle
					(start 0.635 0.889)
					(end 4.445 -0.889)
					(stroke
						(width 0.254)
						(type default)
					)
					(fill
						(type none)
					)
				)
			)
			(symbol "R_100k_0402_1_1"
				(pin passive line
					(at 0 0 0)
					(length 0.635)
					(name "~"
						(effects
							(font
								(size 1.27 1.27)
							)
						)
					)
					(number "1"
						(effects
							(font
								(size 1.27 1.27)
							)
						)
					)
				)
				(pin passive line
					(at 5.08 0 180)
					(length 0.635)
					(name "~"
						(effects
							(font
								(size 1.27 1.27)
							)
						)
					)
					(number "2"
						(effects
							(font
								(size 1.27 1.27)
							)
						)
					)
				)
			)
		)
	(symbol "antmicroResistors0402:R_10R_0402"
			(pin_numbers
				(hide yes)
			)
			(pin_names
				(hide yes)
			)
			(exclude_from_sim no)
			(in_bom yes)
			(on_board yes)
			(property "Reference" "R"
				(at 20.32 -5.08 0)
				(effects
					(font
						(size 1.27 1.27)
						(thickness 0.15)
					)
					(justify left bottom)
				)
			)
			(property "Value" "R_10R_0402"
				(at 20.32 -12.7 0)
				(effects
					(font
						(size 1.27 1.27)
						(thickness 0.15)
					)
					(justify left bottom)
					(hide yes)
				)
			)
			(property "Footprint" "antmicro-footprints:R_0402_1005Metric"
				(at 20.32 -15.24 0)
				(effects
					(font
						(size 1.27 1.27)
						(thickness 0.15)
					)
					(justify left bottom)
					(hide yes)
				)
			)
			(property "Datasheet" "https://www.bourns.com/docs/product-datasheets/cr.pdf"
				(at 20.32 -17.78 0)
				(effects
					(font
						(size 1.27 1.27)
						(thickness 0.15)
					)
					(justify left bottom)
					(hide yes)
				)
			)
			(property "Description" "SMD Chip Resistor, 10 ohm, ± 1%, 62.5 mW, 0402 [1005 Metric], Thick Film, General Purpose"
				(at 20.32 -30.48 0)
				(effects
					(font
						(size 1.27 1.27)
					)
					(justify left bottom)
					(hide yes)
				)
			)
			(property "MPN" "CR0402-FX-10R0GLF"
				(at 20.32 -20.32 0)
				(effects
					(font
						(size 1.27 1.27)
						(thickness 0.15)
					)
					(justify left bottom)
					(hide yes)
				)
			)
			(property "Manufacturer" "Bourns"
				(at 20.32 -22.86 0)
				(effects
					(font
						(size 1.27 1.27)
						(thickness 0.15)
					)
					(justify left bottom)
					(hide yes)
				)
			)
			(property "License" "Apache-2.0"
				(at 20.32 -25.4 0)
				(effects
					(font
						(size 1.27 1.27)
						(thickness 0.15)
					)
					(justify left bottom)
					(hide yes)
				)
			)
			(property "Author" "Antmicro"
				(at 20.32 -27.94 0)
				(effects
					(font
						(size 1.27 1.27)
						(thickness 0.15)
					)
					(justify left bottom)
					(hide yes)
				)
			)
			(property "Val" "10R"
				(at 20.32 -7.62 0)
				(effects
					(font
						(size 1.27 1.27)
						(thickness 0.15)
					)
					(justify left bottom)
				)
			)
			(property "Tolerance" "1%"
				(at 20.32 -10.16 0)
				(effects
					(font
						(size 1.27 1.27)
					)
					(justify left bottom)
					(hide yes)
				)
			)
			(property "ki_keywords" "0402, SMT, RESISTOR, PASSIVE"
				(at 0 0 0)
				(effects
					(font
						(size 1.27 1.27)
					)
					(hide yes)
				)
			)
			(symbol "R_10R_0402_0_1"
				(rectangle
					(start 0.635 0.889)
					(end 4.445 -0.889)
					(stroke
						(width 0.254)
						(type default)
					)
					(fill
						(type none)
					)
				)
			)
			(symbol "R_10R_0402_1_1"
				(pin passive line
					(at 0 0 0)
					(length 0.635)
					(name "~"
						(effects
							(font
								(size 1.27 1.27)
							)
						)
					)
					(number "1"
						(effects
							(font
								(size 1.27 1.27)
							)
						)
					)
				)
				(pin passive line
					(at 5.08 0 180)
					(length 0.635)
					(name "~"
						(effects
							(font
								(size 1.27 1.27)
							)
						)
					)
					(number "2"
						(effects
							(font
								(size 1.27 1.27)
							)
						)
					)
				)
			)
		)
	(symbol "antmicroResistors0402:R_10k_0402"
			(pin_numbers
				(hide yes)
			)
			(pin_names
				(hide yes)
			)
			(exclude_from_sim no)
			(in_bom yes)
			(on_board yes)
			(property "Reference" "R"
				(at 20.32 -5.08 0)
				(effects
					(font
						(size 1.27 1.27)
						(thickness 0.15)
					)
					(justify left bottom)
				)
			)
			(property "Value" "R_10k_0402"
				(at 20.32 -12.7 0)
				(effects
					(font
						(size 1.27 1.27)
						(thickness 0.15)
					)
					(justify left bottom)
					(hide yes)
				)
			)
			(property "Footprint" "antmicro-footprints:R_0402_1005Metric"
				(at 20.32 -15.24 0)
				(effects
					(font
						(size 1.27 1.27)
						(thickness 0.15)
					)
					(justify left bottom)
					(hide yes)
				)
			)
			(property "Datasheet" "https://www.bourns.com/docs/product-datasheets/cr.pdf"
				(at 20.32 -17.78 0)
				(effects
					(font
						(size 1.27 1.27)
						(thickness 0.15)
					)
					(justify left bottom)
					(hide yes)
				)
			)
			(property "Description" "SMD Chip Resistor, 10 kohm, ± 1%, 62.5 mW, 0402 [1005 Metric], Thick Film, General Purpose"
				(at 20.32 -30.48 0)
				(effects
					(font
						(size 1.27 1.27)
					)
					(justify left bottom)
					(hide yes)
				)
			)
			(property "MPN" "CR0402-FX-1002GLF"
				(at 20.32 -20.32 0)
				(effects
					(font
						(size 1.27 1.27)
						(thickness 0.15)
					)
					(justify left bottom)
					(hide yes)
				)
			)
			(property "Manufacturer" "Bourns"
				(at 20.32 -22.86 0)
				(effects
					(font
						(size 1.27 1.27)
						(thickness 0.15)
					)
					(justify left bottom)
					(hide yes)
				)
			)
			(property "License" "Apache-2.0"
				(at 20.32 -25.4 0)
				(effects
					(font
						(size 1.27 1.27)
						(thickness 0.15)
					)
					(justify left bottom)
					(hide yes)
				)
			)
			(property "Author" "Antmicro"
				(at 20.32 -27.94 0)
				(effects
					(font
						(size 1.27 1.27)
						(thickness 0.15)
					)
					(justify left bottom)
					(hide yes)
				)
			)
			(property "Val" "10k"
				(at 20.32 -7.62 0)
				(effects
					(font
						(size 1.27 1.27)
						(thickness 0.15)
					)
					(justify left bottom)
				)
			)
			(property "Tolerance" "1%"
				(at 20.32 -10.16 0)
				(effects
					(font
						(size 1.27 1.27)
					)
					(justify left bottom)
					(hide yes)
				)
			)
			(property "ki_keywords" "0402, SMT, RESISTOR, PASSIVE"
				(at 0 0 0)
				(effects
					(font
						(size 1.27 1.27)
					)
					(hide yes)
				)
			)
			(symbol "R_10k_0402_0_1"
				(rectangle
					(start 0.635 0.889)
					(end 4.445 -0.889)
					(stroke
						(width 0.254)
						(type default)
					)
					(fill
						(type none)
					)
				)
			)
			(symbol "R_10k_0402_1_1"
				(pin passive line
					(at 0 0 0)
					(length 0.635)
					(name "~"
						(effects
							(font
								(size 1.27 1.27)
							)
						)
					)
					(number "1"
						(effects
							(font
								(size 1.27 1.27)
							)
						)
					)
				)
				(pin passive line
					(at 5.08 0 180)
					(length 0.635)
					(name "~"
						(effects
							(font
								(size 1.27 1.27)
							)
						)
					)
					(number "2"
						(effects
							(font
								(size 1.27 1.27)
							)
						)
					)
				)
			)
		)
	(symbol "antmicroResistors0402:R_14k_0402"
			(pin_numbers
				(hide yes)
			)
			(pin_names
				(hide yes)
			)
			(exclude_from_sim no)
			(in_bom yes)
			(on_board yes)
			(property "Reference" "R"
				(at 20.32 -5.08 0)
				(effects
					(font
						(size 1.27 1.27)
						(thickness 0.15)
					)
					(justify left bottom)
				)
			)
			(property "Value" "R_14k_0402"
				(at 20.32 -12.7 0)
				(effects
					(font
						(size 1.27 1.27)
						(thickness 0.15)
					)
					(justify left bottom)
					(hide yes)
				)
			)
			(property "Footprint" "antmicro-footprints:R_0402_1005Metric"
				(at 20.32 -15.24 0)
				(effects
					(font
						(size 1.27 1.27)
						(thickness 0.15)
					)
					(justify left bottom)
					(hide yes)
				)
			)
			(property "Datasheet" "https://www.bourns.com/docs/product-datasheets/cr.pdf"
				(at 20.32 -17.78 0)
				(effects
					(font
						(size 1.27 1.27)
						(thickness 0.15)
					)
					(justify left bottom)
					(hide yes)
				)
			)
			(property "Description" "SMD Chip Resistor, 14 kohm, ± 1%, 100 mW, 0402 [1005 Metric], Thick Film, Precision"
				(at 20.32 -30.48 0)
				(effects
					(font
						(size 1.27 1.27)
					)
					(justify left bottom)
					(hide yes)
				)
			)
			(property "MPN" "CR0402-FX-1402GLF"
				(at 20.32 -20.32 0)
				(effects
					(font
						(size 1.27 1.27)
						(thickness 0.15)
					)
					(justify left bottom)
					(hide yes)
				)
			)
			(property "Manufacturer" "Bourns"
				(at 20.32 -22.86 0)
				(effects
					(font
						(size 1.27 1.27)
						(thickness 0.15)
					)
					(justify left bottom)
					(hide yes)
				)
			)
			(property "License" "Apache-2.0"
				(at 20.32 -25.4 0)
				(effects
					(font
						(size 1.27 1.27)
						(thickness 0.15)
					)
					(justify left bottom)
					(hide yes)
				)
			)
			(property "Author" "Antmicro"
				(at 20.32 -27.94 0)
				(effects
					(font
						(size 1.27 1.27)
						(thickness 0.15)
					)
					(justify left bottom)
					(hide yes)
				)
			)
			(property "Val" "14k"
				(at 20.32 -7.62 0)
				(effects
					(font
						(size 1.27 1.27)
						(thickness 0.15)
					)
					(justify left bottom)
				)
			)
			(property "Tolerance" "1%"
				(at 20.32 -10.16 0)
				(effects
					(font
						(size 1.27 1.27)
					)
					(justify left bottom)
					(hide yes)
				)
			)
			(property "ki_keywords" "0402, SMT, RESISTOR, PASSIVE"
				(at 0 0 0)
				(effects
					(font
						(size 1.27 1.27)
					)
					(hide yes)
				)
			)
			(symbol "R_14k_0402_0_1"
				(rectangle
					(start 0.635 0.889)
					(end 4.445 -0.889)
					(stroke
						(width 0.254)
						(type default)
					)
					(fill
						(type none)
					)
				)
			)
			(symbol "R_14k_0402_1_1"
				(pin passive line
					(at 0 0 0)
					(length 0.635)
					(name "~"
						(effects
							(font
								(size 1.27 1.27)
							)
						)
					)
					(number "1"
						(effects
							(font
								(size 1.27 1.27)
							)
						)
					)
				)
				(pin passive line
					(at 5.08 0 180)
					(length 0.635)
					(name "~"
						(effects
							(font
								(size 1.27 1.27)
							)
						)
					)
					(number "2"
						(effects
							(font
								(size 1.27 1.27)
							)
						)
					)
				)
			)
		)
	(symbol "antmicroResistors0402:R_150R_0402"
			(pin_numbers
				(hide yes)
			)
			(pin_names
				(hide yes)
			)
			(exclude_from_sim no)
			(in_bom yes)
			(on_board yes)
			(property "Reference" "R"
				(at 20.32 -5.08 0)
				(effects
					(font
						(size 1.27 1.27)
						(thickness 0.15)
					)
					(justify left bottom)
				)
			)
			(property "Value" "R_150R_0402"
				(at 20.32 -12.7 0)
				(effects
					(font
						(size 1.27 1.27)
						(thickness 0.15)
					)
					(justify left bottom)
					(hide yes)
				)
			)
			(property "Footprint" "antmicro-footprints:R_0402_1005Metric"
				(at 20.32 -15.24 0)
				(effects
					(font
						(size 1.27 1.27)
						(thickness 0.15)
					)
					(justify left bottom)
					(hide yes)
				)
			)
			(property "Datasheet" "https://www.bourns.com/docs/product-datasheets/cr.pdf"
				(at 20.32 -17.78 0)
				(effects
					(font
						(size 1.27 1.27)
						(thickness 0.15)
					)
					(justify left bottom)
					(hide yes)
				)
			)
			(property "Description" "SMD Chip Resistor, 150 ohm, ± 1%, 62.5 mW, 0402 [1005 Metric], Thick Film, General Purpose"
				(at 20.32 -30.48 0)
				(effects
					(font
						(size 1.27 1.27)
					)
					(justify left bottom)
					(hide yes)
				)
			)
			(property "MPN" "CR0402-FX-1500GLF"
				(at 20.32 -20.32 0)
				(effects
					(font
						(size 1.27 1.27)
						(thickness 0.15)
					)
					(justify left bottom)
					(hide yes)
				)
			)
			(property "Manufacturer" "Bourns"
				(at 20.32 -22.86 0)
				(effects
					(font
						(size 1.27 1.27)
						(thickness 0.15)
					)
					(justify left bottom)
					(hide yes)
				)
			)
			(property "License" "Apache-2.0"
				(at 20.32 -25.4 0)
				(effects
					(font
						(size 1.27 1.27)
						(thickness 0.15)
					)
					(justify left bottom)
					(hide yes)
				)
			)
			(property "Author" "Antmicro"
				(at 20.32 -27.94 0)
				(effects
					(font
						(size 1.27 1.27)
						(thickness 0.15)
					)
					(justify left bottom)
					(hide yes)
				)
			)
			(property "Val" "150R"
				(at 20.32 -7.62 0)
				(effects
					(font
						(size 1.27 1.27)
						(thickness 0.15)
					)
					(justify left bottom)
				)
			)
			(property "Tolerance" "1%"
				(at 20.32 -10.16 0)
				(effects
					(font
						(size 1.27 1.27)
					)
					(justify left bottom)
					(hide yes)
				)
			)
			(property "ki_keywords" "0402, SMT, RESISTOR, PASSIVE"
				(at 0 0 0)
				(effects
					(font
						(size 1.27 1.27)
					)
					(hide yes)
				)
			)
			(symbol "R_150R_0402_0_1"
				(rectangle
					(start 0.635 0.889)
					(end 4.445 -0.889)
					(stroke
						(width 0.254)
						(type default)
					)
					(fill
						(type none)
					)
				)
			)
			(symbol "R_150R_0402_1_1"
				(pin passive line
					(at 0 0 0)
					(length 0.635)
					(name "~"
						(effects
							(font
								(size 1.27 1.27)
							)
						)
					)
					(number "1"
						(effects
							(font
								(size 1.27 1.27)
							)
						)
					)
				)
				(pin passive line
					(at 5.08 0 180)
					(length 0.635)
					(name "~"
						(effects
							(font
								(size 1.27 1.27)
							)
						)
					)
					(number "2"
						(effects
							(font
								(size 1.27 1.27)
							)
						)
					)
				)
			)
		)
	(symbol "antmicroResistors0402:R_15k_0.1%_0402"
			(pin_numbers
				(hide yes)
			)
			(pin_names
				(hide yes)
			)
			(exclude_from_sim no)
			(in_bom yes)
			(on_board yes)
			(property "Reference" "R"
				(at 20.32 -5.08 0)
				(effects
					(font
						(size 1.27 1.27)
						(thickness 0.15)
					)
					(justify left bottom)
				)
			)
			(property "Value" "R_15k_0.1%_0402"
				(at 20.32 -12.7 0)
				(effects
					(font
						(size 1.27 1.27)
						(thickness 0.15)
					)
					(justify left bottom)
					(hide yes)
				)
			)
			(property "Footprint" "antmicro-footprints:R_0402_1005Metric"
				(at 20.32 -15.24 0)
				(effects
					(font
						(size 1.27 1.27)
						(thickness 0.15)
					)
					(justify left bottom)
					(hide yes)
				)
			)
			(property "Datasheet" "https://www.mouser.com/datasheet/2/315/AOA0000C307-1149632.pdf"
				(at 20.32 -17.78 0)
				(effects
					(font
						(size 1.27 1.27)
						(thickness 0.15)
					)
					(justify left bottom)
					(hide yes)
				)
			)
			(property "Description" "SMD Chip Resistor, 15 kohm, ± 0.1%, 62.5 mW, 0402 [1005 Metric], Metal Film (Thin Film)"
				(at 20.32 -30.48 0)
				(effects
					(font
						(size 1.27 1.27)
					)
					(justify left bottom)
					(hide yes)
				)
			)
			(property "MPN" "ERA-2ARB153X"
				(at 20.32 -20.32 0)
				(effects
					(font
						(size 1.27 1.27)
						(thickness 0.15)
					)
					(justify left bottom)
					(hide yes)
				)
			)
			(property "Manufacturer" "Panasonic"
				(at 20.32 -22.86 0)
				(effects
					(font
						(size 1.27 1.27)
						(thickness 0.15)
					)
					(justify left bottom)
					(hide yes)
				)
			)
			(property "License" "Apache-2.0"
				(at 20.32 -25.4 0)
				(effects
					(font
						(size 1.27 1.27)
						(thickness 0.15)
					)
					(justify left bottom)
					(hide yes)
				)
			)
			(property "Author" "Antmicro"
				(at 20.32 -27.94 0)
				(effects
					(font
						(size 1.27 1.27)
						(thickness 0.15)
					)
					(justify left bottom)
					(hide yes)
				)
			)
			(property "Val" "15k"
				(at 20.32 -7.62 0)
				(effects
					(font
						(size 1.27 1.27)
						(thickness 0.15)
					)
					(justify left bottom)
				)
			)
			(property "Tolerance" "0.1%"
				(at 20.32 -10.16 0)
				(effects
					(font
						(size 1.27 1.27)
					)
					(justify left bottom)
					(hide yes)
				)
			)
			(property "ki_keywords" "0402, SMT, RESISTOR, PASSIVE"
				(at 0 0 0)
				(effects
					(font
						(size 1.27 1.27)
					)
					(hide yes)
				)
			)
			(symbol "R_15k_0.1%_0402_0_1"
				(rectangle
					(start 0.635 0.889)
					(end 4.445 -0.889)
					(stroke
						(width 0.254)
						(type default)
					)
					(fill
						(type none)
					)
				)
			)
			(symbol "R_15k_0.1%_0402_1_1"
				(pin passive line
					(at 0 0 0)
					(length 0.635)
					(name "~"
						(effects
							(font
								(size 1.27 1.27)
							)
						)
					)
					(number "1"
						(effects
							(font
								(size 1.27 1.27)
							)
						)
					)
				)
				(pin passive line
					(at 5.08 0 180)
					(length 0.635)
					(name "~"
						(effects
							(font
								(size 1.27 1.27)
							)
						)
					)
					(number "2"
						(effects
							(font
								(size 1.27 1.27)
							)
						)
					)
				)
			)
		)
	(symbol "antmicroResistors0402:R_16k_0402"
			(pin_numbers
				(hide yes)
			)
			(pin_names
				(hide yes)
			)
			(exclude_from_sim no)
			(in_bom yes)
			(on_board yes)
			(property "Reference" "R"
				(at 20.32 -5.08 0)
				(effects
					(font
						(size 1.27 1.27)
						(thickness 0.15)
					)
					(justify left bottom)
				)
			)
			(property "Value" "R_16k_0402"
				(at 20.32 -12.7 0)
				(effects
					(font
						(size 1.27 1.27)
						(thickness 0.15)
					)
					(justify left bottom)
					(hide yes)
				)
			)
			(property "Footprint" "antmicro-footprints:R_0402_1005Metric"
				(at 20.32 -15.24 0)
				(effects
					(font
						(size 1.27 1.27)
						(thickness 0.15)
					)
					(justify left bottom)
					(hide yes)
				)
			)
			(property "Datasheet" "https://www.bourns.com/docs/product-datasheets/cr.pdf"
				(at 20.32 -17.78 0)
				(effects
					(font
						(size 1.27 1.27)
						(thickness 0.15)
					)
					(justify left bottom)
					(hide yes)
				)
			)
			(property "Description" "SMD Chip Resistor"
				(at 20.32 -30.48 0)
				(effects
					(font
						(size 1.27 1.27)
					)
					(justify left bottom)
					(hide yes)
				)
			)
			(property "MPN" "CR0402-FX-1602GLF"
				(at 20.32 -20.32 0)
				(effects
					(font
						(size 1.27 1.27)
						(thickness 0.15)
					)
					(justify left bottom)
					(hide yes)
				)
			)
			(property "Manufacturer" "Bourns"
				(at 20.32 -22.86 0)
				(effects
					(font
						(size 1.27 1.27)
						(thickness 0.15)
					)
					(justify left bottom)
					(hide yes)
				)
			)
			(property "License" "Apache-2.0"
				(at 20.32 -25.4 0)
				(effects
					(font
						(size 1.27 1.27)
						(thickness 0.15)
					)
					(justify left bottom)
					(hide yes)
				)
			)
			(property "Author" "Antmicro"
				(at 20.32 -27.94 0)
				(effects
					(font
						(size 1.27 1.27)
						(thickness 0.15)
					)
					(justify left bottom)
					(hide yes)
				)
			)
			(property "Val" "16k"
				(at 20.32 -7.62 0)
				(effects
					(font
						(size 1.27 1.27)
						(thickness 0.15)
					)
					(justify left bottom)
				)
			)
			(property "Tolerance" "1%"
				(at 20.32 -10.16 0)
				(effects
					(font
						(size 1.27 1.27)
					)
					(justify left bottom)
					(hide yes)
				)
			)
			(property "ki_keywords" "0402, SMT, RESISTOR, PASSIVE"
				(at 0 0 0)
				(effects
					(font
						(size 1.27 1.27)
					)
					(hide yes)
				)
			)
			(symbol "R_16k_0402_0_1"
				(rectangle
					(start 0.635 0.889)
					(end 4.445 -0.889)
					(stroke
						(width 0.254)
						(type default)
					)
					(fill
						(type none)
					)
				)
			)
			(symbol "R_16k_0402_1_1"
				(pin passive line
					(at 0 0 0)
					(length 0.635)
					(name "~"
						(effects
							(font
								(size 1.27 1.27)
							)
						)
					)
					(number "1"
						(effects
							(font
								(size 1.27 1.27)
							)
						)
					)
				)
				(pin passive line
					(at 5.08 0 180)
					(length 0.635)
					(name "~"
						(effects
							(font
								(size 1.27 1.27)
							)
						)
					)
					(number "2"
						(effects
							(font
								(size 1.27 1.27)
							)
						)
					)
				)
			)
		)
	(symbol "antmicroResistors0402:R_1M_0402"
			(pin_numbers
				(hide yes)
			)
			(pin_names
				(hide yes)
			)
			(exclude_from_sim no)
			(in_bom yes)
			(on_board yes)
			(property "Reference" "R"
				(at 20.32 -5.08 0)
				(effects
					(font
						(size 1.27 1.27)
						(thickness 0.15)
					)
					(justify left bottom)
				)
			)
			(property "Value" "R_1M_0402"
				(at 20.32 -12.7 0)
				(effects
					(font
						(size 1.27 1.27)
						(thickness 0.15)
					)
					(justify left bottom)
					(hide yes)
				)
			)
			(property "Footprint" "antmicro-footprints:R_0402_1005Metric"
				(at 20.32 -15.24 0)
				(effects
					(font
						(size 1.27 1.27)
						(thickness 0.15)
					)
					(justify left bottom)
					(hide yes)
				)
			)
			(property "Datasheet" "https://www.bourns.com/docs/product-datasheets/cr.pdf"
				(at 20.32 -17.78 0)
				(effects
					(font
						(size 1.27 1.27)
						(thickness 0.15)
					)
					(justify left bottom)
					(hide yes)
				)
			)
			(property "Description" "SMD Chip Resistor, 1 Mohm, ± 1%, 62.5 mW, 0402 [1005 Metric], Thick Film, General Purpose"
				(at 20.32 -30.48 0)
				(effects
					(font
						(size 1.27 1.27)
					)
					(justify left bottom)
					(hide yes)
				)
			)
			(property "MPN" "CR0402-FX-1004GLF"
				(at 20.32 -20.32 0)
				(effects
					(font
						(size 1.27 1.27)
						(thickness 0.15)
					)
					(justify left bottom)
					(hide yes)
				)
			)
			(property "Manufacturer" "Bourns"
				(at 20.32 -22.86 0)
				(effects
					(font
						(size 1.27 1.27)
						(thickness 0.15)
					)
					(justify left bottom)
					(hide yes)
				)
			)
			(property "License" "Apache-2.0"
				(at 20.32 -25.4 0)
				(effects
					(font
						(size 1.27 1.27)
						(thickness 0.15)
					)
					(justify left bottom)
					(hide yes)
				)
			)
			(property "Author" "Antmicro"
				(at 20.32 -27.94 0)
				(effects
					(font
						(size 1.27 1.27)
						(thickness 0.15)
					)
					(justify left bottom)
					(hide yes)
				)
			)
			(property "Val" "1M"
				(at 20.32 -7.62 0)
				(effects
					(font
						(size 1.27 1.27)
						(thickness 0.15)
					)
					(justify left bottom)
				)
			)
			(property "Tolerance" "1%"
				(at 20.32 -10.16 0)
				(effects
					(font
						(size 1.27 1.27)
					)
					(justify left bottom)
					(hide yes)
				)
			)
			(property "ki_keywords" "0402, SMT, RESISTOR, PASSIVE"
				(at 0 0 0)
				(effects
					(font
						(size 1.27 1.27)
					)
					(hide yes)
				)
			)
			(symbol "R_1M_0402_0_1"
				(rectangle
					(start 0.635 0.889)
					(end 4.445 -0.889)
					(stroke
						(width 0.254)
						(type default)
					)
					(fill
						(type none)
					)
				)
			)
			(symbol "R_1M_0402_1_1"
				(pin passive line
					(at 0 0 0)
					(length 0.635)
					(name "~"
						(effects
							(font
								(size 1.27 1.27)
							)
						)
					)
					(number "1"
						(effects
							(font
								(size 1.27 1.27)
							)
						)
					)
				)
				(pin passive line
					(at 5.08 0 180)
					(length 0.635)
					(name "~"
						(effects
							(font
								(size 1.27 1.27)
							)
						)
					)
					(number "2"
						(effects
							(font
								(size 1.27 1.27)
							)
						)
					)
				)
			)
		)
	(symbol "antmicroResistors0402:R_1k_0402"
			(pin_numbers
				(hide yes)
			)
			(pin_names
				(hide yes)
			)
			(exclude_from_sim no)
			(in_bom yes)
			(on_board yes)
			(property "Reference" "R"
				(at 20.32 -5.08 0)
				(effects
					(font
						(size 1.27 1.27)
						(thickness 0.15)
					)
					(justify left bottom)
				)
			)
			(property "Value" "R_1k_0402"
				(at 20.32 -12.7 0)
				(effects
					(font
						(size 1.27 1.27)
						(thickness 0.15)
					)
					(justify left bottom)
					(hide yes)
				)
			)
			(property "Footprint" "antmicro-footprints:R_0402_1005Metric"
				(at 20.32 -15.24 0)
				(effects
					(font
						(size 1.27 1.27)
						(thickness 0.15)
					)
					(justify left bottom)
					(hide yes)
				)
			)
			(property "Datasheet" "https://www.bourns.com/docs/product-datasheets/cr.pdf"
				(at 20.32 -17.78 0)
				(effects
					(font
						(size 1.27 1.27)
						(thickness 0.15)
					)
					(justify left bottom)
					(hide yes)
				)
			)
			(property "Description" "SMD Chip Resistor, 1 kohm, ± 1%, 63 mW, 0402 [1005 Metric], Thick Film, General Purpose"
				(at 20.32 -30.48 0)
				(effects
					(font
						(size 1.27 1.27)
					)
					(justify left bottom)
					(hide yes)
				)
			)
			(property "MPN" "CR0402-FX-1001GLF"
				(at 20.32 -20.32 0)
				(effects
					(font
						(size 1.27 1.27)
						(thickness 0.15)
					)
					(justify left bottom)
					(hide yes)
				)
			)
			(property "Manufacturer" "Bourns"
				(at 20.32 -22.86 0)
				(effects
					(font
						(size 1.27 1.27)
						(thickness 0.15)
					)
					(justify left bottom)
					(hide yes)
				)
			)
			(property "License" "Apache-2.0"
				(at 20.32 -25.4 0)
				(effects
					(font
						(size 1.27 1.27)
						(thickness 0.15)
					)
					(justify left bottom)
					(hide yes)
				)
			)
			(property "Author" "Antmicro"
				(at 20.32 -27.94 0)
				(effects
					(font
						(size 1.27 1.27)
						(thickness 0.15)
					)
					(justify left bottom)
					(hide yes)
				)
			)
			(property "Val" "1k"
				(at 20.32 -7.62 0)
				(effects
					(font
						(size 1.27 1.27)
						(thickness 0.15)
					)
					(justify left bottom)
				)
			)
			(property "Tolerance" "1%"
				(at 20.32 -10.16 0)
				(effects
					(font
						(size 1.27 1.27)
					)
					(justify left bottom)
					(hide yes)
				)
			)
			(property "ki_keywords" "0402, SMT, RESISTOR, PASSIVE"
				(at 0 0 0)
				(effects
					(font
						(size 1.27 1.27)
					)
					(hide yes)
				)
			)
			(symbol "R_1k_0402_0_1"
				(rectangle
					(start 0.635 0.889)
					(end 4.445 -0.889)
					(stroke
						(width 0.254)
						(type default)
					)
					(fill
						(type none)
					)
				)
			)
			(symbol "R_1k_0402_1_1"
				(pin passive line
					(at 0 0 0)
					(length 0.635)
					(name "~"
						(effects
							(font
								(size 1.27 1.27)
							)
						)
					)
					(number "1"
						(effects
							(font
								(size 1.27 1.27)
							)
						)
					)
				)
				(pin passive line
					(at 5.08 0 180)
					(length 0.635)
					(name "~"
						(effects
							(font
								(size 1.27 1.27)
							)
						)
					)
					(number "2"
						(effects
							(font
								(size 1.27 1.27)
							)
						)
					)
				)
			)
		)
	(symbol "antmicroResistors0402:R_200k_0402"
			(pin_numbers
				(hide yes)
			)
			(pin_names
				(hide yes)
			)
			(exclude_from_sim no)
			(in_bom yes)
			(on_board yes)
			(property "Reference" "R"
				(at 20.32 -5.08 0)
				(effects
					(font
						(size 1.27 1.27)
						(thickness 0.15)
					)
					(justify left bottom)
				)
			)
			(property "Value" "R_200k_0402"
				(at 20.32 -12.7 0)
				(effects
					(font
						(size 1.27 1.27)
						(thickness 0.15)
					)
					(justify left bottom)
					(hide yes)
				)
			)
			(property "Footprint" "antmicro-footprints:R_0402_1005Metric"
				(at 20.32 -15.24 0)
				(effects
					(font
						(size 1.27 1.27)
						(thickness 0.15)
					)
					(justify left bottom)
					(hide yes)
				)
			)
			(property "Datasheet" "https://www.bourns.com/docs/product-datasheets/cr.pdf"
				(at 20.32 -17.78 0)
				(effects
					(font
						(size 1.27 1.27)
						(thickness 0.15)
					)
					(justify left bottom)
					(hide yes)
				)
			)
			(property "Description" "SMD Chip Resistor, 200 kohm, ± 1%, 62.5 mW, 0402 [1005 Metric], Thick Film, General Purpose"
				(at 20.32 -30.48 0)
				(effects
					(font
						(size 1.27 1.27)
					)
					(justify left bottom)
					(hide yes)
				)
			)
			(property "MPN" "CR0402-FX-2003GLF"
				(at 20.32 -20.32 0)
				(effects
					(font
						(size 1.27 1.27)
						(thickness 0.15)
					)
					(justify left bottom)
					(hide yes)
				)
			)
			(property "Manufacturer" "Bourns"
				(at 20.32 -22.86 0)
				(effects
					(font
						(size 1.27 1.27)
						(thickness 0.15)
					)
					(justify left bottom)
					(hide yes)
				)
			)
			(property "License" "Apache-2.0"
				(at 20.32 -25.4 0)
				(effects
					(font
						(size 1.27 1.27)
						(thickness 0.15)
					)
					(justify left bottom)
					(hide yes)
				)
			)
			(property "Author" "Antmicro"
				(at 20.32 -27.94 0)
				(effects
					(font
						(size 1.27 1.27)
						(thickness 0.15)
					)
					(justify left bottom)
					(hide yes)
				)
			)
			(property "Val" "200k"
				(at 20.32 -7.62 0)
				(effects
					(font
						(size 1.27 1.27)
						(thickness 0.15)
					)
					(justify left bottom)
				)
			)
			(property "Tolerance" "1%"
				(at 20.32 -10.16 0)
				(effects
					(font
						(size 1.27 1.27)
					)
					(justify left bottom)
					(hide yes)
				)
			)
			(property "ki_keywords" "0402, SMT, RESISTOR, PASSIVE"
				(at 0 0 0)
				(effects
					(font
						(size 1.27 1.27)
					)
					(hide yes)
				)
			)
			(symbol "R_200k_0402_0_1"
				(rectangle
					(start 0.635 0.889)
					(end 4.445 -0.889)
					(stroke
						(width 0.254)
						(type default)
					)
					(fill
						(type none)
					)
				)
			)
			(symbol "R_200k_0402_1_1"
				(pin passive line
					(at 0 0 0)
					(length 0.635)
					(name "~"
						(effects
							(font
								(size 1.27 1.27)
							)
						)
					)
					(number "1"
						(effects
							(font
								(size 1.27 1.27)
							)
						)
					)
				)
				(pin passive line
					(at 5.08 0 180)
					(length 0.635)
					(name "~"
						(effects
							(font
								(size 1.27 1.27)
							)
						)
					)
					(number "2"
						(effects
							(font
								(size 1.27 1.27)
							)
						)
					)
				)
			)
		)
	(symbol "antmicroResistors0402:R_20k_0402"
			(pin_numbers
				(hide yes)
			)
			(pin_names
				(hide yes)
			)
			(exclude_from_sim no)
			(in_bom yes)
			(on_board yes)
			(property "Reference" "R"
				(at 20.32 -5.08 0)
				(effects
					(font
						(size 1.27 1.27)
						(thickness 0.15)
					)
					(justify left bottom)
				)
			)
			(property "Value" "R_20k_0402"
				(at 20.32 -12.7 0)
				(effects
					(font
						(size 1.27 1.27)
						(thickness 0.15)
					)
					(justify left bottom)
					(hide yes)
				)
			)
			(property "Footprint" "antmicro-footprints:R_0402_1005Metric"
				(at 20.32 -15.24 0)
				(effects
					(font
						(size 1.27 1.27)
						(thickness 0.15)
					)
					(justify left bottom)
					(hide yes)
				)
			)
			(property "Datasheet" "https://www.bourns.com/docs/product-datasheets/cr.pdf"
				(at 20.32 -17.78 0)
				(effects
					(font
						(size 1.27 1.27)
						(thickness 0.15)
					)
					(justify left bottom)
					(hide yes)
				)
			)
			(property "Description" "SMD Chip Resistor, 20 kohm, ± 1%, 62.5 mW, 0402 [1005 Metric], Thick Film, General Purpose"
				(at 20.32 -30.48 0)
				(effects
					(font
						(size 1.27 1.27)
					)
					(justify left bottom)
					(hide yes)
				)
			)
			(property "MPN" "CR0402-FX-2002GLF"
				(at 20.32 -20.32 0)
				(effects
					(font
						(size 1.27 1.27)
						(thickness 0.15)
					)
					(justify left bottom)
					(hide yes)
				)
			)
			(property "Manufacturer" "Bourns"
				(at 20.32 -22.86 0)
				(effects
					(font
						(size 1.27 1.27)
						(thickness 0.15)
					)
					(justify left bottom)
					(hide yes)
				)
			)
			(property "License" "Apache-2.0"
				(at 20.32 -25.4 0)
				(effects
					(font
						(size 1.27 1.27)
						(thickness 0.15)
					)
					(justify left bottom)
					(hide yes)
				)
			)
			(property "Author" "Antmicro"
				(at 20.32 -27.94 0)
				(effects
					(font
						(size 1.27 1.27)
						(thickness 0.15)
					)
					(justify left bottom)
					(hide yes)
				)
			)
			(property "Val" "20k"
				(at 20.32 -7.62 0)
				(effects
					(font
						(size 1.27 1.27)
						(thickness 0.15)
					)
					(justify left bottom)
				)
			)
			(property "Tolerance" "1%"
				(at 20.32 -10.16 0)
				(effects
					(font
						(size 1.27 1.27)
					)
					(justify left bottom)
					(hide yes)
				)
			)
			(property "ki_keywords" "0402, SMT, RESISTOR, PASSIVE"
				(at 0 0 0)
				(effects
					(font
						(size 1.27 1.27)
					)
					(hide yes)
				)
			)
			(symbol "R_20k_0402_0_1"
				(rectangle
					(start 0.635 0.889)
					(end 4.445 -0.889)
					(stroke
						(width 0.254)
						(type default)
					)
					(fill
						(type none)
					)
				)
			)
			(symbol "R_20k_0402_1_1"
				(pin passive line
					(at 0 0 0)
					(length 0.635)
					(name "~"
						(effects
							(font
								(size 1.27 1.27)
							)
						)
					)
					(number "1"
						(effects
							(font
								(size 1.27 1.27)
							)
						)
					)
				)
				(pin passive line
					(at 5.08 0 180)
					(length 0.635)
					(name "~"
						(effects
							(font
								(size 1.27 1.27)
							)
						)
					)
					(number "2"
						(effects
							(font
								(size 1.27 1.27)
							)
						)
					)
				)
			)
		)
	(symbol "antmicroResistors0402:R_220R_0402"
			(pin_numbers
				(hide yes)
			)
			(pin_names
				(hide yes)
			)
			(exclude_from_sim no)
			(in_bom yes)
			(on_board yes)
			(property "Reference" "R"
				(at 20.32 -5.08 0)
				(effects
					(font
						(size 1.27 1.27)
						(thickness 0.15)
					)
					(justify left bottom)
				)
			)
			(property "Value" "R_220R_0402"
				(at 20.32 -12.7 0)
				(effects
					(font
						(size 1.27 1.27)
						(thickness 0.15)
					)
					(justify left bottom)
					(hide yes)
				)
			)
			(property "Footprint" "antmicro-footprints:R_0402_1005Metric"
				(at 20.32 -15.24 0)
				(effects
					(font
						(size 1.27 1.27)
						(thickness 0.15)
					)
					(justify left bottom)
					(hide yes)
				)
			)
			(property "Datasheet" "https://www.bourns.com/docs/product-datasheets/cr.pdf"
				(at 20.32 -17.78 0)
				(effects
					(font
						(size 1.27 1.27)
						(thickness 0.15)
					)
					(justify left bottom)
					(hide yes)
				)
			)
			(property "Description" "SMD Chip Resistor, 220 ohm, ± 1%, 62.5 mW, 0402 [1005 Metric], Thick Film, General Purpose"
				(at 20.32 -30.48 0)
				(effects
					(font
						(size 1.27 1.27)
					)
					(justify left bottom)
					(hide yes)
				)
			)
			(property "MPN" "CR0402-FX-2200GLF"
				(at 20.32 -20.32 0)
				(effects
					(font
						(size 1.27 1.27)
						(thickness 0.15)
					)
					(justify left bottom)
					(hide yes)
				)
			)
			(property "Manufacturer" "Bourns"
				(at 20.32 -22.86 0)
				(effects
					(font
						(size 1.27 1.27)
						(thickness 0.15)
					)
					(justify left bottom)
					(hide yes)
				)
			)
			(property "License" "Apache-2.0"
				(at 20.32 -25.4 0)
				(effects
					(font
						(size 1.27 1.27)
						(thickness 0.15)
					)
					(justify left bottom)
					(hide yes)
				)
			)
			(property "Author" "Antmicro"
				(at 20.32 -27.94 0)
				(effects
					(font
						(size 1.27 1.27)
						(thickness 0.15)
					)
					(justify left bottom)
					(hide yes)
				)
			)
			(property "Val" "220R"
				(at 20.32 -7.62 0)
				(effects
					(font
						(size 1.27 1.27)
						(thickness 0.15)
					)
					(justify left bottom)
				)
			)
			(property "Tolerance" "1%"
				(at 20.32 -10.16 0)
				(effects
					(font
						(size 1.27 1.27)
					)
					(justify left bottom)
					(hide yes)
				)
			)
			(property "ki_keywords" "0402, SMT, RESISTOR, PASSIVE"
				(at 0 0 0)
				(effects
					(font
						(size 1.27 1.27)
					)
					(hide yes)
				)
			)
			(symbol "R_220R_0402_0_1"
				(rectangle
					(start 0.635 0.889)
					(end 4.445 -0.889)
					(stroke
						(width 0.254)
						(type default)
					)
					(fill
						(type none)
					)
				)
			)
			(symbol "R_220R_0402_1_1"
				(pin passive line
					(at 0 0 0)
					(length 0.635)
					(name "~"
						(effects
							(font
								(size 1.27 1.27)
							)
						)
					)
					(number "1"
						(effects
							(font
								(size 1.27 1.27)
							)
						)
					)
				)
				(pin passive line
					(at 5.08 0 180)
					(length 0.635)
					(name "~"
						(effects
							(font
								(size 1.27 1.27)
							)
						)
					)
					(number "2"
						(effects
							(font
								(size 1.27 1.27)
							)
						)
					)
				)
			)
		)
	(symbol "antmicroResistors0402:R_22R_0402"
			(pin_numbers
				(hide yes)
			)
			(pin_names
				(hide yes)
			)
			(exclude_from_sim no)
			(in_bom yes)
			(on_board yes)
			(property "Reference" "R"
				(at 20.32 -5.08 0)
				(effects
					(font
						(size 1.27 1.27)
						(thickness 0.15)
					)
					(justify left bottom)
				)
			)
			(property "Value" "R_22R_0402"
				(at 20.32 -12.7 0)
				(effects
					(font
						(size 1.27 1.27)
						(thickness 0.15)
					)
					(justify left bottom)
					(hide yes)
				)
			)
			(property "Footprint" "antmicro-footprints:R_0402_1005Metric"
				(at 20.32 -15.24 0)
				(effects
					(font
						(size 1.27 1.27)
						(thickness 0.15)
					)
					(justify left bottom)
					(hide yes)
				)
			)
			(property "Datasheet" "https://www.bourns.com/docs/product-datasheets/cr.pdf"
				(at 20.32 -17.78 0)
				(effects
					(font
						(size 1.27 1.27)
						(thickness 0.15)
					)
					(justify left bottom)
					(hide yes)
				)
			)
			(property "Description" "SMD Chip Resistor, 22 ohm, ± 1%, 62.5 mW, 0402 [1005 Metric], Thick Film, General Purpose"
				(at 20.32 -30.48 0)
				(effects
					(font
						(size 1.27 1.27)
					)
					(justify left bottom)
					(hide yes)
				)
			)
			(property "MPN" "CR0402-FX-22R0GLF"
				(at 20.32 -20.32 0)
				(effects
					(font
						(size 1.27 1.27)
						(thickness 0.15)
					)
					(justify left bottom)
					(hide yes)
				)
			)
			(property "Manufacturer" "Bourns"
				(at 20.32 -22.86 0)
				(effects
					(font
						(size 1.27 1.27)
						(thickness 0.15)
					)
					(justify left bottom)
					(hide yes)
				)
			)
			(property "License" "Apache-2.0"
				(at 20.32 -25.4 0)
				(effects
					(font
						(size 1.27 1.27)
						(thickness 0.15)
					)
					(justify left bottom)
					(hide yes)
				)
			)
			(property "Author" "Antmicro"
				(at 20.32 -27.94 0)
				(effects
					(font
						(size 1.27 1.27)
						(thickness 0.15)
					)
					(justify left bottom)
					(hide yes)
				)
			)
			(property "Val" "22R"
				(at 20.32 -7.62 0)
				(effects
					(font
						(size 1.27 1.27)
						(thickness 0.15)
					)
					(justify left bottom)
				)
			)
			(property "Tolerance" "1%"
				(at 20.32 -10.16 0)
				(effects
					(font
						(size 1.27 1.27)
					)
					(justify left bottom)
					(hide yes)
				)
			)
			(property "ki_keywords" "0402, SMT, RESISTOR, PASSIVE"
				(at 0 0 0)
				(effects
					(font
						(size 1.27 1.27)
					)
					(hide yes)
				)
			)
			(symbol "R_22R_0402_0_1"
				(rectangle
					(start 0.635 0.889)
					(end 4.445 -0.889)
					(stroke
						(width 0.254)
						(type default)
					)
					(fill
						(type none)
					)
				)
			)
			(symbol "R_22R_0402_1_1"
				(pin passive line
					(at 0 0 0)
					(length 0.635)
					(name "~"
						(effects
							(font
								(size 1.27 1.27)
							)
						)
					)
					(number "1"
						(effects
							(font
								(size 1.27 1.27)
							)
						)
					)
				)
				(pin passive line
					(at 5.08 0 180)
					(length 0.635)
					(name "~"
						(effects
							(font
								(size 1.27 1.27)
							)
						)
					)
					(number "2"
						(effects
							(font
								(size 1.27 1.27)
							)
						)
					)
				)
			)
		)
	(symbol "antmicroResistors0402:R_2k2_0402"
			(pin_numbers
				(hide yes)
			)
			(pin_names
				(hide yes)
			)
			(exclude_from_sim no)
			(in_bom yes)
			(on_board yes)
			(property "Reference" "R"
				(at 20.32 -5.08 0)
				(effects
					(font
						(size 1.27 1.27)
						(thickness 0.15)
					)
					(justify left bottom)
				)
			)
			(property "Value" "R_2k2_0402"
				(at 20.32 -12.7 0)
				(effects
					(font
						(size 1.27 1.27)
						(thickness 0.15)
					)
					(justify left bottom)
					(hide yes)
				)
			)
			(property "Footprint" "antmicro-footprints:R_0402_1005Metric"
				(at 20.32 -15.24 0)
				(effects
					(font
						(size 1.27 1.27)
						(thickness 0.15)
					)
					(justify left bottom)
					(hide yes)
				)
			)
			(property "Datasheet" "https://www.bourns.com/docs/product-datasheets/cr.pdf"
				(at 20.32 -17.78 0)
				(effects
					(font
						(size 1.27 1.27)
						(thickness 0.15)
					)
					(justify left bottom)
					(hide yes)
				)
			)
			(property "Description" "SMD Chip Resistor, 2.2 kohm, ± 1%, 62.5 mW, 0402 [1005 Metric], Thick Film, General Purpose"
				(at 20.32 -30.48 0)
				(effects
					(font
						(size 1.27 1.27)
					)
					(justify left bottom)
					(hide yes)
				)
			)
			(property "MPN" "CR0402-FX-2201GLF"
				(at 20.32 -20.32 0)
				(effects
					(font
						(size 1.27 1.27)
						(thickness 0.15)
					)
					(justify left bottom)
					(hide yes)
				)
			)
			(property "Manufacturer" "Bourns"
				(at 20.32 -22.86 0)
				(effects
					(font
						(size 1.27 1.27)
						(thickness 0.15)
					)
					(justify left bottom)
					(hide yes)
				)
			)
			(property "License" "Apache-2.0"
				(at 20.32 -25.4 0)
				(effects
					(font
						(size 1.27 1.27)
						(thickness 0.15)
					)
					(justify left bottom)
					(hide yes)
				)
			)
			(property "Author" "Antmicro"
				(at 20.32 -27.94 0)
				(effects
					(font
						(size 1.27 1.27)
						(thickness 0.15)
					)
					(justify left bottom)
					(hide yes)
				)
			)
			(property "Val" "2k2"
				(at 20.32 -7.62 0)
				(effects
					(font
						(size 1.27 1.27)
						(thickness 0.15)
					)
					(justify left bottom)
				)
			)
			(property "Tolerance" "1%"
				(at 20.32 -10.16 0)
				(effects
					(font
						(size 1.27 1.27)
					)
					(justify left bottom)
					(hide yes)
				)
			)
			(property "ki_keywords" "0402, SMT, RESISTOR, PASSIVE"
				(at 0 0 0)
				(effects
					(font
						(size 1.27 1.27)
					)
					(hide yes)
				)
			)
			(symbol "R_2k2_0402_0_1"
				(rectangle
					(start 0.635 0.889)
					(end 4.445 -0.889)
					(stroke
						(width 0.254)
						(type default)
					)
					(fill
						(type none)
					)
				)
			)
			(symbol "R_2k2_0402_1_1"
				(pin passive line
					(at 0 0 0)
					(length 0.635)
					(name "~"
						(effects
							(font
								(size 1.27 1.27)
							)
						)
					)
					(number "1"
						(effects
							(font
								(size 1.27 1.27)
							)
						)
					)
				)
				(pin passive line
					(at 5.08 0 180)
					(length 0.635)
					(name "~"
						(effects
							(font
								(size 1.27 1.27)
							)
						)
					)
					(number "2"
						(effects
							(font
								(size 1.27 1.27)
							)
						)
					)
				)
			)
		)
	(symbol "antmicroResistors0402:R_2k_0402"
			(pin_numbers
				(hide yes)
			)
			(pin_names
				(hide yes)
			)
			(exclude_from_sim no)
			(in_bom yes)
			(on_board yes)
			(property "Reference" "R"
				(at 20.32 -5.08 0)
				(effects
					(font
						(size 1.27 1.27)
						(thickness 0.15)
					)
					(justify left bottom)
				)
			)
			(property "Value" "R_2k_0402"
				(at 20.32 -12.7 0)
				(effects
					(font
						(size 1.27 1.27)
						(thickness 0.15)
					)
					(justify left bottom)
					(hide yes)
				)
			)
			(property "Footprint" "antmicro-footprints:R_0402_1005Metric"
				(at 20.32 -15.24 0)
				(effects
					(font
						(size 1.27 1.27)
						(thickness 0.15)
					)
					(justify left bottom)
					(hide yes)
				)
			)
			(property "Datasheet" "https://www.bourns.com/docs/product-datasheets/cr.pdf"
				(at 20.32 -17.78 0)
				(effects
					(font
						(size 1.27 1.27)
						(thickness 0.15)
					)
					(justify left bottom)
					(hide yes)
				)
			)
			(property "Description" "SMD Chip Resistor, 2 kohm, ± 1%, 62.5 mW, 0402 [1005 Metric], Thick Film, General Purpose"
				(at 20.32 -30.48 0)
				(effects
					(font
						(size 1.27 1.27)
					)
					(justify left bottom)
					(hide yes)
				)
			)
			(property "MPN" "CR0402-FX-2001GLF"
				(at 20.32 -20.32 0)
				(effects
					(font
						(size 1.27 1.27)
						(thickness 0.15)
					)
					(justify left bottom)
					(hide yes)
				)
			)
			(property "Manufacturer" "Bourns"
				(at 20.32 -22.86 0)
				(effects
					(font
						(size 1.27 1.27)
						(thickness 0.15)
					)
					(justify left bottom)
					(hide yes)
				)
			)
			(property "License" "Apache-2.0"
				(at 20.32 -25.4 0)
				(effects
					(font
						(size 1.27 1.27)
						(thickness 0.15)
					)
					(justify left bottom)
					(hide yes)
				)
			)
			(property "Author" "Antmicro"
				(at 20.32 -27.94 0)
				(effects
					(font
						(size 1.27 1.27)
						(thickness 0.15)
					)
					(justify left bottom)
					(hide yes)
				)
			)
			(property "Val" "2k"
				(at 20.32 -7.62 0)
				(effects
					(font
						(size 1.27 1.27)
						(thickness 0.15)
					)
					(justify left bottom)
				)
			)
			(property "Tolerance" "1%"
				(at 20.32 -10.16 0)
				(effects
					(font
						(size 1.27 1.27)
					)
					(justify left bottom)
					(hide yes)
				)
			)
			(property "ki_keywords" "0402, SMT, RESISTOR, PASSIVE"
				(at 0 0 0)
				(effects
					(font
						(size 1.27 1.27)
					)
					(hide yes)
				)
			)
			(symbol "R_2k_0402_0_1"
				(rectangle
					(start 0.635 0.889)
					(end 4.445 -0.889)
					(stroke
						(width 0.254)
						(type default)
					)
					(fill
						(type none)
					)
				)
			)
			(symbol "R_2k_0402_1_1"
				(pin passive line
					(at 0 0 0)
					(length 0.635)
					(name "~"
						(effects
							(font
								(size 1.27 1.27)
							)
						)
					)
					(number "1"
						(effects
							(font
								(size 1.27 1.27)
							)
						)
					)
				)
				(pin passive line
					(at 5.08 0 180)
					(length 0.635)
					(name "~"
						(effects
							(font
								(size 1.27 1.27)
							)
						)
					)
					(number "2"
						(effects
							(font
								(size 1.27 1.27)
							)
						)
					)
				)
			)
		)
	(symbol "antmicroResistors0402:R_30k_0402"
			(pin_numbers
				(hide yes)
			)
			(pin_names
				(hide yes)
			)
			(exclude_from_sim no)
			(in_bom yes)
			(on_board yes)
			(property "Reference" "R"
				(at 20.32 -5.08 0)
				(effects
					(font
						(size 1.27 1.27)
						(thickness 0.15)
					)
					(justify left bottom)
				)
			)
			(property "Value" "R_30k_0402"
				(at 20.32 -12.7 0)
				(effects
					(font
						(size 1.27 1.27)
						(thickness 0.15)
					)
					(justify left bottom)
					(hide yes)
				)
			)
			(property "Footprint" "antmicro-footprints:R_0402_1005Metric"
				(at 20.32 -15.24 0)
				(effects
					(font
						(size 1.27 1.27)
						(thickness 0.15)
					)
					(justify left bottom)
					(hide yes)
				)
			)
			(property "Datasheet" "https://www.bourns.com/docs/product-datasheets/cr.pdf"
				(at 20.32 -17.78 0)
				(effects
					(font
						(size 1.27 1.27)
						(thickness 0.15)
					)
					(justify left bottom)
					(hide yes)
				)
			)
			(property "Description" "SMD Chip Resistor, 30 kohm, ± 1%, 63 mW, 0402 [1005 Metric], Thick Film, General Purpose"
				(at 20.32 -30.48 0)
				(effects
					(font
						(size 1.27 1.27)
					)
					(justify left bottom)
					(hide yes)
				)
			)
			(property "MPN" "CR0402-FX-3002GLF"
				(at 20.32 -20.32 0)
				(effects
					(font
						(size 1.27 1.27)
						(thickness 0.15)
					)
					(justify left bottom)
					(hide yes)
				)
			)
			(property "Manufacturer" "Bourns"
				(at 20.32 -22.86 0)
				(effects
					(font
						(size 1.27 1.27)
						(thickness 0.15)
					)
					(justify left bottom)
					(hide yes)
				)
			)
			(property "License" "Apache-2.0"
				(at 20.32 -25.4 0)
				(effects
					(font
						(size 1.27 1.27)
						(thickness 0.15)
					)
					(justify left bottom)
					(hide yes)
				)
			)
			(property "Author" "Antmicro"
				(at 20.32 -27.94 0)
				(effects
					(font
						(size 1.27 1.27)
						(thickness 0.15)
					)
					(justify left bottom)
					(hide yes)
				)
			)
			(property "Val" "30k"
				(at 20.32 -7.62 0)
				(effects
					(font
						(size 1.27 1.27)
						(thickness 0.15)
					)
					(justify left bottom)
				)
			)
			(property "Tolerance" "1%"
				(at 20.32 -10.16 0)
				(effects
					(font
						(size 1.27 1.27)
					)
					(justify left bottom)
					(hide yes)
				)
			)
			(property "ki_keywords" "0402, SMT, RESISTOR, PASSIVE"
				(at 0 0 0)
				(effects
					(font
						(size 1.27 1.27)
					)
					(hide yes)
				)
			)
			(symbol "R_30k_0402_0_1"
				(rectangle
					(start 0.635 0.889)
					(end 4.445 -0.889)
					(stroke
						(width 0.254)
						(type default)
					)
					(fill
						(type none)
					)
				)
			)
			(symbol "R_30k_0402_1_1"
				(pin passive line
					(at 0 0 0)
					(length 0.635)
					(name "~"
						(effects
							(font
								(size 1.27 1.27)
							)
						)
					)
					(number "1"
						(effects
							(font
								(size 1.27 1.27)
							)
						)
					)
				)
				(pin passive line
					(at 5.08 0 180)
					(length 0.635)
					(name "~"
						(effects
							(font
								(size 1.27 1.27)
							)
						)
					)
					(number "2"
						(effects
							(font
								(size 1.27 1.27)
							)
						)
					)
				)
			)
		)
	(symbol "antmicroResistors0402:R_330R_0402"
			(pin_numbers
				(hide yes)
			)
			(pin_names
				(hide yes)
			)
			(exclude_from_sim no)
			(in_bom yes)
			(on_board yes)
			(property "Reference" "R"
				(at 20.32 -5.08 0)
				(effects
					(font
						(size 1.27 1.27)
						(thickness 0.15)
					)
					(justify left bottom)
				)
			)
			(property "Value" "R_330R_0402"
				(at 20.32 -12.7 0)
				(effects
					(font
						(size 1.27 1.27)
						(thickness 0.15)
					)
					(justify left bottom)
					(hide yes)
				)
			)
			(property "Footprint" "antmicro-footprints:R_0402_1005Metric"
				(at 20.32 -15.24 0)
				(effects
					(font
						(size 1.27 1.27)
						(thickness 0.15)
					)
					(justify left bottom)
					(hide yes)
				)
			)
			(property "Datasheet" "https://www.bourns.com/docs/product-datasheets/cr.pdf"
				(at 20.32 -17.78 0)
				(effects
					(font
						(size 1.27 1.27)
						(thickness 0.15)
					)
					(justify left bottom)
					(hide yes)
				)
			)
			(property "Description" "SMD Chip Resistor, 330 ohm, ± 1%, 62.5 mW, 0402 [1005 Metric], Thick Film, General Purpose"
				(at 20.32 -30.48 0)
				(effects
					(font
						(size 1.27 1.27)
					)
					(justify left bottom)
					(hide yes)
				)
			)
			(property "MPN" "CR0402-FX-3300GLF"
				(at 20.32 -20.32 0)
				(effects
					(font
						(size 1.27 1.27)
						(thickness 0.15)
					)
					(justify left bottom)
					(hide yes)
				)
			)
			(property "Manufacturer" "Bourns"
				(at 20.32 -22.86 0)
				(effects
					(font
						(size 1.27 1.27)
						(thickness 0.15)
					)
					(justify left bottom)
					(hide yes)
				)
			)
			(property "License" "Apache-2.0"
				(at 20.32 -25.4 0)
				(effects
					(font
						(size 1.27 1.27)
						(thickness 0.15)
					)
					(justify left bottom)
					(hide yes)
				)
			)
			(property "Author" "Antmicro"
				(at 20.32 -27.94 0)
				(effects
					(font
						(size 1.27 1.27)
						(thickness 0.15)
					)
					(justify left bottom)
					(hide yes)
				)
			)
			(property "Val" "330R"
				(at 20.32 -7.62 0)
				(effects
					(font
						(size 1.27 1.27)
						(thickness 0.15)
					)
					(justify left bottom)
				)
			)
			(property "Tolerance" "1%"
				(at 20.32 -10.16 0)
				(effects
					(font
						(size 1.27 1.27)
					)
					(justify left bottom)
					(hide yes)
				)
			)
			(property "ki_keywords" "0402, SMT, RESISTOR, PASSIVE"
				(at 0 0 0)
				(effects
					(font
						(size 1.27 1.27)
					)
					(hide yes)
				)
			)
			(symbol "R_330R_0402_0_1"
				(rectangle
					(start 0.635 0.889)
					(end 4.445 -0.889)
					(stroke
						(width 0.254)
						(type default)
					)
					(fill
						(type none)
					)
				)
			)
			(symbol "R_330R_0402_1_1"
				(pin passive line
					(at 0 0 0)
					(length 0.635)
					(name "~"
						(effects
							(font
								(size 1.27 1.27)
							)
						)
					)
					(number "1"
						(effects
							(font
								(size 1.27 1.27)
							)
						)
					)
				)
				(pin passive line
					(at 5.08 0 180)
					(length 0.635)
					(name "~"
						(effects
							(font
								(size 1.27 1.27)
							)
						)
					)
					(number "2"
						(effects
							(font
								(size 1.27 1.27)
							)
						)
					)
				)
			)
		)
	(symbol "antmicroResistors0402:R_3k01_0402"
			(pin_numbers
				(hide yes)
			)
			(pin_names
				(hide yes)
			)
			(exclude_from_sim no)
			(in_bom yes)
			(on_board yes)
			(property "Reference" "R"
				(at 20.32 -5.08 0)
				(effects
					(font
						(size 1.27 1.27)
						(thickness 0.15)
					)
					(justify left bottom)
				)
			)
			(property "Value" "R_3k01_0402"
				(at 20.32 -12.7 0)
				(effects
					(font
						(size 1.27 1.27)
						(thickness 0.15)
					)
					(justify left bottom)
					(hide yes)
				)
			)
			(property "Footprint" "antmicro-footprints:R_0402_1005Metric"
				(at 20.32 -15.24 0)
				(effects
					(font
						(size 1.27 1.27)
						(thickness 0.15)
					)
					(justify left bottom)
					(hide yes)
				)
			)
			(property "Datasheet" "https://www.bourns.com/docs/product-datasheets/cr.pdf"
				(at 20.32 -17.78 0)
				(effects
					(font
						(size 1.27 1.27)
						(thickness 0.15)
					)
					(justify left bottom)
					(hide yes)
				)
			)
			(property "Description" "SMD Chip Resistor, 3.01 kohm, ± 1%, 62.5 mW, 0402 [1005 Metric], Thick Film, General Purpose"
				(at 20.32 -30.48 0)
				(effects
					(font
						(size 1.27 1.27)
					)
					(justify left bottom)
					(hide yes)
				)
			)
			(property "MPN" "CR0402-FX-3011GLF"
				(at 20.32 -20.32 0)
				(effects
					(font
						(size 1.27 1.27)
						(thickness 0.15)
					)
					(justify left bottom)
					(hide yes)
				)
			)
			(property "Manufacturer" "Bourns"
				(at 20.32 -22.86 0)
				(effects
					(font
						(size 1.27 1.27)
						(thickness 0.15)
					)
					(justify left bottom)
					(hide yes)
				)
			)
			(property "License" "Apache-2.0"
				(at 20.32 -25.4 0)
				(effects
					(font
						(size 1.27 1.27)
						(thickness 0.15)
					)
					(justify left bottom)
					(hide yes)
				)
			)
			(property "Author" "Antmicro"
				(at 20.32 -27.94 0)
				(effects
					(font
						(size 1.27 1.27)
						(thickness 0.15)
					)
					(justify left bottom)
					(hide yes)
				)
			)
			(property "Val" "3k01"
				(at 20.32 -7.62 0)
				(effects
					(font
						(size 1.27 1.27)
						(thickness 0.15)
					)
					(justify left bottom)
				)
			)
			(property "Tolerance" "1%"
				(at 20.32 -10.16 0)
				(effects
					(font
						(size 1.27 1.27)
					)
					(justify left bottom)
					(hide yes)
				)
			)
			(property "ki_keywords" "0402, SMT, RESISTOR, PASSIVE"
				(at 0 0 0)
				(effects
					(font
						(size 1.27 1.27)
					)
					(hide yes)
				)
			)
			(symbol "R_3k01_0402_0_1"
				(rectangle
					(start 0.635 0.889)
					(end 4.445 -0.889)
					(stroke
						(width 0.254)
						(type default)
					)
					(fill
						(type none)
					)
				)
			)
			(symbol "R_3k01_0402_1_1"
				(pin passive line
					(at 0 0 0)
					(length 0.635)
					(name "~"
						(effects
							(font
								(size 1.27 1.27)
							)
						)
					)
					(number "1"
						(effects
							(font
								(size 1.27 1.27)
							)
						)
					)
				)
				(pin passive line
					(at 5.08 0 180)
					(length 0.635)
					(name "~"
						(effects
							(font
								(size 1.27 1.27)
							)
						)
					)
					(number "2"
						(effects
							(font
								(size 1.27 1.27)
							)
						)
					)
				)
			)
		)
	(symbol "antmicroResistors0402:R_3k24_0402"
			(pin_numbers
				(hide yes)
			)
			(pin_names
				(hide yes)
			)
			(exclude_from_sim no)
			(in_bom yes)
			(on_board yes)
			(property "Reference" "R"
				(at 20.32 -5.08 0)
				(effects
					(font
						(size 1.27 1.27)
						(thickness 0.15)
					)
					(justify left bottom)
				)
			)
			(property "Value" "R_3k24_0402"
				(at 20.32 -12.7 0)
				(effects
					(font
						(size 1.27 1.27)
						(thickness 0.15)
					)
					(justify left bottom)
					(hide yes)
				)
			)
			(property "Footprint" "antmicro-footprints:R_0402_1005Metric"
				(at 20.32 -15.24 0)
				(effects
					(font
						(size 1.27 1.27)
						(thickness 0.15)
					)
					(justify left bottom)
					(hide yes)
				)
			)
			(property "Datasheet" "https://www.farnell.com/datasheets/3795017.pdf"
				(at 20.32 -17.78 0)
				(effects
					(font
						(size 1.27 1.27)
						(thickness 0.15)
					)
					(justify left bottom)
					(hide yes)
				)
			)
			(property "Description" "SMD Chip Resistor, 3.24 kohm, ± 1%, 62.5 mW, 0402 [1005 Metric], Thick Film, General Purpose"
				(at 20.32 -30.48 0)
				(effects
					(font
						(size 1.27 1.27)
					)
					(justify left bottom)
					(hide yes)
				)
			)
			(property "MPN" "RMCF0402FT3K24"
				(at 20.32 -20.32 0)
				(effects
					(font
						(size 1.27 1.27)
						(thickness 0.15)
					)
					(justify left bottom)
					(hide yes)
				)
			)
			(property "Manufacturer" "Stackpole Electronics"
				(at 20.32 -22.86 0)
				(effects
					(font
						(size 1.27 1.27)
						(thickness 0.15)
					)
					(justify left bottom)
					(hide yes)
				)
			)
			(property "License" "Apache-2.0"
				(at 20.32 -25.4 0)
				(effects
					(font
						(size 1.27 1.27)
						(thickness 0.15)
					)
					(justify left bottom)
					(hide yes)
				)
			)
			(property "Author" "Antmicro"
				(at 20.32 -27.94 0)
				(effects
					(font
						(size 1.27 1.27)
						(thickness 0.15)
					)
					(justify left bottom)
					(hide yes)
				)
			)
			(property "Val" "3k24"
				(at 20.32 -7.62 0)
				(effects
					(font
						(size 1.27 1.27)
						(thickness 0.15)
					)
					(justify left bottom)
				)
			)
			(property "Tolerance" "1%"
				(at 20.32 -10.16 0)
				(effects
					(font
						(size 1.27 1.27)
					)
					(justify left bottom)
					(hide yes)
				)
			)
			(property "ki_keywords" "0402, SMT, RESISTOR, PASSIVE"
				(at 0 0 0)
				(effects
					(font
						(size 1.27 1.27)
					)
					(hide yes)
				)
			)
			(symbol "R_3k24_0402_0_1"
				(rectangle
					(start 0.635 0.889)
					(end 4.445 -0.889)
					(stroke
						(width 0.254)
						(type default)
					)
					(fill
						(type none)
					)
				)
			)
			(symbol "R_3k24_0402_1_1"
				(pin passive line
					(at 0 0 0)
					(length 0.635)
					(name "~"
						(effects
							(font
								(size 1.27 1.27)
							)
						)
					)
					(number "1"
						(effects
							(font
								(size 1.27 1.27)
							)
						)
					)
				)
				(pin passive line
					(at 5.08 0 180)
					(length 0.635)
					(name "~"
						(effects
							(font
								(size 1.27 1.27)
							)
						)
					)
					(number "2"
						(effects
							(font
								(size 1.27 1.27)
							)
						)
					)
				)
			)
		)
	(symbol "antmicroResistors0402:R_3k3_0402"
			(pin_numbers
				(hide yes)
			)
			(pin_names
				(hide yes)
			)
			(exclude_from_sim no)
			(in_bom yes)
			(on_board yes)
			(property "Reference" "R"
				(at 20.32 -5.08 0)
				(effects
					(font
						(size 1.27 1.27)
						(thickness 0.15)
					)
					(justify left bottom)
				)
			)
			(property "Value" "R_3k3_0402"
				(at 20.32 -12.7 0)
				(effects
					(font
						(size 1.27 1.27)
						(thickness 0.15)
					)
					(justify left bottom)
					(hide yes)
				)
			)
			(property "Footprint" "antmicro-footprints:R_0402_1005Metric"
				(at 20.32 -15.24 0)
				(effects
					(font
						(size 1.27 1.27)
						(thickness 0.15)
					)
					(justify left bottom)
					(hide yes)
				)
			)
			(property "Datasheet" "https://www.bourns.com/docs/product-datasheets/cr.pdf"
				(at 20.32 -17.78 0)
				(effects
					(font
						(size 1.27 1.27)
						(thickness 0.15)
					)
					(justify left bottom)
					(hide yes)
				)
			)
			(property "Description" "SMD Chip Resistor, 3.3 kohm, ± 1%, 63 mW, 0402 [1005 Metric], Thick Film, General Purpose"
				(at 20.32 -30.48 0)
				(effects
					(font
						(size 1.27 1.27)
					)
					(justify left bottom)
					(hide yes)
				)
			)
			(property "MPN" "CR0402-FX-3301GLF"
				(at 20.32 -20.32 0)
				(effects
					(font
						(size 1.27 1.27)
						(thickness 0.15)
					)
					(justify left bottom)
					(hide yes)
				)
			)
			(property "Manufacturer" "Bourns"
				(at 20.32 -22.86 0)
				(effects
					(font
						(size 1.27 1.27)
						(thickness 0.15)
					)
					(justify left bottom)
					(hide yes)
				)
			)
			(property "License" "Apache-2.0"
				(at 20.32 -25.4 0)
				(effects
					(font
						(size 1.27 1.27)
						(thickness 0.15)
					)
					(justify left bottom)
					(hide yes)
				)
			)
			(property "Author" "Antmicro"
				(at 20.32 -27.94 0)
				(effects
					(font
						(size 1.27 1.27)
						(thickness 0.15)
					)
					(justify left bottom)
					(hide yes)
				)
			)
			(property "Val" "3k3"
				(at 20.32 -7.62 0)
				(effects
					(font
						(size 1.27 1.27)
						(thickness 0.15)
					)
					(justify left bottom)
				)
			)
			(property "Tolerance" "1%"
				(at 20.32 -10.16 0)
				(effects
					(font
						(size 1.27 1.27)
					)
					(justify left bottom)
					(hide yes)
				)
			)
			(property "ki_keywords" "0402, SMT, RESISTOR, PASSIVE"
				(at 0 0 0)
				(effects
					(font
						(size 1.27 1.27)
					)
					(hide yes)
				)
			)
			(symbol "R_3k3_0402_0_1"
				(rectangle
					(start 0.635 0.889)
					(end 4.445 -0.889)
					(stroke
						(width 0.254)
						(type default)
					)
					(fill
						(type none)
					)
				)
			)
			(symbol "R_3k3_0402_1_1"
				(pin passive line
					(at 0 0 0)
					(length 0.635)
					(name "~"
						(effects
							(font
								(size 1.27 1.27)
							)
						)
					)
					(number "1"
						(effects
							(font
								(size 1.27 1.27)
							)
						)
					)
				)
				(pin passive line
					(at 5.08 0 180)
					(length 0.635)
					(name "~"
						(effects
							(font
								(size 1.27 1.27)
							)
						)
					)
					(number "2"
						(effects
							(font
								(size 1.27 1.27)
							)
						)
					)
				)
			)
		)
	(symbol "antmicroResistors0402:R_40k2_0402"
			(pin_numbers
				(hide yes)
			)
			(pin_names
				(hide yes)
			)
			(exclude_from_sim no)
			(in_bom yes)
			(on_board yes)
			(property "Reference" "R"
				(at 20.32 -5.08 0)
				(effects
					(font
						(size 1.27 1.27)
						(thickness 0.15)
					)
					(justify left bottom)
				)
			)
			(property "Value" "R_40k2_0402"
				(at 20.32 -12.7 0)
				(effects
					(font
						(size 1.27 1.27)
						(thickness 0.15)
					)
					(justify left bottom)
					(hide yes)
				)
			)
			(property "Footprint" "antmicro-footprints:R_0402_1005Metric"
				(at 20.32 -15.24 0)
				(effects
					(font
						(size 1.27 1.27)
						(thickness 0.15)
					)
					(justify left bottom)
					(hide yes)
				)
			)
			(property "Datasheet" "https://www.bourns.com/docs/product-datasheets/cr.pdf"
				(at 20.32 -17.78 0)
				(effects
					(font
						(size 1.27 1.27)
						(thickness 0.15)
					)
					(justify left bottom)
					(hide yes)
				)
			)
			(property "Description" "SMD Chip Resistor, 40.2 kohm, ± 1%, 63 mW, 0402 [1005 Metric], Thick Film, General Purpose"
				(at 20.32 -30.48 0)
				(effects
					(font
						(size 1.27 1.27)
					)
					(justify left bottom)
					(hide yes)
				)
			)
			(property "MPN" "CR0402-FX-4022GLF"
				(at 20.32 -20.32 0)
				(effects
					(font
						(size 1.27 1.27)
						(thickness 0.15)
					)
					(justify left bottom)
					(hide yes)
				)
			)
			(property "Manufacturer" "Bourns"
				(at 20.32 -22.86 0)
				(effects
					(font
						(size 1.27 1.27)
						(thickness 0.15)
					)
					(justify left bottom)
					(hide yes)
				)
			)
			(property "License" "Apache-2.0"
				(at 20.32 -25.4 0)
				(effects
					(font
						(size 1.27 1.27)
						(thickness 0.15)
					)
					(justify left bottom)
					(hide yes)
				)
			)
			(property "Author" "Antmicro"
				(at 20.32 -27.94 0)
				(effects
					(font
						(size 1.27 1.27)
						(thickness 0.15)
					)
					(justify left bottom)
					(hide yes)
				)
			)
			(property "Val" "40k2"
				(at 20.32 -7.62 0)
				(effects
					(font
						(size 1.27 1.27)
						(thickness 0.15)
					)
					(justify left bottom)
				)
			)
			(property "Tolerance" "1%"
				(at 20.32 -10.16 0)
				(effects
					(font
						(size 1.27 1.27)
					)
					(justify left bottom)
					(hide yes)
				)
			)
			(property "ki_keywords" "0402, SMT, RESISTOR, PASSIVE"
				(at 0 0 0)
				(effects
					(font
						(size 1.27 1.27)
					)
					(hide yes)
				)
			)
			(symbol "R_40k2_0402_0_1"
				(rectangle
					(start 0.635 0.889)
					(end 4.445 -0.889)
					(stroke
						(width 0.254)
						(type default)
					)
					(fill
						(type none)
					)
				)
			)
			(symbol "R_40k2_0402_1_1"
				(pin passive line
					(at 0 0 0)
					(length 0.635)
					(name "~"
						(effects
							(font
								(size 1.27 1.27)
							)
						)
					)
					(number "1"
						(effects
							(font
								(size 1.27 1.27)
							)
						)
					)
				)
				(pin passive line
					(at 5.08 0 180)
					(length 0.635)
					(name "~"
						(effects
							(font
								(size 1.27 1.27)
							)
						)
					)
					(number "2"
						(effects
							(font
								(size 1.27 1.27)
							)
						)
					)
				)
			)
		)
	(symbol "antmicroResistors0402:R_470R_0402"
			(pin_numbers
				(hide yes)
			)
			(pin_names
				(hide yes)
			)
			(exclude_from_sim no)
			(in_bom yes)
			(on_board yes)
			(property "Reference" "R"
				(at 20.32 -5.08 0)
				(effects
					(font
						(size 1.27 1.27)
						(thickness 0.15)
					)
					(justify left bottom)
				)
			)
			(property "Value" "R_470R_0402"
				(at 20.32 -12.7 0)
				(effects
					(font
						(size 1.27 1.27)
						(thickness 0.15)
					)
					(justify left bottom)
					(hide yes)
				)
			)
			(property "Footprint" "antmicro-footprints:R_0402_1005Metric"
				(at 20.32 -15.24 0)
				(effects
					(font
						(size 1.27 1.27)
						(thickness 0.15)
					)
					(justify left bottom)
					(hide yes)
				)
			)
			(property "Datasheet" "https://www.bourns.com/docs/product-datasheets/cr.pdf"
				(at 20.32 -17.78 0)
				(effects
					(font
						(size 1.27 1.27)
						(thickness 0.15)
					)
					(justify left bottom)
					(hide yes)
				)
			)
			(property "Description" "SMD Chip Resistor, 470 ohm, ± 1%, 62.5 mW, 0402 [1005 Metric], Thick Film, General Purpose"
				(at 20.32 -30.48 0)
				(effects
					(font
						(size 1.27 1.27)
					)
					(justify left bottom)
					(hide yes)
				)
			)
			(property "MPN" "CR0402-FX-4700GLF"
				(at 20.32 -20.32 0)
				(effects
					(font
						(size 1.27 1.27)
						(thickness 0.15)
					)
					(justify left bottom)
					(hide yes)
				)
			)
			(property "Manufacturer" "Bourns"
				(at 20.32 -22.86 0)
				(effects
					(font
						(size 1.27 1.27)
						(thickness 0.15)
					)
					(justify left bottom)
					(hide yes)
				)
			)
			(property "License" "Apache-2.0"
				(at 20.32 -25.4 0)
				(effects
					(font
						(size 1.27 1.27)
						(thickness 0.15)
					)
					(justify left bottom)
					(hide yes)
				)
			)
			(property "Author" "Antmicro"
				(at 20.32 -27.94 0)
				(effects
					(font
						(size 1.27 1.27)
						(thickness 0.15)
					)
					(justify left bottom)
					(hide yes)
				)
			)
			(property "Val" "470R"
				(at 20.32 -7.62 0)
				(effects
					(font
						(size 1.27 1.27)
						(thickness 0.15)
					)
					(justify left bottom)
				)
			)
			(property "Tolerance" "1%"
				(at 20.32 -10.16 0)
				(effects
					(font
						(size 1.27 1.27)
					)
					(justify left bottom)
					(hide yes)
				)
			)
			(property "ki_keywords" "0402, SMT, RESISTOR, PASSIVE"
				(at 0 0 0)
				(effects
					(font
						(size 1.27 1.27)
					)
					(hide yes)
				)
			)
			(symbol "R_470R_0402_0_1"
				(rectangle
					(start 0.635 0.889)
					(end 4.445 -0.889)
					(stroke
						(width 0.254)
						(type default)
					)
					(fill
						(type none)
					)
				)
			)
			(symbol "R_470R_0402_1_1"
				(pin passive line
					(at 0 0 0)
					(length 0.635)
					(name "~"
						(effects
							(font
								(size 1.27 1.27)
							)
						)
					)
					(number "1"
						(effects
							(font
								(size 1.27 1.27)
							)
						)
					)
				)
				(pin passive line
					(at 5.08 0 180)
					(length 0.635)
					(name "~"
						(effects
							(font
								(size 1.27 1.27)
							)
						)
					)
					(number "2"
						(effects
							(font
								(size 1.27 1.27)
							)
						)
					)
				)
			)
		)
	(symbol "antmicroResistors0402:R_47k_0402"
			(pin_numbers
				(hide yes)
			)
			(pin_names
				(hide yes)
			)
			(exclude_from_sim no)
			(in_bom yes)
			(on_board yes)
			(property "Reference" "R"
				(at 20.32 -5.08 0)
				(effects
					(font
						(size 1.27 1.27)
						(thickness 0.15)
					)
					(justify left bottom)
				)
			)
			(property "Value" "R_47k_0402"
				(at 20.32 -12.7 0)
				(effects
					(font
						(size 1.27 1.27)
						(thickness 0.15)
					)
					(justify left bottom)
					(hide yes)
				)
			)
			(property "Footprint" "antmicro-footprints:R_0402_1005Metric"
				(at 20.32 -15.24 0)
				(effects
					(font
						(size 1.27 1.27)
						(thickness 0.15)
					)
					(justify left bottom)
					(hide yes)
				)
			)
			(property "Datasheet" "https://www.bourns.com/docs/product-datasheets/cr.pdf"
				(at 20.32 -17.78 0)
				(effects
					(font
						(size 1.27 1.27)
						(thickness 0.15)
					)
					(justify left bottom)
					(hide yes)
				)
			)
			(property "Description" "SMD Chip Resistor, 47 kohm, ± 1%, 62.5 mW, 0402 [1005 Metric], Thick Film, General Purpose"
				(at 20.32 -30.48 0)
				(effects
					(font
						(size 1.27 1.27)
					)
					(justify left bottom)
					(hide yes)
				)
			)
			(property "MPN" "CR0402-FX-4702GLF"
				(at 20.32 -20.32 0)
				(effects
					(font
						(size 1.27 1.27)
						(thickness 0.15)
					)
					(justify left bottom)
					(hide yes)
				)
			)
			(property "Manufacturer" "Bourns"
				(at 20.32 -22.86 0)
				(effects
					(font
						(size 1.27 1.27)
						(thickness 0.15)
					)
					(justify left bottom)
					(hide yes)
				)
			)
			(property "License" "Apache-2.0"
				(at 20.32 -25.4 0)
				(effects
					(font
						(size 1.27 1.27)
						(thickness 0.15)
					)
					(justify left bottom)
					(hide yes)
				)
			)
			(property "Author" "Antmicro"
				(at 20.32 -27.94 0)
				(effects
					(font
						(size 1.27 1.27)
						(thickness 0.15)
					)
					(justify left bottom)
					(hide yes)
				)
			)
			(property "Val" "47k"
				(at 20.32 -7.62 0)
				(effects
					(font
						(size 1.27 1.27)
						(thickness 0.15)
					)
					(justify left bottom)
				)
			)
			(property "Tolerance" "1%"
				(at 20.32 -10.16 0)
				(effects
					(font
						(size 1.27 1.27)
					)
					(justify left bottom)
					(hide yes)
				)
			)
			(property "ki_keywords" "0402, SMT, RESISTOR, PASSIVE"
				(at 0 0 0)
				(effects
					(font
						(size 1.27 1.27)
					)
					(hide yes)
				)
			)
			(symbol "R_47k_0402_0_1"
				(rectangle
					(start 0.635 0.889)
					(end 4.445 -0.889)
					(stroke
						(width 0.254)
						(type default)
					)
					(fill
						(type none)
					)
				)
			)
			(symbol "R_47k_0402_1_1"
				(pin passive line
					(at 0 0 0)
					(length 0.635)
					(name "~"
						(effects
							(font
								(size 1.27 1.27)
							)
						)
					)
					(number "1"
						(effects
							(font
								(size 1.27 1.27)
							)
						)
					)
				)
				(pin passive line
					(at 5.08 0 180)
					(length 0.635)
					(name "~"
						(effects
							(font
								(size 1.27 1.27)
							)
						)
					)
					(number "2"
						(effects
							(font
								(size 1.27 1.27)
							)
						)
					)
				)
			)
		)
	(symbol "antmicroResistors0402:R_499R_0402"
			(pin_numbers
				(hide yes)
			)
			(pin_names
				(hide yes)
			)
			(exclude_from_sim no)
			(in_bom yes)
			(on_board yes)
			(property "Reference" "R"
				(at 20.32 -5.08 0)
				(effects
					(font
						(size 1.27 1.27)
						(thickness 0.15)
					)
					(justify left bottom)
				)
			)
			(property "Value" "R_499R_0402"
				(at 20.32 -12.7 0)
				(effects
					(font
						(size 1.27 1.27)
						(thickness 0.15)
					)
					(justify left bottom)
					(hide yes)
				)
			)
			(property "Footprint" "antmicro-footprints:R_0402_1005Metric"
				(at 20.32 -15.24 0)
				(effects
					(font
						(size 1.27 1.27)
						(thickness 0.15)
					)
					(justify left bottom)
					(hide yes)
				)
			)
			(property "Datasheet" "https://www.mouser.com/datasheet/2/54/cr-1858361.pdf"
				(at 20.32 -17.78 0)
				(effects
					(font
						(size 1.27 1.27)
						(thickness 0.15)
					)
					(justify left bottom)
					(hide yes)
				)
			)
			(property "Description" "SMD Chip Resistor, 499 ohm, ± 1%, 63 mW, 0402 [1005 Metric], Thick Film, General Purpose"
				(at 20.32 -30.48 0)
				(effects
					(font
						(size 1.27 1.27)
					)
					(justify left bottom)
					(hide yes)
				)
			)
			(property "MPN" "CR0402-FX-4990GLF"
				(at 20.32 -20.32 0)
				(effects
					(font
						(size 1.27 1.27)
						(thickness 0.15)
					)
					(justify left bottom)
					(hide yes)
				)
			)
			(property "Manufacturer" "Bourns"
				(at 20.32 -22.86 0)
				(effects
					(font
						(size 1.27 1.27)
						(thickness 0.15)
					)
					(justify left bottom)
					(hide yes)
				)
			)
			(property "License" "Apache-2.0"
				(at 20.32 -25.4 0)
				(effects
					(font
						(size 1.27 1.27)
						(thickness 0.15)
					)
					(justify left bottom)
					(hide yes)
				)
			)
			(property "Author" "Antmicro"
				(at 20.32 -27.94 0)
				(effects
					(font
						(size 1.27 1.27)
						(thickness 0.15)
					)
					(justify left bottom)
					(hide yes)
				)
			)
			(property "Val" "499R"
				(at 20.32 -7.62 0)
				(effects
					(font
						(size 1.27 1.27)
						(thickness 0.15)
					)
					(justify left bottom)
				)
			)
			(property "Tolerance" "1%"
				(at 20.32 -10.16 0)
				(effects
					(font
						(size 1.27 1.27)
					)
					(justify left bottom)
					(hide yes)
				)
			)
			(property "ki_keywords" "0402, SMT, RESISTOR, PASSIVE"
				(at 0 0 0)
				(effects
					(font
						(size 1.27 1.27)
					)
					(hide yes)
				)
			)
			(symbol "R_499R_0402_0_1"
				(rectangle
					(start 0.635 0.889)
					(end 4.445 -0.889)
					(stroke
						(width 0.254)
						(type default)
					)
					(fill
						(type none)
					)
				)
			)
			(symbol "R_499R_0402_1_1"
				(pin passive line
					(at 0 0 0)
					(length 0.635)
					(name "~"
						(effects
							(font
								(size 1.27 1.27)
							)
						)
					)
					(number "1"
						(effects
							(font
								(size 1.27 1.27)
							)
						)
					)
				)
				(pin passive line
					(at 5.08 0 180)
					(length 0.635)
					(name "~"
						(effects
							(font
								(size 1.27 1.27)
							)
						)
					)
					(number "2"
						(effects
							(font
								(size 1.27 1.27)
							)
						)
					)
				)
			)
		)
	(symbol "antmicroResistors0402:R_499k_0402"
			(pin_numbers
				(hide yes)
			)
			(pin_names
				(hide yes)
			)
			(exclude_from_sim no)
			(in_bom yes)
			(on_board yes)
			(property "Reference" "R"
				(at 20.32 -5.08 0)
				(effects
					(font
						(size 1.27 1.27)
						(thickness 0.15)
					)
					(justify left bottom)
				)
			)
			(property "Value" "R_499k_0402"
				(at 20.32 -12.7 0)
				(effects
					(font
						(size 1.27 1.27)
						(thickness 0.15)
					)
					(justify left bottom)
					(hide yes)
				)
			)
			(property "Footprint" "antmicro-footprints:R_0402_1005Metric"
				(at 20.32 -15.24 0)
				(effects
					(font
						(size 1.27 1.27)
						(thickness 0.15)
					)
					(justify left bottom)
					(hide yes)
				)
			)
			(property "Datasheet" "https://www.mouser.com/datasheet/2/54/cr-1858361.pdf"
				(at 20.32 -17.78 0)
				(effects
					(font
						(size 1.27 1.27)
						(thickness 0.15)
					)
					(justify left bottom)
					(hide yes)
				)
			)
			(property "Description" "SMD Chip Resistor, 499 kohm, ± 1%, 63 mW, 0402 [1005 Metric], Thick Film, General Purpose"
				(at 20.32 -30.48 0)
				(effects
					(font
						(size 1.27 1.27)
					)
					(justify left bottom)
					(hide yes)
				)
			)
			(property "MPN" "CR0402-FX-4993GLF"
				(at 20.32 -20.32 0)
				(effects
					(font
						(size 1.27 1.27)
						(thickness 0.15)
					)
					(justify left bottom)
					(hide yes)
				)
			)
			(property "Manufacturer" "Bourns"
				(at 20.32 -22.86 0)
				(effects
					(font
						(size 1.27 1.27)
						(thickness 0.15)
					)
					(justify left bottom)
					(hide yes)
				)
			)
			(property "License" "Apache-2.0"
				(at 20.32 -25.4 0)
				(effects
					(font
						(size 1.27 1.27)
						(thickness 0.15)
					)
					(justify left bottom)
					(hide yes)
				)
			)
			(property "Author" "Antmicro"
				(at 20.32 -27.94 0)
				(effects
					(font
						(size 1.27 1.27)
						(thickness 0.15)
					)
					(justify left bottom)
					(hide yes)
				)
			)
			(property "Val" "499k"
				(at 20.32 -7.62 0)
				(effects
					(font
						(size 1.27 1.27)
						(thickness 0.15)
					)
					(justify left bottom)
				)
			)
			(property "Tolerance" "1%"
				(at 20.32 -10.16 0)
				(effects
					(font
						(size 1.27 1.27)
					)
					(justify left bottom)
					(hide yes)
				)
			)
			(property "ki_keywords" "0402, SMT, RESISTOR, PASSIVE"
				(at 0 0 0)
				(effects
					(font
						(size 1.27 1.27)
					)
					(hide yes)
				)
			)
			(symbol "R_499k_0402_0_1"
				(rectangle
					(start 0.635 0.889)
					(end 4.445 -0.889)
					(stroke
						(width 0.254)
						(type default)
					)
					(fill
						(type none)
					)
				)
			)
			(symbol "R_499k_0402_1_1"
				(pin passive line
					(at 0 0 0)
					(length 0.635)
					(name "~"
						(effects
							(font
								(size 1.27 1.27)
							)
						)
					)
					(number "1"
						(effects
							(font
								(size 1.27 1.27)
							)
						)
					)
				)
				(pin passive line
					(at 5.08 0 180)
					(length 0.635)
					(name "~"
						(effects
							(font
								(size 1.27 1.27)
							)
						)
					)
					(number "2"
						(effects
							(font
								(size 1.27 1.27)
							)
						)
					)
				)
			)
		)
	(symbol "antmicroResistors0402:R_4k53_0402"
			(pin_numbers
				(hide yes)
			)
			(pin_names
				(hide yes)
			)
			(exclude_from_sim no)
			(in_bom yes)
			(on_board yes)
			(property "Reference" "R"
				(at 20.32 -5.08 0)
				(effects
					(font
						(size 1.27 1.27)
						(thickness 0.15)
					)
					(justify left bottom)
				)
			)
			(property "Value" "R_4k53_0402"
				(at 20.32 -12.7 0)
				(effects
					(font
						(size 1.27 1.27)
						(thickness 0.15)
					)
					(justify left bottom)
					(hide yes)
				)
			)
			(property "Footprint" "antmicro-footprints:R_0402_1005Metric"
				(at 20.32 -15.24 0)
				(effects
					(font
						(size 1.27 1.27)
						(thickness 0.15)
					)
					(justify left bottom)
					(hide yes)
				)
			)
			(property "Datasheet" "https://industrial.panasonic.com/cdbs/www-data/pdf/RDM0000/AOA0000C307.pdf"
				(at 20.32 -17.78 0)
				(effects
					(font
						(size 1.27 1.27)
						(thickness 0.15)
					)
					(justify left bottom)
					(hide yes)
				)
			)
			(property "Description" "SMD Chip Resistor, 4.53 kohm, ± 0.1%, 62.5 mW, 0402 [1005 Metric], Automotive AEC-Q200 Thin Film"
				(at 20.32 -30.48 0)
				(effects
					(font
						(size 1.27 1.27)
					)
					(justify left bottom)
					(hide yes)
				)
			)
			(property "MPN" "ERA-2AEB4531X"
				(at 20.32 -20.32 0)
				(effects
					(font
						(size 1.27 1.27)
						(thickness 0.15)
					)
					(justify left bottom)
					(hide yes)
				)
			)
			(property "Manufacturer" "Panasonic"
				(at 20.32 -22.86 0)
				(effects
					(font
						(size 1.27 1.27)
						(thickness 0.15)
					)
					(justify left bottom)
					(hide yes)
				)
			)
			(property "License" "Apache-2.0"
				(at 20.32 -25.4 0)
				(effects
					(font
						(size 1.27 1.27)
						(thickness 0.15)
					)
					(justify left bottom)
					(hide yes)
				)
			)
			(property "Author" "Antmicro"
				(at 20.32 -27.94 0)
				(effects
					(font
						(size 1.27 1.27)
						(thickness 0.15)
					)
					(justify left bottom)
					(hide yes)
				)
			)
			(property "Val" "4k53"
				(at 20.32 -7.62 0)
				(effects
					(font
						(size 1.27 1.27)
						(thickness 0.15)
					)
					(justify left bottom)
				)
			)
			(property "Tolerance" "0.1%"
				(at 20.32 -10.16 0)
				(effects
					(font
						(size 1.27 1.27)
					)
					(justify left bottom)
				)
			)
			(property "ki_keywords" "0402, SMT, RESISTOR, PASSIVE"
				(at 0 0 0)
				(effects
					(font
						(size 1.27 1.27)
					)
					(hide yes)
				)
			)
			(symbol "R_4k53_0402_0_1"
				(rectangle
					(start 0.635 0.889)
					(end 4.445 -0.889)
					(stroke
						(width 0.254)
						(type default)
					)
					(fill
						(type none)
					)
				)
			)
			(symbol "R_4k53_0402_1_1"
				(pin passive line
					(at 0 0 0)
					(length 0.635)
					(name "~"
						(effects
							(font
								(size 1.27 1.27)
							)
						)
					)
					(number "1"
						(effects
							(font
								(size 1.27 1.27)
							)
						)
					)
				)
				(pin passive line
					(at 5.08 0 180)
					(length 0.635)
					(name "~"
						(effects
							(font
								(size 1.27 1.27)
							)
						)
					)
					(number "2"
						(effects
							(font
								(size 1.27 1.27)
							)
						)
					)
				)
			)
		)
	(symbol "antmicroResistors0402:R_4k75_0.5%_0402"
			(pin_numbers
				(hide yes)
			)
			(pin_names
				(hide yes)
			)
			(exclude_from_sim no)
			(in_bom yes)
			(on_board yes)
			(property "Reference" "R"
				(at 20.32 -5.08 0)
				(effects
					(font
						(size 1.27 1.27)
						(thickness 0.15)
					)
					(justify left bottom)
				)
			)
			(property "Value" "R_4k75_0.5%_0402"
				(at 20.32 -12.7 0)
				(effects
					(font
						(size 1.27 1.27)
						(thickness 0.15)
					)
					(justify left bottom)
					(hide yes)
				)
			)
			(property "Footprint" "antmicro-footprints:R_0402_1005Metric"
				(at 20.32 -15.24 0)
				(effects
					(font
						(size 1.27 1.27)
						(thickness 0.15)
					)
					(justify left bottom)
					(hide yes)
				)
			)
			(property "Datasheet" "https://industrial.panasonic.com/cdbs/www-data/pdf/RDQ0000/ast-ind-151033.pdf"
				(at 20.32 -17.78 0)
				(effects
					(font
						(size 1.27 1.27)
						(thickness 0.15)
					)
					(justify left bottom)
					(hide yes)
				)
			)
			(property "Description" "SMD Chip Resistor, 4.75 kohm, ± 0.5%, 100 mW, 0402 [1005 Metric], Thick Film, High Temperature"
				(at 20.32 -30.48 0)
				(effects
					(font
						(size 1.27 1.27)
					)
					(justify left bottom)
					(hide yes)
				)
			)
			(property "MPN" "ERJ-H2RD4751X"
				(at 20.32 -20.32 0)
				(effects
					(font
						(size 1.27 1.27)
						(thickness 0.15)
					)
					(justify left bottom)
					(hide yes)
				)
			)
			(property "Manufacturer" "Panasonic"
				(at 20.32 -22.86 0)
				(effects
					(font
						(size 1.27 1.27)
						(thickness 0.15)
					)
					(justify left bottom)
					(hide yes)
				)
			)
			(property "License" "Apache-2.0"
				(at 20.32 -25.4 0)
				(effects
					(font
						(size 1.27 1.27)
						(thickness 0.15)
					)
					(justify left bottom)
					(hide yes)
				)
			)
			(property "Author" "Antmicro"
				(at 20.32 -27.94 0)
				(effects
					(font
						(size 1.27 1.27)
						(thickness 0.15)
					)
					(justify left bottom)
					(hide yes)
				)
			)
			(property "Val" "4k75"
				(at 20.32 -7.62 0)
				(effects
					(font
						(size 1.27 1.27)
						(thickness 0.15)
					)
					(justify left bottom)
				)
			)
			(property "Tolerance" "0.5%"
				(at 20.32 -10.16 0)
				(effects
					(font
						(size 1.27 1.27)
					)
					(justify left bottom)
					(hide yes)
				)
			)
			(property "ki_keywords" "0402, SMT, RESISTOR, PASSIVE"
				(at 0 0 0)
				(effects
					(font
						(size 1.27 1.27)
					)
					(hide yes)
				)
			)
			(symbol "R_4k75_0.5%_0402_0_1"
				(rectangle
					(start 0.635 0.889)
					(end 4.445 -0.889)
					(stroke
						(width 0.254)
						(type default)
					)
					(fill
						(type none)
					)
				)
			)
			(symbol "R_4k75_0.5%_0402_1_1"
				(pin passive line
					(at 0 0 0)
					(length 0.635)
					(name "~"
						(effects
							(font
								(size 1.27 1.27)
							)
						)
					)
					(number "1"
						(effects
							(font
								(size 1.27 1.27)
							)
						)
					)
				)
				(pin passive line
					(at 5.08 0 180)
					(length 0.635)
					(name "~"
						(effects
							(font
								(size 1.27 1.27)
							)
						)
					)
					(number "2"
						(effects
							(font
								(size 1.27 1.27)
							)
						)
					)
				)
			)
		)
	(symbol "antmicroResistors0402:R_5k1_0402"
			(pin_numbers
				(hide yes)
			)
			(pin_names
				(hide yes)
			)
			(exclude_from_sim no)
			(in_bom yes)
			(on_board yes)
			(property "Reference" "R"
				(at 20.32 -5.08 0)
				(effects
					(font
						(size 1.27 1.27)
						(thickness 0.15)
					)
					(justify left bottom)
				)
			)
			(property "Value" "R_5k1_0402"
				(at 20.32 -12.7 0)
				(effects
					(font
						(size 1.27 1.27)
						(thickness 0.15)
					)
					(justify left bottom)
					(hide yes)
				)
			)
			(property "Footprint" "antmicro-footprints:R_0402_1005Metric"
				(at 20.32 -15.24 0)
				(effects
					(font
						(size 1.27 1.27)
						(thickness 0.15)
					)
					(justify left bottom)
					(hide yes)
				)
			)
			(property "Datasheet" "https://www.bourns.com/docs/product-datasheets/cr.pdf"
				(at 20.32 -17.78 0)
				(effects
					(font
						(size 1.27 1.27)
						(thickness 0.15)
					)
					(justify left bottom)
					(hide yes)
				)
			)
			(property "Description" "SMD Chip Resistor, 5.1 kohm, ± 1%, 63 mW, 0402 [1005 Metric], Thick Film, General Purpose"
				(at 20.32 -30.48 0)
				(effects
					(font
						(size 1.27 1.27)
					)
					(justify left bottom)
					(hide yes)
				)
			)
			(property "MPN" "CR0402-FX-5101GLF"
				(at 20.32 -20.32 0)
				(effects
					(font
						(size 1.27 1.27)
						(thickness 0.15)
					)
					(justify left bottom)
					(hide yes)
				)
			)
			(property "Manufacturer" "Bourns"
				(at 20.32 -22.86 0)
				(effects
					(font
						(size 1.27 1.27)
						(thickness 0.15)
					)
					(justify left bottom)
					(hide yes)
				)
			)
			(property "License" "Apache-2.0"
				(at 20.32 -25.4 0)
				(effects
					(font
						(size 1.27 1.27)
						(thickness 0.15)
					)
					(justify left bottom)
					(hide yes)
				)
			)
			(property "Author" "Antmicro"
				(at 20.32 -27.94 0)
				(effects
					(font
						(size 1.27 1.27)
						(thickness 0.15)
					)
					(justify left bottom)
					(hide yes)
				)
			)
			(property "Val" "5k1"
				(at 20.32 -7.62 0)
				(effects
					(font
						(size 1.27 1.27)
						(thickness 0.15)
					)
					(justify left bottom)
				)
			)
			(property "Tolerance" "1%"
				(at 20.32 -10.16 0)
				(effects
					(font
						(size 1.27 1.27)
					)
					(justify left bottom)
					(hide yes)
				)
			)
			(property "ki_keywords" "0402, SMT, RESISTOR, PASSIVE"
				(at 0 0 0)
				(effects
					(font
						(size 1.27 1.27)
					)
					(hide yes)
				)
			)
			(symbol "R_5k1_0402_0_1"
				(rectangle
					(start 0.635 0.889)
					(end 4.445 -0.889)
					(stroke
						(width 0.254)
						(type default)
					)
					(fill
						(type none)
					)
				)
			)
			(symbol "R_5k1_0402_1_1"
				(pin passive line
					(at 0 0 0)
					(length 0.635)
					(name "~"
						(effects
							(font
								(size 1.27 1.27)
							)
						)
					)
					(number "1"
						(effects
							(font
								(size 1.27 1.27)
							)
						)
					)
				)
				(pin passive line
					(at 5.08 0 180)
					(length 0.635)
					(name "~"
						(effects
							(font
								(size 1.27 1.27)
							)
						)
					)
					(number "2"
						(effects
							(font
								(size 1.27 1.27)
							)
						)
					)
				)
			)
		)
	(symbol "antmicroResistors0402:R_63k4_0402"
			(pin_numbers
				(hide yes)
			)
			(pin_names
				(hide yes)
			)
			(exclude_from_sim no)
			(in_bom yes)
			(on_board yes)
			(property "Reference" "R"
				(at 20.32 -5.08 0)
				(effects
					(font
						(size 1.27 1.27)
						(thickness 0.15)
					)
					(justify left bottom)
				)
			)
			(property "Value" "R_63k4_0402"
				(at 20.32 -12.7 0)
				(effects
					(font
						(size 1.27 1.27)
						(thickness 0.15)
					)
					(justify left bottom)
					(hide yes)
				)
			)
			(property "Footprint" "antmicro-footprints:R_0402_1005Metric"
				(at 20.32 -15.24 0)
				(effects
					(font
						(size 1.27 1.27)
						(thickness 0.15)
					)
					(justify left bottom)
					(hide yes)
				)
			)
			(property "Datasheet" "https://industrial.panasonic.com/cdbs/www-data/pdf/RDM0000/AOA0000C307.pdf"
				(at 20.32 -17.78 0)
				(effects
					(font
						(size 1.27 1.27)
						(thickness 0.15)
					)
					(justify left bottom)
					(hide yes)
				)
			)
			(property "Description" "SMD Chip Resistor, 63.4 kohm, ± 0.1%, 63 mW, 0402 [1005 Metric], Thin Film,  Precision"
				(at 20.32 -30.48 0)
				(effects
					(font
						(size 1.27 1.27)
					)
					(justify left bottom)
					(hide yes)
				)
			)
			(property "MPN" "ERA-2AEB6342X"
				(at 20.32 -20.32 0)
				(effects
					(font
						(size 1.27 1.27)
						(thickness 0.15)
					)
					(justify left bottom)
					(hide yes)
				)
			)
			(property "Manufacturer" "Panasonic"
				(at 20.32 -22.86 0)
				(effects
					(font
						(size 1.27 1.27)
						(thickness 0.15)
					)
					(justify left bottom)
					(hide yes)
				)
			)
			(property "License" "Apache-2.0"
				(at 20.32 -25.4 0)
				(effects
					(font
						(size 1.27 1.27)
						(thickness 0.15)
					)
					(justify left bottom)
					(hide yes)
				)
			)
			(property "Author" "Antmicro"
				(at 20.32 -27.94 0)
				(effects
					(font
						(size 1.27 1.27)
						(thickness 0.15)
					)
					(justify left bottom)
					(hide yes)
				)
			)
			(property "Val" "63k4"
				(at 20.32 -7.62 0)
				(effects
					(font
						(size 1.27 1.27)
						(thickness 0.15)
					)
					(justify left bottom)
				)
			)
			(property "Tolerance" "0.1%"
				(at 20.32 -10.16 0)
				(effects
					(font
						(size 1.27 1.27)
					)
					(justify left bottom)
					(hide yes)
				)
			)
			(property "ki_keywords" "0402, SMT, RESISTOR, PASSIVE"
				(at 0 0 0)
				(effects
					(font
						(size 1.27 1.27)
					)
					(hide yes)
				)
			)
			(symbol "R_63k4_0402_0_1"
				(rectangle
					(start 0.635 0.889)
					(end 4.445 -0.889)
					(stroke
						(width 0.254)
						(type default)
					)
					(fill
						(type none)
					)
				)
			)
			(symbol "R_63k4_0402_1_1"
				(pin passive line
					(at 0 0 0)
					(length 0.635)
					(name "~"
						(effects
							(font
								(size 1.27 1.27)
							)
						)
					)
					(number "1"
						(effects
							(font
								(size 1.27 1.27)
							)
						)
					)
				)
				(pin passive line
					(at 5.08 0 180)
					(length 0.635)
					(name "~"
						(effects
							(font
								(size 1.27 1.27)
							)
						)
					)
					(number "2"
						(effects
							(font
								(size 1.27 1.27)
							)
						)
					)
				)
			)
		)
	(symbol "antmicroResistors0402:R_6k04_0.1%_0402"
			(pin_numbers
				(hide yes)
			)
			(pin_names
				(hide yes)
			)
			(exclude_from_sim no)
			(in_bom yes)
			(on_board yes)
			(property "Reference" "R"
				(at 20.32 -5.08 0)
				(effects
					(font
						(size 1.27 1.27)
						(thickness 0.15)
					)
					(justify left bottom)
				)
			)
			(property "Value" "R_6k04_0.1%_0402"
				(at 20.32 -12.7 0)
				(effects
					(font
						(size 1.27 1.27)
						(thickness 0.15)
					)
					(justify left bottom)
					(hide yes)
				)
			)
			(property "Footprint" "antmicro-footprints:R_0402_1005Metric"
				(at 20.32 -15.24 0)
				(effects
					(font
						(size 1.27 1.27)
						(thickness 0.15)
					)
					(justify left bottom)
					(hide yes)
				)
			)
			(property "Datasheet" "https://www.vishay.com/docs/28758/tnpw_e3.pdf"
				(at 20.32 -17.78 0)
				(effects
					(font
						(size 1.27 1.27)
						(thickness 0.15)
					)
					(justify left bottom)
					(hide yes)
				)
			)
			(property "Description" "SMD Chip Resistor, 6.49 kohm, ± 1%, 62.5 mW, 0402 [1005 Metric], Thick Film, General Purpose"
				(at 20.32 -30.48 0)
				(effects
					(font
						(size 1.27 1.27)
					)
					(justify left bottom)
					(hide yes)
				)
			)
			(property "MPN" "TNPW04026K04BEED"
				(at 20.32 -20.32 0)
				(effects
					(font
						(size 1.27 1.27)
						(thickness 0.15)
					)
					(justify left bottom)
					(hide yes)
				)
			)
			(property "Manufacturer" "Vishay"
				(at 20.32 -22.86 0)
				(effects
					(font
						(size 1.27 1.27)
						(thickness 0.15)
					)
					(justify left bottom)
					(hide yes)
				)
			)
			(property "License" "Apache-2.0"
				(at 20.32 -25.4 0)
				(effects
					(font
						(size 1.27 1.27)
						(thickness 0.15)
					)
					(justify left bottom)
					(hide yes)
				)
			)
			(property "Author" "Antmicro"
				(at 20.32 -27.94 0)
				(effects
					(font
						(size 1.27 1.27)
						(thickness 0.15)
					)
					(justify left bottom)
					(hide yes)
				)
			)
			(property "Val" "6k04"
				(at 20.32 -7.62 0)
				(effects
					(font
						(size 1.27 1.27)
						(thickness 0.15)
					)
					(justify left bottom)
				)
			)
			(property "Tolerance" "0.1%"
				(at 20.32 -10.16 0)
				(effects
					(font
						(size 1.27 1.27)
					)
					(justify left bottom)
				)
			)
			(property "ki_keywords" "0402, SMT, RESISTOR, PASSIVE"
				(at 0 0 0)
				(effects
					(font
						(size 1.27 1.27)
					)
					(hide yes)
				)
			)
			(symbol "R_6k04_0.1%_0402_0_1"
				(rectangle
					(start 0.635 0.889)
					(end 4.445 -0.889)
					(stroke
						(width 0.254)
						(type default)
					)
					(fill
						(type none)
					)
				)
			)
			(symbol "R_6k04_0.1%_0402_1_1"
				(pin passive line
					(at 0 0 0)
					(length 0.635)
					(name "~"
						(effects
							(font
								(size 1.27 1.27)
							)
						)
					)
					(number "1"
						(effects
							(font
								(size 1.27 1.27)
							)
						)
					)
				)
				(pin passive line
					(at 5.08 0 180)
					(length 0.635)
					(name "~"
						(effects
							(font
								(size 1.27 1.27)
							)
						)
					)
					(number "2"
						(effects
							(font
								(size 1.27 1.27)
							)
						)
					)
				)
			)
		)
	(symbol "antmicroResistors0402:R_73k2_0402"
			(pin_numbers
				(hide yes)
			)
			(pin_names
				(hide yes)
			)
			(exclude_from_sim no)
			(in_bom yes)
			(on_board yes)
			(property "Reference" "R"
				(at 20.32 -5.08 0)
				(effects
					(font
						(size 1.27 1.27)
						(thickness 0.15)
					)
					(justify left bottom)
				)
			)
			(property "Value" "R_73k2_0402"
				(at 20.32 -12.7 0)
				(effects
					(font
						(size 1.27 1.27)
						(thickness 0.15)
					)
					(justify left bottom)
					(hide yes)
				)
			)
			(property "Footprint" "antmicro-footprints:R_0402_1005Metric"
				(at 20.32 -15.24 0)
				(effects
					(font
						(size 1.27 1.27)
						(thickness 0.15)
					)
					(justify left bottom)
					(hide yes)
				)
			)
			(property "Datasheet" "https://www.bourns.com/docs/product-datasheets/cr.pdf"
				(at 20.32 -17.78 0)
				(effects
					(font
						(size 1.27 1.27)
						(thickness 0.15)
					)
					(justify left bottom)
					(hide yes)
				)
			)
			(property "Description" "SMD Chip Resistor"
				(at 20.32 -30.48 0)
				(effects
					(font
						(size 1.27 1.27)
					)
					(justify left bottom)
					(hide yes)
				)
			)
			(property "MPN" "CR0402-FX-7322GLF"
				(at 20.32 -20.32 0)
				(effects
					(font
						(size 1.27 1.27)
						(thickness 0.15)
					)
					(justify left bottom)
					(hide yes)
				)
			)
			(property "Manufacturer" "Bourns"
				(at 20.32 -22.86 0)
				(effects
					(font
						(size 1.27 1.27)
						(thickness 0.15)
					)
					(justify left bottom)
					(hide yes)
				)
			)
			(property "License" "Apache-2.0"
				(at 20.32 -25.4 0)
				(effects
					(font
						(size 1.27 1.27)
						(thickness 0.15)
					)
					(justify left bottom)
					(hide yes)
				)
			)
			(property "Author" "Antmicro"
				(at 20.32 -27.94 0)
				(effects
					(font
						(size 1.27 1.27)
						(thickness 0.15)
					)
					(justify left bottom)
					(hide yes)
				)
			)
			(property "Val" "73k2"
				(at 20.32 -7.62 0)
				(effects
					(font
						(size 1.27 1.27)
						(thickness 0.15)
					)
					(justify left bottom)
				)
			)
			(property "Tolerance" "1%"
				(at 20.32 -10.16 0)
				(effects
					(font
						(size 1.27 1.27)
					)
					(justify left bottom)
					(hide yes)
				)
			)
			(property "ki_keywords" "0402, SMT, RESISTOR, PASSIVE"
				(at 0 0 0)
				(effects
					(font
						(size 1.27 1.27)
					)
					(hide yes)
				)
			)
			(symbol "R_73k2_0402_0_1"
				(rectangle
					(start 0.635 0.889)
					(end 4.445 -0.889)
					(stroke
						(width 0.254)
						(type default)
					)
					(fill
						(type none)
					)
				)
			)
			(symbol "R_73k2_0402_1_1"
				(pin passive line
					(at 0 0 0)
					(length 0.635)
					(name "~"
						(effects
							(font
								(size 1.27 1.27)
							)
						)
					)
					(number "1"
						(effects
							(font
								(size 1.27 1.27)
							)
						)
					)
				)
				(pin passive line
					(at 5.08 0 180)
					(length 0.635)
					(name "~"
						(effects
							(font
								(size 1.27 1.27)
							)
						)
					)
					(number "2"
						(effects
							(font
								(size 1.27 1.27)
							)
						)
					)
				)
			)
		)
	(symbol "antmicroResistors0402:R_8k2_0402"
			(pin_numbers
				(hide yes)
			)
			(pin_names
				(hide yes)
			)
			(exclude_from_sim no)
			(in_bom yes)
			(on_board yes)
			(property "Reference" "R"
				(at 20.32 -5.08 0)
				(effects
					(font
						(size 1.27 1.27)
						(thickness 0.15)
					)
					(justify left bottom)
				)
			)
			(property "Value" "R_8k2_0402"
				(at 20.32 -12.7 0)
				(effects
					(font
						(size 1.27 1.27)
						(thickness 0.15)
					)
					(justify left bottom)
					(hide yes)
				)
			)
			(property "Footprint" "antmicro-footprints:R_0402_1005Metric"
				(at 20.32 -15.24 0)
				(effects
					(font
						(size 1.27 1.27)
						(thickness 0.15)
					)
					(justify left bottom)
					(hide yes)
				)
			)
			(property "Datasheet" "https://www.bourns.com/docs/product-datasheets/cr.pdf"
				(at 20.32 -17.78 0)
				(effects
					(font
						(size 1.27 1.27)
						(thickness 0.15)
					)
					(justify left bottom)
					(hide yes)
				)
			)
			(property "Description" "SMD Chip Resistor"
				(at 20.32 -30.48 0)
				(effects
					(font
						(size 1.27 1.27)
					)
					(justify left bottom)
					(hide yes)
				)
			)
			(property "MPN" "CR0402-FX-8201GLF"
				(at 20.32 -20.32 0)
				(effects
					(font
						(size 1.27 1.27)
						(thickness 0.15)
					)
					(justify left bottom)
					(hide yes)
				)
			)
			(property "Manufacturer" "Bourns"
				(at 20.32 -22.86 0)
				(effects
					(font
						(size 1.27 1.27)
						(thickness 0.15)
					)
					(justify left bottom)
					(hide yes)
				)
			)
			(property "License" "Apache-2.0"
				(at 20.32 -25.4 0)
				(effects
					(font
						(size 1.27 1.27)
						(thickness 0.15)
					)
					(justify left bottom)
					(hide yes)
				)
			)
			(property "Author" "Antmicro"
				(at 20.32 -27.94 0)
				(effects
					(font
						(size 1.27 1.27)
						(thickness 0.15)
					)
					(justify left bottom)
					(hide yes)
				)
			)
			(property "Val" "8k2"
				(at 20.32 -7.62 0)
				(effects
					(font
						(size 1.27 1.27)
						(thickness 0.15)
					)
					(justify left bottom)
				)
			)
			(property "Tolerance" "1%"
				(at 20.32 -10.16 0)
				(effects
					(font
						(size 1.27 1.27)
					)
					(justify left bottom)
					(hide yes)
				)
			)
			(property "ki_keywords" "0402, SMT, RESISTOR, PASSIVE"
				(at 0 0 0)
				(effects
					(font
						(size 1.27 1.27)
					)
					(hide yes)
				)
			)
			(symbol "R_8k2_0402_0_1"
				(rectangle
					(start 0.635 0.889)
					(end 4.445 -0.889)
					(stroke
						(width 0.254)
						(type default)
					)
					(fill
						(type none)
					)
				)
			)
			(symbol "R_8k2_0402_1_1"
				(pin passive line
					(at 0 0 0)
					(length 0.635)
					(name "~"
						(effects
							(font
								(size 1.27 1.27)
							)
						)
					)
					(number "1"
						(effects
							(font
								(size 1.27 1.27)
							)
						)
					)
				)
				(pin passive line
					(at 5.08 0 180)
					(length 0.635)
					(name "~"
						(effects
							(font
								(size 1.27 1.27)
							)
						)
					)
					(number "2"
						(effects
							(font
								(size 1.27 1.27)
							)
						)
					)
				)
			)
		)
	(symbol "antmicroResistors0402:R_8k87_0402"
			(pin_numbers
				(hide yes)
			)
			(pin_names
				(hide yes)
			)
			(exclude_from_sim no)
			(in_bom yes)
			(on_board yes)
			(property "Reference" "R"
				(at 20.32 -5.08 0)
				(effects
					(font
						(size 1.27 1.27)
						(thickness 0.15)
					)
					(justify left bottom)
				)
			)
			(property "Value" "R_8k87_0402"
				(at 20.32 -12.7 0)
				(effects
					(font
						(size 1.27 1.27)
						(thickness 0.15)
					)
					(justify left bottom)
					(hide yes)
				)
			)
			(property "Footprint" "antmicro-footprints:R_0402_1005Metric"
				(at 20.32 -15.24 0)
				(effects
					(font
						(size 1.27 1.27)
						(thickness 0.15)
					)
					(justify left bottom)
					(hide yes)
				)
			)
			(property "Datasheet" "https://www.bourns.com/docs/product-datasheets/cr.pdf"
				(at 20.32 -17.78 0)
				(effects
					(font
						(size 1.27 1.27)
						(thickness 0.15)
					)
					(justify left bottom)
					(hide yes)
				)
			)
			(property "Description" "SMD Chip Resistor, 8.87 kohm, ± 1%, 100 mW, 0402 [1005 Metric], Thick Film, Precision"
				(at 20.32 -30.48 0)
				(effects
					(font
						(size 1.27 1.27)
					)
					(justify left bottom)
					(hide yes)
				)
			)
			(property "MPN" "CR0402-FX-8871GLF"
				(at 20.32 -20.32 0)
				(effects
					(font
						(size 1.27 1.27)
						(thickness 0.15)
					)
					(justify left bottom)
					(hide yes)
				)
			)
			(property "Manufacturer" "Bourns"
				(at 20.32 -22.86 0)
				(effects
					(font
						(size 1.27 1.27)
						(thickness 0.15)
					)
					(justify left bottom)
					(hide yes)
				)
			)
			(property "License" "Apache-2.0"
				(at 20.32 -25.4 0)
				(effects
					(font
						(size 1.27 1.27)
						(thickness 0.15)
					)
					(justify left bottom)
					(hide yes)
				)
			)
			(property "Author" "Antmicro"
				(at 20.32 -27.94 0)
				(effects
					(font
						(size 1.27 1.27)
						(thickness 0.15)
					)
					(justify left bottom)
					(hide yes)
				)
			)
			(property "Val" "8k87"
				(at 20.32 -7.62 0)
				(effects
					(font
						(size 1.27 1.27)
						(thickness 0.15)
					)
					(justify left bottom)
				)
			)
			(property "Tolerance" "1%"
				(at 20.32 -10.16 0)
				(effects
					(font
						(size 1.27 1.27)
					)
					(justify left bottom)
					(hide yes)
				)
			)
			(property "ki_keywords" "0402, SMT, RESISTOR, PASSIVE"
				(at 0 0 0)
				(effects
					(font
						(size 1.27 1.27)
					)
					(hide yes)
				)
			)
			(symbol "R_8k87_0402_0_1"
				(rectangle
					(start 0.635 0.889)
					(end 4.445 -0.889)
					(stroke
						(width 0.254)
						(type default)
					)
					(fill
						(type none)
					)
				)
			)
			(symbol "R_8k87_0402_1_1"
				(pin passive line
					(at 0 0 0)
					(length 0.635)
					(name "~"
						(effects
							(font
								(size 1.27 1.27)
							)
						)
					)
					(number "1"
						(effects
							(font
								(size 1.27 1.27)
							)
						)
					)
				)
				(pin passive line
					(at 5.08 0 180)
					(length 0.635)
					(name "~"
						(effects
							(font
								(size 1.27 1.27)
							)
						)
					)
					(number "2"
						(effects
							(font
								(size 1.27 1.27)
							)
						)
					)
				)
			)
		)
	(symbol "antmicroResistors0402:R_90k9_0402"
			(pin_numbers
				(hide yes)
			)
			(pin_names
				(hide yes)
			)
			(exclude_from_sim no)
			(in_bom yes)
			(on_board yes)
			(property "Reference" "R"
				(at 20.32 -5.08 0)
				(effects
					(font
						(size 1.27 1.27)
						(thickness 0.15)
					)
					(justify left bottom)
				)
			)
			(property "Value" "R_90k9_0402"
				(at 20.32 -12.7 0)
				(effects
					(font
						(size 1.27 1.27)
						(thickness 0.15)
					)
					(justify left bottom)
					(hide yes)
				)
			)
			(property "Footprint" "antmicro-footprints:R_0402_1005Metric"
				(at 20.32 -15.24 0)
				(effects
					(font
						(size 1.27 1.27)
						(thickness 0.15)
					)
					(justify left bottom)
					(hide yes)
				)
			)
			(property "Datasheet" "https://www.bourns.com/docs/product-datasheets/cr.pdf"
				(at 20.32 -17.78 0)
				(effects
					(font
						(size 1.27 1.27)
						(thickness 0.15)
					)
					(justify left bottom)
					(hide yes)
				)
			)
			(property "Description" "SMD Chip Resistor"
				(at 20.32 -30.48 0)
				(effects
					(font
						(size 1.27 1.27)
					)
					(justify left bottom)
					(hide yes)
				)
			)
			(property "MPN" "CR0402-FX-9092GLF"
				(at 20.32 -20.32 0)
				(effects
					(font
						(size 1.27 1.27)
						(thickness 0.15)
					)
					(justify left bottom)
					(hide yes)
				)
			)
			(property "Manufacturer" "Bourns"
				(at 20.32 -22.86 0)
				(effects
					(font
						(size 1.27 1.27)
						(thickness 0.15)
					)
					(justify left bottom)
					(hide yes)
				)
			)
			(property "License" "Apache-2.0"
				(at 20.32 -25.4 0)
				(effects
					(font
						(size 1.27 1.27)
						(thickness 0.15)
					)
					(justify left bottom)
					(hide yes)
				)
			)
			(property "Author" "Antmicro"
				(at 20.32 -27.94 0)
				(effects
					(font
						(size 1.27 1.27)
						(thickness 0.15)
					)
					(justify left bottom)
					(hide yes)
				)
			)
			(property "Val" "90k9"
				(at 20.32 -7.62 0)
				(effects
					(font
						(size 1.27 1.27)
						(thickness 0.15)
					)
					(justify left bottom)
				)
			)
			(property "Tolerance" "1%"
				(at 20.32 -10.16 0)
				(effects
					(font
						(size 1.27 1.27)
					)
					(justify left bottom)
					(hide yes)
				)
			)
			(property "ki_keywords" "0402, SMT, RESISTOR, PASSIVE"
				(at 0 0 0)
				(effects
					(font
						(size 1.27 1.27)
					)
					(hide yes)
				)
			)
			(symbol "R_90k9_0402_0_1"
				(rectangle
					(start 0.635 0.889)
					(end 4.445 -0.889)
					(stroke
						(width 0.254)
						(type default)
					)
					(fill
						(type none)
					)
				)
			)
			(symbol "R_90k9_0402_1_1"
				(pin passive line
					(at 0 0 0)
					(length 0.635)
					(name "~"
						(effects
							(font
								(size 1.27 1.27)
							)
						)
					)
					(number "1"
						(effects
							(font
								(size 1.27 1.27)
							)
						)
					)
				)
				(pin passive line
					(at 5.08 0 180)
					(length 0.635)
					(name "~"
						(effects
							(font
								(size 1.27 1.27)
							)
						)
					)
					(number "2"
						(effects
							(font
								(size 1.27 1.27)
							)
						)
					)
				)
			)
		)
	(symbol "antmicroResistors0603:R_0R_22.4A_0603"
			(pin_numbers
				(hide yes)
			)
			(pin_names
				(hide yes)
			)
			(exclude_from_sim no)
			(in_bom yes)
			(on_board yes)
			(property "Reference" "R"
				(at 15.24 -2.54 0)
				(effects
					(font
						(size 1.27 1.27)
						(thickness 0.15)
					)
					(justify left bottom)
				)
			)
			(property "Value" "R_0R_22.4A_0603"
				(at 15.24 -5.08 0)
				(effects
					(font
						(size 1.27 1.27)
						(thickness 0.15)
					)
					(justify left bottom)
					(hide yes)
				)
			)
			(property "Footprint" "antmicro-footprints:R_0603_1608Metric"
				(at 15.24 -10.16 0)
				(effects
					(font
						(size 1.27 1.27)
						(thickness 0.15)
					)
					(justify left bottom)
					(hide yes)
				)
			)
			(property "Datasheet" "https://fscdn.rohm.com/en/products/databook/datasheet/passive/resistor/chip_resistor/pmr-jpw-e.pdf"
				(at 15.24 -12.7 0)
				(effects
					(font
						(size 1.27 1.27)
						(thickness 0.15)
					)
					(justify left bottom)
					(hide yes)
				)
			)
			(property "Description" "SMD Chip Resistor"
				(at 15.24 -27.94 0)
				(effects
					(font
						(size 1.27 1.27)
					)
					(justify left bottom)
					(hide yes)
				)
			)
			(property "MPN" "PMR03EZPJ000"
				(at 15.24 -15.24 0)
				(effects
					(font
						(size 1.27 1.27)
						(thickness 0.15)
					)
					(justify left bottom)
					(hide yes)
				)
			)
			(property "Manufacturer" "ROHM Semiconductor"
				(at 15.24 -17.78 0)
				(effects
					(font
						(size 1.27 1.27)
						(thickness 0.15)
					)
					(justify left bottom)
					(hide yes)
				)
			)
			(property "Val" "0R"
				(at 15.24 -7.62 0)
				(effects
					(font
						(size 1.27 1.27)
						(thickness 0.15)
					)
					(justify left bottom)
				)
			)
			(property "Max. Curr." "22.4A"
				(at 15.24 -20.32 0)
				(effects
					(font
						(size 1.27 1.27)
						(thickness 0.15)
					)
					(justify left bottom)
				)
			)
			(property "Author" "Antmicro"
				(at 15.24 -22.86 0)
				(effects
					(font
						(size 1.27 1.27)
						(thickness 0.15)
					)
					(justify left bottom)
					(hide yes)
				)
			)
			(property "License" "Apache-2.0"
				(at 15.24 -25.4 0)
				(effects
					(font
						(size 1.27 1.27)
						(thickness 0.15)
					)
					(justify left bottom)
					(hide yes)
				)
			)
			(property "Tolerance" "template_tolerance"
				(at 20.32 -10.16 0)
				(effects
					(font
						(size 1.27 1.27)
					)
					(justify left bottom)
					(hide yes)
				)
			)
			(property "ki_keywords" "0603, SMT, RESISTOR, PASSIVE"
				(at 0 0 0)
				(effects
					(font
						(size 1.27 1.27)
					)
					(hide yes)
				)
			)
			(symbol "R_0R_22.4A_0603_0_1"
				(rectangle
					(start 0.635 0.889)
					(end 4.445 -0.889)
					(stroke
						(width 0.254)
						(type default)
					)
					(fill
						(type none)
					)
				)
			)
			(symbol "R_0R_22.4A_0603_1_1"
				(pin passive line
					(at 0 0 0)
					(length 0.635)
					(name "~"
						(effects
							(font
								(size 1.27 1.27)
							)
						)
					)
					(number "1"
						(effects
							(font
								(size 1.27 1.27)
							)
						)
					)
				)
				(pin passive line
					(at 5.08 0 180)
					(length 0.635)
					(name "~"
						(effects
							(font
								(size 1.27 1.27)
							)
						)
					)
					(number "2"
						(effects
							(font
								(size 1.27 1.27)
							)
						)
					)
				)
			)
		)
	(symbol "antmicroResonators:Resonator_25MHz_ABM8G"
			(pin_names
				(hide yes)
			)
			(exclude_from_sim no)
			(in_bom yes)
			(on_board yes)
			(property "Reference" "Y"
				(at 15.24 -5.08 0)
				(effects
					(font
						(size 1.27 1.27)
						(thickness 0.15)
					)
					(justify left bottom)
				)
			)
			(property "Value" "Resonator_25MHz_ABM8G"
				(at 15.24 -12.7 0)
				(effects
					(font
						(size 1.27 1.27)
						(thickness 0.15)
					)
					(justify left bottom)
					(hide yes)
				)
			)
			(property "Footprint" "antmicro-footprints:Resonator_SMD_Abracon_ABM8G_3.2x2.5mm"
				(at 15.24 -15.24 0)
				(effects
					(font
						(size 1.27 1.27)
						(thickness 0.15)
					)
					(justify left bottom)
					(hide yes)
				)
			)
			(property "Datasheet" "https://abracon.com/Resonators/ABM8G.pdf"
				(at 15.24 -17.78 0)
				(effects
					(font
						(size 1.27 1.27)
						(thickness 0.15)
					)
					(justify left bottom)
					(hide yes)
				)
			)
			(property "Description" "Crystal, 25 MHz, SMD, 3.2mm x 2.5mm, 30 ppm, 18 pF, 20 ppm, ABM8G"
				(at 15.24 -27.94 0)
				(effects
					(font
						(size 1.27 1.27)
					)
					(justify left bottom)
					(hide yes)
				)
			)
			(property "MPN" "ABM8G-25.000MHZ-18-D2Y-T3"
				(at 15.24 -7.62 0)
				(effects
					(font
						(size 1.27 1.27)
						(thickness 0.15)
					)
					(justify left bottom)
				)
			)
			(property "Manufacturer" "Abracon"
				(at 15.24 -20.32 0)
				(effects
					(font
						(size 1.27 1.27)
						(thickness 0.15)
					)
					(justify left bottom)
					(hide yes)
				)
			)
			(property "Author" "Antmicro"
				(at 15.24 -22.86 0)
				(effects
					(font
						(size 1.27 1.27)
						(thickness 0.15)
					)
					(justify left bottom)
					(hide yes)
				)
			)
			(property "License" "Apache-2.0"
				(at 15.24 -25.4 0)
				(effects
					(font
						(size 1.27 1.27)
						(thickness 0.15)
					)
					(justify left bottom)
					(hide yes)
				)
			)
			(property "Val" "25 MHz"
				(at 15.24 -10.16 0)
				(effects
					(font
						(size 1.27 1.27)
						(thickness 0.15)
					)
					(justify left bottom)
				)
			)
			(property "ki_keywords" "SMT, CERAMIC, OSCILLATOR"
				(at 0 0 0)
				(effects
					(font
						(size 1.27 1.27)
					)
					(hide yes)
				)
			)
			(symbol "Resonator_25MHz_ABM8G_1_1"
				(polyline
					(pts
						(xy 1.905 1.905) (xy 1.905 2.54) (xy 5.715 2.54) (xy 5.715 1.905)
					)
					(stroke
						(width 0.254)
						(type default)
					)
					(fill
						(type none)
					)
				)
				(polyline
					(pts
						(xy 1.905 -1.905) (xy 1.905 -2.54) (xy 5.715 -2.54) (xy 5.715 -1.905)
					)
					(stroke
						(width 0.254)
						(type default)
					)
					(fill
						(type none)
					)
				)
				(polyline
					(pts
						(xy 2.54 1.27) (xy 2.54 -1.27)
					)
					(stroke
						(width 0.254)
						(type default)
					)
					(fill
						(type background)
					)
				)
				(rectangle
					(start 3.175 1.905)
					(end 4.445 -1.905)
					(stroke
						(width 0.254)
						(type default)
					)
					(fill
						(type background)
					)
				)
				(polyline
					(pts
						(xy 5.08 1.27) (xy 5.08 -1.27)
					)
					(stroke
						(width 0.254)
						(type default)
					)
					(fill
						(type background)
					)
				)
				(pin passive line
					(at 0 0 0)
					(length 2.54)
					(name "~"
						(effects
							(font
								(size 1.27 1.27)
							)
						)
					)
					(number "1"
						(effects
							(font
								(size 1.27 1.27)
							)
						)
					)
				)
				(pin passive line
					(at 3.81 -5.08 90)
					(length 2.54)
					(name "SH"
						(effects
							(font
								(size 1.27 1.27)
							)
						)
					)
					(number "2"
						(effects
							(font
								(size 1.27 1.27)
							)
						)
					)
				)
				(pin passive line
					(at 3.81 -5.08 90)
					(length 2.54)
					(hide yes)
					(name "SH"
						(effects
							(font
								(size 1.27 1.27)
							)
						)
					)
					(number "4"
						(effects
							(font
								(size 1.27 1.27)
							)
						)
					)
				)
				(pin passive line
					(at 7.62 0 180)
					(length 2.54)
					(name "~"
						(effects
							(font
								(size 1.27 1.27)
							)
						)
					)
					(number "3"
						(effects
							(font
								(size 1.27 1.27)
							)
						)
					)
				)
			)
		)
	(symbol "antmicroResonators:Resonator_50MHz_XRCGE"
			(pin_names
				(hide yes)
			)
			(exclude_from_sim no)
			(in_bom yes)
			(on_board yes)
			(property "Reference" "Y"
				(at 22.86 -2.54 0)
				(effects
					(font
						(size 1.27 1.27)
						(thickness 0.15)
					)
					(justify left bottom)
				)
			)
			(property "Value" "Resonator_50MHz_XRCGE"
				(at 22.86 -7.62 0)
				(effects
					(font
						(size 1.27 1.27)
						(thickness 0.15)
					)
					(justify left bottom)
					(hide yes)
				)
			)
			(property "Footprint" "antmicro-footprints:Resonator_SMD_Murata_XRCGB_2x1.6x0.65mm"
				(at 22.86 -10.16 0)
				(effects
					(font
						(size 1.27 1.27)
						(thickness 0.15)
					)
					(justify left bottom)
					(hide yes)
				)
			)
			(property "Datasheet" "https://www.murata.com/products/productdata/8813268205598/SPEC-XRCGE50M000F5A2AR0.pdf"
				(at 22.86 -12.7 0)
				(effects
					(font
						(size 1.27 1.27)
						(thickness 0.15)
					)
					(justify left bottom)
					(hide yes)
				)
			)
			(property "Description" "Crystal, 50 MHz, 2mm x 1.6mm, 50 ppm, 4.7 pF, 50 ppm, XRCGE Series"
				(at 22.86 -27.94 0)
				(effects
					(font
						(size 1.27 1.27)
					)
					(justify left bottom)
					(hide yes)
				)
			)
			(property "Manufacturer" "Murata"
				(at 22.86 -25.4 0)
				(effects
					(font
						(size 1.27 1.27)
					)
					(justify left bottom)
					(hide yes)
				)
			)
			(property "MPN" "XRCGE50M000F5A2AR0"
				(at 22.86 -22.86 0)
				(effects
					(font
						(size 1.27 1.27)
					)
					(justify left bottom)
				)
			)
			(property "Val" "50MHz"
				(at 22.86 -5.08 0)
				(effects
					(font
						(size 1.27 1.27)
					)
					(justify left bottom)
				)
			)
			(property "CLoad" "4.7pF"
				(at 22.86 -20.32 0)
				(effects
					(font
						(size 1.27 1.27)
					)
					(justify left bottom)
					(hide yes)
				)
			)
			(property "Author" "Antmicro"
				(at 22.86 -15.24 0)
				(effects
					(font
						(size 1.27 1.27)
					)
					(justify left bottom)
					(hide yes)
				)
			)
			(property "License" "Apache-2.0"
				(at 22.86 -17.78 0)
				(effects
					(font
						(size 1.27 1.27)
					)
					(justify left bottom)
					(hide yes)
				)
			)
			(property "ki_keywords" "OSCILLATOR"
				(at 0 0 0)
				(effects
					(font
						(size 1.27 1.27)
					)
					(hide yes)
				)
			)
			(symbol "Resonator_50MHz_XRCGE_1_1"
				(polyline
					(pts
						(xy 1.905 1.905) (xy 1.905 2.54) (xy 5.715 2.54) (xy 5.715 1.905)
					)
					(stroke
						(width 0.254)
						(type default)
					)
					(fill
						(type none)
					)
				)
				(polyline
					(pts
						(xy 1.905 -1.905) (xy 1.905 -2.54) (xy 5.715 -2.54) (xy 5.715 -1.905)
					)
					(stroke
						(width 0.254)
						(type default)
					)
					(fill
						(type none)
					)
				)
				(polyline
					(pts
						(xy 2.54 1.27) (xy 2.54 -1.27)
					)
					(stroke
						(width 0.254)
						(type default)
					)
					(fill
						(type background)
					)
				)
				(rectangle
					(start 3.175 1.905)
					(end 4.445 -1.905)
					(stroke
						(width 0.254)
						(type default)
					)
					(fill
						(type background)
					)
				)
				(polyline
					(pts
						(xy 5.08 1.27) (xy 5.08 -1.27)
					)
					(stroke
						(width 0.254)
						(type default)
					)
					(fill
						(type background)
					)
				)
				(pin passive line
					(at 0 0 0)
					(length 2.54)
					(name "~"
						(effects
							(font
								(size 1.27 1.27)
							)
						)
					)
					(number "1"
						(effects
							(font
								(size 1.27 1.27)
							)
						)
					)
				)
				(pin passive line
					(at 3.81 -5.08 90)
					(length 2.54)
					(name "SH"
						(effects
							(font
								(size 1.27 1.27)
							)
						)
					)
					(number "2"
						(effects
							(font
								(size 1.27 1.27)
							)
						)
					)
				)
				(pin passive line
					(at 3.81 -5.08 90)
					(length 2.54)
					(hide yes)
					(name "SH"
						(effects
							(font
								(size 1.27 1.27)
							)
						)
					)
					(number "4"
						(effects
							(font
								(size 1.27 1.27)
							)
						)
					)
				)
				(pin passive line
					(at 7.62 0 180)
					(length 2.54)
					(name "~"
						(effects
							(font
								(size 1.27 1.27)
							)
						)
					)
					(number "3"
						(effects
							(font
								(size 1.27 1.27)
							)
						)
					)
				)
			)
		)
	(symbol "antmicroSlideSwitches:SW_DS04-254-1-01BK-SMT"
			(exclude_from_sim no)
			(in_bom yes)
			(on_board yes)
			(property "Reference" "SW"
				(at 26.67 -2.54 0)
				(effects
					(font
						(size 1.27 1.27)
						(thickness 0.15)
					)
					(justify left bottom)
				)
			)
			(property "Value" "SW_DS04-254-1-01BK-SMT"
				(at 26.67 -5.08 0)
				(effects
					(font
						(size 1.27 1.27)
						(thickness 0.15)
					)
					(justify left bottom)
					(hide yes)
				)
			)
			(property "Footprint" "antmicro-footprints:SW_DS04-254-1-01BK-SMT"
				(at 26.67 -7.62 0)
				(effects
					(font
						(size 1.27 1.27)
						(thickness 0.15)
					)
					(justify left bottom)
					(hide yes)
				)
			)
			(property "Datasheet" "https://www.mouser.com/datasheet/2/670/ds04_254_smt-1777718.pdf"
				(at 26.67 -10.16 0)
				(effects
					(font
						(size 1.27 1.27)
						(thickness 0.15)
					)
					(justify left bottom)
					(hide yes)
				)
			)
			(property "Description" "Slide switch"
				(at 26.67 -22.86 0)
				(effects
					(font
						(size 1.27 1.27)
					)
					(justify left bottom)
					(hide yes)
				)
			)
			(property "MPN" "DS04-254-1-01BK-SMT"
				(at 26.67 -12.7 0)
				(effects
					(font
						(size 1.27 1.27)
						(thickness 0.15)
					)
					(justify left bottom)
				)
			)
			(property "Manufacturer" "CUI Inc"
				(at 26.67 -15.24 0)
				(effects
					(font
						(size 1.27 1.27)
						(thickness 0.15)
					)
					(justify left bottom)
					(hide yes)
				)
			)
			(property "Author" "Antmicro"
				(at 26.67 -17.78 0)
				(effects
					(font
						(size 1.27 1.27)
						(thickness 0.15)
					)
					(justify left bottom)
					(hide yes)
				)
			)
			(property "License" "Apache-2.0"
				(at 26.67 -20.32 0)
				(effects
					(font
						(size 1.27 1.27)
						(thickness 0.15)
					)
					(justify left bottom)
					(hide yes)
				)
			)
			(property "ki_keywords" "HORIZONTAL, SMT, SWITCH, MECHANICAL, SLIDE"
				(at 0 0 0)
				(effects
					(font
						(size 1.27 1.27)
					)
					(hide yes)
				)
			)
			(property "ki_fp_filters" "SW?DIP?x1*"
				(at 0 0 0)
				(effects
					(font
						(size 1.27 1.27)
					)
					(hide yes)
				)
			)
			(symbol "SW_DS04-254-1-01BK-SMT_0_1"
				(polyline
					(pts
						(xy 3.81 0) (xy 2.54 0)
					)
					(stroke
						(width 0.254)
						(type default)
					)
					(fill
						(type none)
					)
				)
				(polyline
					(pts
						(xy 10.16 0) (xy 8.89 0)
					)
					(stroke
						(width 0.254)
						(type default)
					)
					(fill
						(type none)
					)
				)
			)
			(symbol "SW_DS04-254-1-01BK-SMT_1_1"
				(rectangle
					(start 2.54 2.54)
					(end 10.16 -2.54)
					(stroke
						(width 0.254)
						(type default)
					)
					(fill
						(type background)
					)
				)
				(circle
					(center 4.318 0)
					(radius 0.508)
					(stroke
						(width 0.254)
						(type default)
					)
					(fill
						(type background)
					)
				)
				(polyline
					(pts
						(xy 4.826 0.127) (xy 8.7122 1.1684)
					)
					(stroke
						(width 0.254)
						(type default)
					)
					(fill
						(type background)
					)
				)
				(circle
					(center 8.382 0)
					(radius 0.508)
					(stroke
						(width 0.254)
						(type default)
					)
					(fill
						(type background)
					)
				)
				(pin passive line
					(at 0 0 0)
					(length 2.54)
					(name "~"
						(effects
							(font
								(size 1.27 1.27)
							)
						)
					)
					(number "1"
						(effects
							(font
								(size 1.27 1.27)
							)
						)
					)
				)
				(pin passive line
					(at 12.7 0 180)
					(length 2.54)
					(name "~"
						(effects
							(font
								(size 1.27 1.27)
							)
						)
					)
					(number "2"
						(effects
							(font
								(size 1.27 1.27)
							)
						)
					)
				)
			)
		)
	(symbol "antmicroTVSDiodes:PESD5Z5_0F"
			(pin_numbers
				(hide yes)
			)
			(pin_names
				(hide yes)
			)
			(exclude_from_sim no)
			(in_bom yes)
			(on_board yes)
			(property "Reference" "D"
				(at 15.24 0 0)
				(effects
					(font
						(size 1.27 1.27)
						(thickness 0.15)
					)
					(justify left bottom)
				)
			)
			(property "Value" "PESD5Z5_0F"
				(at 15.24 -12.7 0)
				(effects
					(font
						(size 1.27 1.27)
						(thickness 0.15)
					)
					(justify left bottom)
					(hide yes)
				)
			)
			(property "Footprint" "antmicro-footprints:SOD-523"
				(at 15.24 -5.08 0)
				(effects
					(font
						(size 1.27 1.27)
						(thickness 0.15)
					)
					(justify left bottom)
					(hide yes)
				)
			)
			(property "Datasheet" "https://assets.nexperia.com/documents/data-sheet/PESD5Z5_0.pdf"
				(at 15.24 -7.62 0)
				(effects
					(font
						(size 1.27 1.27)
						(thickness 0.15)
					)
					(justify left bottom)
					(hide yes)
				)
			)
			(property "Description" "Unidirectional TVS, 30 kV,  SOD-523, 5 V, 89 pF"
				(at 15.24 -20.32 0)
				(effects
					(font
						(size 1.27 1.27)
					)
					(justify left bottom)
					(hide yes)
				)
			)
			(property "Manufacturer" "Nexperia"
				(at 15.24 -10.16 0)
				(effects
					(font
						(size 1.27 1.27)
						(thickness 0.15)
					)
					(justify left bottom)
					(hide yes)
				)
			)
			(property "MPN" "PESD5Z5.0F"
				(at 15.24 -2.54 0)
				(effects
					(font
						(size 1.27 1.27)
						(thickness 0.15)
					)
					(justify left bottom)
				)
			)
			(property "Author" "Antmicro"
				(at 15.24 -15.24 0)
				(effects
					(font
						(size 1.27 1.27)
						(thickness 0.15)
					)
					(justify left bottom)
					(hide yes)
				)
			)
			(property "License" "Apache-2.0"
				(at 15.24 -17.78 0)
				(effects
					(font
						(size 1.27 1.27)
						(thickness 0.15)
					)
					(justify left bottom)
					(hide yes)
				)
			)
			(property "ki_keywords" "DIODE, SEMICONDUCTOR, TVS, ESD"
				(at 0 0 0)
				(effects
					(font
						(size 1.27 1.27)
					)
					(hide yes)
				)
			)
			(symbol "PESD5Z5_0F_0_1"
				(polyline
					(pts
						(xy 1.905 0) (xy 0.635 0)
					)
					(stroke
						(width 0)
						(type default)
					)
					(fill
						(type none)
					)
				)
				(polyline
					(pts
						(xy 4.445 0) (xy 3.175 0)
					)
					(stroke
						(width 0)
						(type default)
					)
					(fill
						(type none)
					)
				)
			)
			(symbol "PESD5Z5_0F_1_1"
				(polyline
					(pts
						(xy 1.778 1.016) (xy 1.397 1.016)
					)
					(stroke
						(width 0.254)
						(type default)
					)
					(fill
						(type none)
					)
				)
				(polyline
					(pts
						(xy 1.778 1.016) (xy 1.778 -1.016)
					)
					(stroke
						(width 0.254)
						(type default)
					)
					(fill
						(type none)
					)
				)
				(polyline
					(pts
						(xy 2.159 -1.016) (xy 1.778 -1.016)
					)
					(stroke
						(width 0.254)
						(type default)
					)
					(fill
						(type none)
					)
				)
				(polyline
					(pts
						(xy 3.302 1.016) (xy 3.302 -1.016) (xy 1.778 0) (xy 3.302 1.016)
					)
					(stroke
						(width 0.254)
						(type default)
					)
					(fill
						(type outline)
					)
				)
				(pin passive line
					(at 0 0 0)
					(length 0.635)
					(name "C"
						(effects
							(font
								(size 1.27 1.27)
							)
						)
					)
					(number "1"
						(effects
							(font
								(size 1.27 1.27)
							)
						)
					)
				)
				(pin passive line
					(at 5.08 0 180)
					(length 0.635)
					(name "A"
						(effects
							(font
								(size 1.27 1.27)
							)
						)
					)
					(number "2"
						(effects
							(font
								(size 1.27 1.27)
							)
						)
					)
				)
			)
		)
	(symbol "antmicroTVSDiodes:PTVS26VS1UR,115"
			(pin_numbers
				(hide yes)
			)
			(pin_names
				(hide yes)
			)
			(exclude_from_sim no)
			(in_bom yes)
			(on_board yes)
			(property "Reference" "D"
				(at 20.32 -2.54 0)
				(effects
					(font
						(size 1.27 1.27)
						(thickness 0.15)
					)
					(justify left bottom)
				)
			)
			(property "Value" "PTVS26VS1UR,115"
				(at 20.32 -5.08 0)
				(effects
					(font
						(size 1.27 1.27)
						(thickness 0.15)
					)
					(justify left bottom)
					(hide yes)
				)
			)
			(property "Footprint" "antmicro-footprints:D_SOD-123"
				(at 20.32 -7.62 0)
				(effects
					(font
						(size 1.27 1.27)
						(thickness 0.15)
					)
					(justify left bottom)
					(hide yes)
				)
			)
			(property "Datasheet" "https://www.mouser.com/datasheet/2/916/PTVSXS1UR_SER-1545507.pdf"
				(at 20.32 -10.16 0)
				(effects
					(font
						(size 1.27 1.27)
						(thickness 0.15)
					)
					(justify left bottom)
					(hide yes)
				)
			)
			(property "Description" "Unidirectional TVS, 8 kV,  SOD-123F, 26 V, 400 W"
				(at 20.32 -22.86 0)
				(effects
					(font
						(size 1.27 1.27)
					)
					(justify left bottom)
					(hide yes)
				)
			)
			(property "Author" "Antmicro"
				(at 20.32 -17.78 0)
				(effects
					(font
						(size 1.27 1.27)
						(thickness 0.15)
					)
					(justify left bottom)
					(hide yes)
				)
			)
			(property "License" "Apache-2.0"
				(at 20.32 -20.32 0)
				(effects
					(font
						(size 1.27 1.27)
						(thickness 0.15)
					)
					(justify left bottom)
					(hide yes)
				)
			)
			(property "Manufacturer" "Nexperia"
				(at 20.32 -15.24 0)
				(effects
					(font
						(size 1.27 1.27)
					)
					(justify left bottom)
					(hide yes)
				)
			)
			(property "MPN" "PTVS26VS1UR,115"
				(at 20.32 -12.7 0)
				(effects
					(font
						(size 1.27 1.27)
					)
					(justify left bottom)
				)
			)
			(property "ki_keywords" "DIODE, SEMICONDUCTOR, TVS, ESD"
				(at 0 0 0)
				(effects
					(font
						(size 1.27 1.27)
					)
					(hide yes)
				)
			)
			(symbol "PTVS26VS1UR,115_0_1"
				(polyline
					(pts
						(xy 1.905 0) (xy 0.635 0)
					)
					(stroke
						(width 0)
						(type default)
					)
					(fill
						(type none)
					)
				)
				(polyline
					(pts
						(xy 4.445 0) (xy 3.175 0)
					)
					(stroke
						(width 0)
						(type default)
					)
					(fill
						(type none)
					)
				)
			)
			(symbol "PTVS26VS1UR,115_1_1"
				(polyline
					(pts
						(xy 1.778 1.016) (xy 1.397 1.016)
					)
					(stroke
						(width 0.254)
						(type default)
					)
					(fill
						(type none)
					)
				)
				(polyline
					(pts
						(xy 1.778 1.016) (xy 1.778 -1.016)
					)
					(stroke
						(width 0.254)
						(type default)
					)
					(fill
						(type none)
					)
				)
				(polyline
					(pts
						(xy 2.159 -1.016) (xy 1.778 -1.016)
					)
					(stroke
						(width 0.254)
						(type default)
					)
					(fill
						(type none)
					)
				)
				(polyline
					(pts
						(xy 3.302 1.016) (xy 3.302 -1.016) (xy 1.778 0) (xy 3.302 1.016)
					)
					(stroke
						(width 0.254)
						(type default)
					)
					(fill
						(type outline)
					)
				)
				(pin passive line
					(at 0 0 0)
					(length 0.635)
					(name "C"
						(effects
							(font
								(size 1.27 1.27)
							)
						)
					)
					(number "1"
						(effects
							(font
								(size 1.27 1.27)
							)
						)
					)
				)
				(pin passive line
					(at 5.08 0 180)
					(length 0.635)
					(name "A"
						(effects
							(font
								(size 1.27 1.27)
							)
						)
					)
					(number "2"
						(effects
							(font
								(size 1.27 1.27)
							)
						)
					)
				)
			)
		)
	(symbol "antmicroTemperatureSensorsAnalogandDigitalOutput:MAX31740ATA+T"
			(exclude_from_sim no)
			(in_bom yes)
			(on_board yes)
			(property "Reference" "U"
				(at 35.56 -2.54 0)
				(effects
					(font
						(size 1.27 1.27)
						(thickness 0.15)
					)
					(justify left bottom)
				)
			)
			(property "Value" "MAX31740ATA+T"
				(at 35.56 -7.62 0)
				(effects
					(font
						(size 1.27 1.27)
						(thickness 0.15)
					)
					(justify left bottom)
					(hide yes)
				)
			)
			(property "Footprint" "antmicro-footprints:TDFN-8-1EP_2x3x0.75mm_P0.5mm_EP1.75x1.63mm"
				(at 35.56 -10.16 0)
				(effects
					(font
						(size 1.27 1.27)
						(thickness 0.15)
					)
					(justify left bottom)
					(hide yes)
				)
			)
			(property "Datasheet" "https://www.analog.com/media/en/technical-documentation/data-sheets/max31740.pdf"
				(at 35.56 -12.7 0)
				(effects
					(font
						(size 1.27 1.27)
						(thickness 0.15)
					)
					(justify left bottom)
					(hide yes)
				)
			)
			(property "Description" "Pwm fan speed controller, temperature measurement, Control speed of 2-, 3-, 4- Wire Fans"
				(at 35.56 -22.86 0)
				(effects
					(font
						(size 1.27 1.27)
					)
					(justify left bottom)
					(hide yes)
				)
			)
			(property "MPN" "MAX31740ATA+T"
				(at 35.56 -5.08 0)
				(effects
					(font
						(size 1.27 1.27)
						(thickness 0.15)
					)
					(justify left bottom)
				)
			)
			(property "Manufacturer" "Analog Devices"
				(at 35.56 -15.24 0)
				(effects
					(font
						(size 1.27 1.27)
						(thickness 0.15)
					)
					(justify left bottom)
					(hide yes)
				)
			)
			(property "Author" "Antmicro"
				(at 35.56 -17.78 0)
				(effects
					(font
						(size 1.27 1.27)
						(thickness 0.15)
					)
					(justify left bottom)
					(hide yes)
				)
			)
			(property "License" "Apache-2.0"
				(at 35.56 -20.32 0)
				(effects
					(font
						(size 1.27 1.27)
						(thickness 0.15)
					)
					(justify left bottom)
					(hide yes)
				)
			)
			(property "ki_keywords" "SENSOR, IC, SMT"
				(at 0 0 0)
				(effects
					(font
						(size 1.27 1.27)
					)
					(hide yes)
				)
			)
			(symbol "MAX31740ATA+T_1_1"
				(rectangle
					(start 2.54 2.54)
					(end 20.32 -17.78)
					(stroke
						(width 0.254)
						(type default)
					)
					(fill
						(type background)
					)
				)
				(pin power_in line
					(at 0 0 0)
					(length 2.54)
					(name "VDD"
						(effects
							(font
								(size 1.27 1.27)
							)
						)
					)
					(number "8"
						(effects
							(font
								(size 1.27 1.27)
							)
						)
					)
				)
				(pin passive line
					(at 0 -5.08 0)
					(length 2.54)
					(name "SENSE"
						(effects
							(font
								(size 1.27 1.27)
							)
						)
					)
					(number "3"
						(effects
							(font
								(size 1.27 1.27)
							)
						)
					)
				)
				(pin passive line
					(at 0 -12.7 0)
					(length 2.54)
					(name "DMIN"
						(effects
							(font
								(size 1.27 1.27)
							)
						)
					)
					(number "1"
						(effects
							(font
								(size 1.27 1.27)
							)
						)
					)
				)
				(pin passive line
					(at 0 -15.24 0)
					(length 2.54)
					(name "D0"
						(effects
							(font
								(size 1.27 1.27)
							)
						)
					)
					(number "6"
						(effects
							(font
								(size 1.27 1.27)
							)
						)
					)
				)
				(pin output line
					(at 22.86 0 180)
					(length 2.54)
					(name "PWM_OUT"
						(effects
							(font
								(size 1.27 1.27)
							)
						)
					)
					(number "7"
						(effects
							(font
								(size 1.27 1.27)
							)
						)
					)
				)
				(pin passive line
					(at 22.86 -5.08 180)
					(length 2.54)
					(name "FREQ"
						(effects
							(font
								(size 1.27 1.27)
							)
						)
					)
					(number "5"
						(effects
							(font
								(size 1.27 1.27)
							)
						)
					)
				)
				(pin passive line
					(at 22.86 -7.62 180)
					(length 2.54)
					(name "SLOPE"
						(effects
							(font
								(size 1.27 1.27)
							)
						)
					)
					(number "2"
						(effects
							(font
								(size 1.27 1.27)
							)
						)
					)
				)
				(pin power_in line
					(at 22.86 -12.7 180)
					(length 2.54)
					(name "EP"
						(effects
							(font
								(size 1.27 1.27)
							)
						)
					)
					(number "9"
						(effects
							(font
								(size 1.27 1.27)
							)
						)
					)
				)
				(pin power_in line
					(at 22.86 -15.24 180)
					(length 2.54)
					(name "GND"
						(effects
							(font
								(size 1.27 1.27)
							)
						)
					)
					(number "4"
						(effects
							(font
								(size 1.27 1.27)
							)
						)
					)
				)
			)
		)
	(symbol "antmicroTemperatureSensorsAnalogandDigitalOutput:RT_NTC_10k_0402"
			(pin_numbers
				(hide yes)
			)
			(pin_names
				(hide yes)
			)
			(exclude_from_sim no)
			(in_bom yes)
			(on_board yes)
			(property "Reference" "RT"
				(at 20.32 -5.08 0)
				(effects
					(font
						(size 1.27 1.27)
						(thickness 0.15)
					)
					(justify left bottom)
				)
			)
			(property "Value" "RT_NTC_10k_0402"
				(at 20.32 -10.16 0)
				(effects
					(font
						(size 1.27 1.27)
						(thickness 0.15)
					)
					(justify left bottom)
					(hide yes)
				)
			)
			(property "Footprint" "antmicro-footprints:R_0402_1005Metric"
				(at 20.32 -15.24 0)
				(effects
					(font
						(size 1.27 1.27)
						(thickness 0.15)
					)
					(justify left bottom)
					(hide yes)
				)
			)
			(property "Datasheet" "https://eu.mouser.com/datasheet/2/281/r44e-522712.pdf"
				(at 20.32 -17.78 0)
				(effects
					(font
						(size 1.27 1.27)
						(thickness 0.15)
					)
					(justify left bottom)
					(hide yes)
				)
			)
			(property "Description" "10k NTC in 0402 package with 5V max voltage"
				(at 20.32 -30.48 0)
				(effects
					(font
						(size 1.27 1.27)
					)
					(justify left bottom)
					(hide yes)
				)
			)
			(property "MPN" "NCP15XH103F03RC"
				(at 20.32 -22.86 0)
				(effects
					(font
						(size 1.27 1.27)
					)
					(justify left bottom)
					(hide yes)
				)
			)
			(property "Manufacturer" "Murata"
				(at 20.32 -20.32 0)
				(effects
					(font
						(size 1.27 1.27)
					)
					(justify left bottom)
					(hide yes)
				)
			)
			(property "License" "Apache-2.0"
				(at 20.32 -27.94 0)
				(effects
					(font
						(size 1.27 1.27)
					)
					(justify left bottom)
					(hide yes)
				)
			)
			(property "Author" "Antmicro"
				(at 20.32 -25.4 0)
				(effects
					(font
						(size 1.27 1.27)
					)
					(justify left bottom)
					(hide yes)
				)
			)
			(property "Val" "10k"
				(at 20.32 -7.62 0)
				(effects
					(font
						(size 1.27 1.27)
					)
					(justify left bottom)
				)
			)
			(property "Voltage" "5V"
				(at 20.32 -12.7 0)
				(effects
					(font
						(size 1.27 1.27)
					)
					(justify left bottom)
					(hide yes)
				)
			)
			(property "ki_keywords" "THERMISTOR, NTC"
				(at 0 0 0)
				(effects
					(font
						(size 1.27 1.27)
					)
					(hide yes)
				)
			)
			(symbol "RT_NTC_10k_0402_0_1"
				(rectangle
					(start 0.635 0.889)
					(end 4.445 -0.889)
					(stroke
						(width 0.254)
						(type default)
					)
					(fill
						(type none)
					)
				)
			)
			(symbol "RT_NTC_10k_0402_1_1"
				(polyline
					(pts
						(xy 4.318 1.524) (xy 1.27 -1.524) (xy 0.508 -1.524)
					)
					(stroke
						(width 0.254)
						(type default)
					)
					(fill
						(type none)
					)
				)
				(pin passive line
					(at 0 0 0)
					(length 0.635)
					(name "~"
						(effects
							(font
								(size 1.27 1.27)
							)
						)
					)
					(number "1"
						(effects
							(font
								(size 1.27 1.27)
							)
						)
					)
				)
				(pin passive line
					(at 5.08 0 180)
					(length 0.635)
					(name "~"
						(effects
							(font
								(size 1.27 1.27)
							)
						)
					)
					(number "2"
						(effects
							(font
								(size 1.27 1.27)
							)
						)
					)
				)
			)
		)
	(symbol "antmicroTestPoints:TP_0.75mm_SMD"
			(pin_names
				(hide yes)
			)
			(exclude_from_sim no)
			(in_bom no)
			(on_board yes)
			(property "Reference" "TP"
				(at 10.16 -1.27 0)
				(effects
					(font
						(size 1.27 1.27)
						(thickness 0.15)
					)
					(justify left bottom)
				)
			)
			(property "Value" "TP_0.75mm_SMD"
				(at 10.16 -3.81 0)
				(effects
					(font
						(size 1.27 1.27)
						(thickness 0.15)
					)
					(justify left bottom)
					(hide yes)
				)
			)
			(property "Footprint" "antmicro-footprints:TP_SMD_0.75mm"
				(at 10.16 -6.35 0)
				(effects
					(font
						(size 1.27 1.27)
						(thickness 0.15)
					)
					(justify left bottom)
					(hide yes)
				)
			)
			(property "Datasheet" ""
				(at 17.78 -12.7 0)
				(effects
					(font
						(size 1.27 1.27)
						(thickness 0.15)
					)
					(justify left bottom)
					(hide yes)
				)
			)
			(property "Description" "SMT test point"
				(at 10.795 -13.97 0)
				(effects
					(font
						(size 1.27 1.27)
					)
					(justify left bottom)
					(hide yes)
				)
			)
			(property "MPN" ""
				(at 10.795 -11.43 0)
				(effects
					(font
						(size 1.27 1.27)
						(thickness 0.15)
					)
					(justify left bottom)
					(hide yes)
				)
			)
			(property "Manufacturer" ""
				(at 10.795 -6.35 0)
				(effects
					(font
						(size 1.27 1.27)
						(thickness 0.15)
					)
					(justify left bottom)
					(hide yes)
				)
			)
			(property "Author" "Antmicro"
				(at 10.16 -8.89 0)
				(effects
					(font
						(size 1.27 1.27)
						(thickness 0.15)
					)
					(justify left bottom)
					(hide yes)
				)
			)
			(property "License" "Apache-2.0"
				(at 10.16 -11.43 0)
				(effects
					(font
						(size 1.27 1.27)
						(thickness 0.15)
					)
					(justify left bottom)
					(hide yes)
				)
			)
			(property "ki_keywords" "TESTPOINT"
				(at 0 0 0)
				(effects
					(font
						(size 1.27 1.27)
					)
					(hide yes)
				)
			)
			(symbol "TP_0.75mm_SMD_1_1"
				(circle
					(center 3.175 0)
					(radius 0.635)
					(stroke
						(width 0.254)
						(type default)
					)
					(fill
						(type none)
					)
				)
				(pin passive line
					(at 0 0 0)
					(length 2.54)
					(name "1"
						(effects
							(font
								(size 1.27 1.27)
							)
						)
					)
					(number "1"
						(effects
							(font
								(size 1.27 1.27)
							)
						)
					)
				)
			)
		)
	(symbol "antmicroTestPoints:Tag-Connect_TC2050-IDC-NL_2x5_P1.27mm"
			(exclude_from_sim no)
			(in_bom no)
			(on_board yes)
			(property "Reference" "J"
				(at 39.37 -1.27 0)
				(effects
					(font
						(size 1.27 1.27)
						(thickness 0.15)
					)
					(justify left bottom)
				)
			)
			(property "Value" "Tag-Connect_TC2050-IDC-NL_2x5_P1.27mm"
				(at 39.37 -3.81 0)
				(effects
					(font
						(size 1.27 1.27)
						(thickness 0.15)
					)
					(justify left bottom)
					(hide yes)
				)
			)
			(property "Footprint" "antmicro-footprints:Tag-Connect_TC2050-IDC-NL_2x5_P1.27mm"
				(at 39.37 -6.35 0)
				(effects
					(font
						(size 1.27 1.27)
						(thickness 0.15)
					)
					(justify left bottom)
					(hide yes)
				)
			)
			(property "Datasheet" "https://www.tag-connect.com/wp-content/uploads/bsk-pdf-manager/TC2050-IDC-NL_Datasheet_8.pdf"
				(at 39.37 -8.89 0)
				(effects
					(font
						(size 1.27 1.27)
						(thickness 0.15)
					)
					(justify left bottom)
					(hide yes)
				)
			)
			(property "Description" "Tag Connect 2x5 1.27mm terminal"
				(at 39.37 -21.59 0)
				(effects
					(font
						(size 1.27 1.27)
					)
					(justify left bottom)
					(hide yes)
				)
			)
			(property "MPN" "TC2050-IDC-NL"
				(at 39.37 -11.43 0)
				(effects
					(font
						(size 1.27 1.27)
						(thickness 0.15)
					)
					(justify left bottom)
				)
			)
			(property "Manufacturer" "Tag Connect"
				(at 39.37 -13.97 0)
				(effects
					(font
						(size 1.27 1.27)
						(thickness 0.15)
					)
					(justify left bottom)
					(hide yes)
				)
			)
			(property "Author" "Antmicro"
				(at 39.37 -16.51 0)
				(effects
					(font
						(size 1.27 1.27)
						(thickness 0.15)
					)
					(justify left bottom)
					(hide yes)
				)
			)
			(property "License" "Apache-2.0"
				(at 39.37 -19.05 0)
				(effects
					(font
						(size 1.27 1.27)
						(thickness 0.15)
					)
					(justify left bottom)
					(hide yes)
				)
			)
			(property "ki_keywords" "POGO-PIN, CONNECTOR"
				(at 0 0 0)
				(effects
					(font
						(size 1.27 1.27)
					)
					(hide yes)
				)
			)
			(symbol "Tag-Connect_TC2050-IDC-NL_2x5_P1.27mm_1_1"
				(rectangle
					(start 2.54 2.54)
					(end 29.21 -12.7)
					(stroke
						(width 0)
						(type default)
					)
					(fill
						(type background)
					)
				)
				(circle
					(center 15.113 -7.5184)
					(radius 0.4572)
					(stroke
						(width 0)
						(type default)
					)
					(fill
						(type none)
					)
				)
				(polyline
					(pts
						(xy 15.24 -8.636) (xy 17.145 -8.636) (xy 17.78 -8.001) (xy 17.78 -2.921) (xy 16.51 -1.016) (xy 15.24 -1.016)
						(xy 13.97 -2.921) (xy 13.97 -8.001) (xy 14.605 -8.636) (xy 15.24 -8.636)
					)
					(stroke
						(width 0)
						(type default)
					)
					(fill
						(type none)
					)
				)
				(circle
					(center 15.367 -3.4544)
					(radius 0.2032)
					(stroke
						(width 0)
						(type default)
					)
					(fill
						(type outline)
					)
				)
				(circle
					(center 15.367 -4.1656)
					(radius 0.2032)
					(stroke
						(width 0)
						(type default)
					)
					(fill
						(type outline)
					)
				)
				(circle
					(center 15.367 -4.9276)
					(radius 0.2032)
					(stroke
						(width 0)
						(type default)
					)
					(fill
						(type outline)
					)
				)
				(circle
					(center 15.367 -5.6388)
					(radius 0.2032)
					(stroke
						(width 0)
						(type default)
					)
					(fill
						(type outline)
					)
				)
				(circle
					(center 15.367 -6.4008)
					(radius 0.2032)
					(stroke
						(width 0)
						(type default)
					)
					(fill
						(type outline)
					)
				)
				(circle
					(center 15.875 -2.1336)
					(radius 0.4572)
					(stroke
						(width 0)
						(type default)
					)
					(fill
						(type none)
					)
				)
				(circle
					(center 16.383 -3.4544)
					(radius 0.2032)
					(stroke
						(width 0)
						(type default)
					)
					(fill
						(type outline)
					)
				)
				(circle
					(center 16.383 -4.1656)
					(radius 0.2032)
					(stroke
						(width 0)
						(type default)
					)
					(fill
						(type outline)
					)
				)
				(circle
					(center 16.383 -4.9276)
					(radius 0.2032)
					(stroke
						(width 0)
						(type default)
					)
					(fill
						(type outline)
					)
				)
				(circle
					(center 16.383 -5.6388)
					(radius 0.2032)
					(stroke
						(width 0)
						(type default)
					)
					(fill
						(type outline)
					)
				)
				(circle
					(center 16.383 -6.4008)
					(radius 0.2032)
					(stroke
						(width 0)
						(type default)
					)
					(fill
						(type outline)
					)
				)
				(circle
					(center 16.7386 -7.5184)
					(radius 0.4572)
					(stroke
						(width 0)
						(type default)
					)
					(fill
						(type none)
					)
				)
				(text "Tag-Connect"
					(at 15.875 1.651 0)
					(effects
						(font
							(size 0.7 0.7)
						)
					)
				)
				(text "ALT: 3.3V I2C/JTAG/SPI/SWD/FTDI"
					(at 16.002 -11.938 0)
					(effects
						(font
							(size 0.7 0.7)
						)
					)
				)
				(pin passive line
					(at 0 0 0)
					(length 2.54)
					(name "1"
						(effects
							(font
								(size 1.27 1.27)
							)
						)
					)
					(number "1"
						(effects
							(font
								(size 1.27 1.27)
							)
						)
					)
					(alternate "3V3" passive line)
				)
				(pin passive line
					(at 0 -2.54 0)
					(length 2.54)
					(name "2"
						(effects
							(font
								(size 1.27 1.27)
							)
						)
					)
					(number "2"
						(effects
							(font
								(size 1.27 1.27)
							)
						)
					)
					(alternate "ADBUS3" passive line)
					(alternate "I2C_NC" passive line)
					(alternate "JTAG_TMS" passive line)
					(alternate "SPI_CS" passive line)
					(alternate "SWD_NC" passive line)
				)
				(pin passive line
					(at 0 -5.08 0)
					(length 2.54)
					(name "3"
						(effects
							(font
								(size 1.27 1.27)
							)
						)
					)
					(number "3"
						(effects
							(font
								(size 1.27 1.27)
							)
						)
					)
					(alternate "GND" passive line)
				)
				(pin passive line
					(at 0 -7.62 0)
					(length 2.54)
					(name "4"
						(effects
							(font
								(size 1.27 1.27)
							)
						)
					)
					(number "4"
						(effects
							(font
								(size 1.27 1.27)
							)
						)
					)
					(alternate "ADBUS0" passive line)
					(alternate "I2C_SCL" passive line)
					(alternate "JTAG_TCK" passive line)
					(alternate "SPI_SCK" passive line)
					(alternate "SWD_CLK" passive line)
				)
				(pin passive line
					(at 0 -10.16 0)
					(length 2.54)
					(name "5"
						(effects
							(font
								(size 1.27 1.27)
							)
						)
					)
					(number "5"
						(effects
							(font
								(size 1.27 1.27)
							)
						)
					)
					(alternate "GND" passive line)
				)
				(pin passive line
					(at 31.75 0 180)
					(length 2.54)
					(name "10"
						(effects
							(font
								(size 1.27 1.27)
							)
						)
					)
					(number "10"
						(effects
							(font
								(size 1.27 1.27)
							)
						)
					)
					(alternate "ADBUS5" passive line)
					(alternate "I2C_NC" passive line)
					(alternate "JTAG_~{RESET}" passive line)
					(alternate "SPI_NC" passive line)
					(alternate "SWD_NC" passive line)
				)
				(pin passive line
					(at 31.75 -2.54 180)
					(length 2.54)
					(name "9"
						(effects
							(font
								(size 1.27 1.27)
							)
						)
					)
					(number "9"
						(effects
							(font
								(size 1.27 1.27)
							)
						)
					)
					(alternate "GND" passive line)
				)
				(pin passive line
					(at 31.75 -5.08 180)
					(length 2.54)
					(name "8"
						(effects
							(font
								(size 1.27 1.27)
							)
						)
					)
					(number "8"
						(effects
							(font
								(size 1.27 1.27)
							)
						)
					)
					(alternate "ADBUS1" passive line)
					(alternate "I2C_SDA" passive line)
					(alternate "JTAG_TDI" passive line)
					(alternate "SPI_MOSI" passive line)
					(alternate "SWD_IO" passive line)
				)
				(pin passive line
					(at 31.75 -7.62 180)
					(length 2.54)
					(name "7"
						(effects
							(font
								(size 1.27 1.27)
							)
						)
					)
					(number "7"
						(effects
							(font
								(size 1.27 1.27)
							)
						)
					)
					(alternate "NC" no_connect line)
				)
				(pin passive line
					(at 31.75 -10.16 180)
					(length 2.54)
					(name "6"
						(effects
							(font
								(size 1.27 1.27)
							)
						)
					)
					(number "6"
						(effects
							(font
								(size 1.27 1.27)
							)
						)
					)
					(alternate "ADBUS2" passive line)
					(alternate "I2C_SDA" passive line)
					(alternate "JTAG_TDO" passive line)
					(alternate "SPI_MISO" passive line)
					(alternate "SWD_IO" passive line)
				)
			)
		)
	(symbol "antmicroTransistorsBipolarSingle:BC817-25W"
			(pin_names
				(offset 0)
				(hide yes)
			)
			(exclude_from_sim no)
			(in_bom yes)
			(on_board yes)
			(property "Reference" "Q"
				(at 22.86 0 0)
				(effects
					(font
						(size 1.27 1.27)
						(thickness 0.15)
					)
					(justify left bottom)
				)
			)
			(property "Value" "BC817-25W"
				(at 22.86 -2.54 0)
				(effects
					(font
						(size 1.27 1.27)
						(thickness 0.15)
					)
					(justify left bottom)
					(hide yes)
				)
			)
			(property "Footprint" "antmicro-footprints:SOT-323"
				(at 22.86 -5.08 0)
				(effects
					(font
						(size 1.27 1.27)
						(thickness 0.15)
					)
					(justify left bottom)
					(hide yes)
				)
			)
			(property "Datasheet" "https://assets.nexperia.com/documents/data-sheet/BC817W_SER.pdf"
				(at 22.86 -7.62 0)
				(effects
					(font
						(size 1.27 1.27)
						(thickness 0.15)
					)
					(justify left bottom)
					(hide yes)
				)
			)
			(property "Description" "Bipolar (BJT) Single Transistor, NPN, 45 V, 500 mA, 200 mW, SOT-323, Surface Mount"
				(at 22.86 -20.32 0)
				(effects
					(font
						(size 1.27 1.27)
					)
					(justify left bottom)
					(hide yes)
				)
			)
			(property "MPN" "BC817-25W,115"
				(at 22.86 -10.16 0)
				(effects
					(font
						(size 1.27 1.27)
						(thickness 0.15)
					)
					(justify left bottom)
				)
			)
			(property "Manufacturer" "Nexperia"
				(at 22.86 -12.7 0)
				(effects
					(font
						(size 1.27 1.27)
						(thickness 0.15)
					)
					(justify left bottom)
					(hide yes)
				)
			)
			(property "Author" "Antmicro"
				(at 22.86 -15.24 0)
				(effects
					(font
						(size 1.27 1.27)
						(thickness 0.15)
					)
					(justify left bottom)
					(hide yes)
				)
			)
			(property "License" "Apache-2.0"
				(at 22.86 -17.78 0)
				(effects
					(font
						(size 1.27 1.27)
						(thickness 0.15)
					)
					(justify left bottom)
					(hide yes)
				)
			)
			(property "ki_keywords" "SMT, TRANSISTOR, SEMICONDUCTOR, BIPOLAR"
				(at 0 0 0)
				(effects
					(font
						(size 1.27 1.27)
					)
					(hide yes)
				)
			)
			(property "ki_fp_filters" "SOT?323*"
				(at 0 0 0)
				(effects
					(font
						(size 1.27 1.27)
					)
					(hide yes)
				)
			)
			(symbol "BC817-25W_0_1"
				(polyline
					(pts
						(xy 2.54 0) (xy 4.445 0)
					)
					(stroke
						(width 0)
						(type default)
					)
					(fill
						(type none)
					)
				)
				(polyline
					(pts
						(xy 4.445 1.905) (xy 4.445 -1.905) (xy 4.445 -1.905)
					)
					(stroke
						(width 0.508)
						(type default)
					)
					(fill
						(type none)
					)
				)
				(polyline
					(pts
						(xy 4.445 0.635) (xy 6.35 2.54)
					)
					(stroke
						(width 0)
						(type default)
					)
					(fill
						(type none)
					)
				)
				(polyline
					(pts
						(xy 4.445 -0.635) (xy 6.35 -2.54) (xy 6.35 -2.54)
					)
					(stroke
						(width 0)
						(type default)
					)
					(fill
						(type none)
					)
				)
				(circle
					(center 5.08 0)
					(radius 2.8194)
					(stroke
						(width 0.254)
						(type default)
					)
					(fill
						(type none)
					)
				)
				(polyline
					(pts
						(xy 5.08 -1.778) (xy 5.588 -1.27) (xy 6.096 -2.286) (xy 5.08 -1.778) (xy 5.08 -1.778)
					)
					(stroke
						(width 0)
						(type default)
					)
					(fill
						(type outline)
					)
				)
			)
			(symbol "BC817-25W_1_1"
				(pin input line
					(at 0 0 0)
					(length 2.54)
					(name "B"
						(effects
							(font
								(size 1.27 1.27)
							)
						)
					)
					(number "1"
						(effects
							(font
								(size 1.27 1.27)
							)
						)
					)
				)
				(pin passive line
					(at 6.35 5.08 270)
					(length 2.54)
					(name "C"
						(effects
							(font
								(size 1.27 1.27)
							)
						)
					)
					(number "3"
						(effects
							(font
								(size 1.27 1.27)
							)
						)
					)
				)
				(pin passive line
					(at 6.35 -5.08 90)
					(length 2.54)
					(name "E"
						(effects
							(font
								(size 1.27 1.27)
							)
						)
					)
					(number "2"
						(effects
							(font
								(size 1.27 1.27)
							)
						)
					)
				)
			)
		)
	(symbol "antmicroTransistorsBipolarSingle:DTC014T_SOT-416"
			(pin_names
				(offset 0)
			)
			(exclude_from_sim no)
			(in_bom yes)
			(on_board yes)
			(property "Reference" "Q"
				(at 25.4 -5.08 0)
				(effects
					(font
						(size 1.27 1.27)
						(thickness 0.15)
					)
					(justify left bottom)
				)
			)
			(property "Value" "DTC014T_SOT-416"
				(at 25.4 -7.62 0)
				(effects
					(font
						(size 1.27 1.27)
						(thickness 0.15)
					)
					(justify left bottom)
					(hide yes)
				)
			)
			(property "Footprint" "antmicro-footprints:SOT-416"
				(at 25.4 -10.16 0)
				(effects
					(font
						(size 1.27 1.27)
						(thickness 0.15)
					)
					(justify left bottom)
					(hide yes)
				)
			)
			(property "Datasheet" "https://www.rohm.com/datasheet?p=DTC014TEB&dist=Mouser&media=referral&source=mouser.com&campaign=Mouser"
				(at 25.4 -12.7 0)
				(effects
					(font
						(size 1.27 1.27)
						(thickness 0.15)
					)
					(justify left bottom)
					(hide yes)
				)
			)
			(property "Description" "Bipolar (BJT) Single Transistor with built-in base resistor, NPN, 50V, 100mA, 150mW, SOT-416FL, Surface Mount"
				(at 25.4 -25.4 0)
				(effects
					(font
						(size 1.27 1.27)
					)
					(justify left bottom)
					(hide yes)
				)
			)
			(property "Manufacturer" "ROHM Semiconductor"
				(at 25.4 -15.24 0)
				(effects
					(font
						(size 1.27 1.27)
						(thickness 0.15)
					)
					(justify left bottom)
					(hide yes)
				)
			)
			(property "MPN" "DTC014TEBTL"
				(at 25.4 -17.78 0)
				(effects
					(font
						(size 1.27 1.27)
						(thickness 0.15)
					)
					(justify left bottom)
				)
			)
			(property "Author" "Antmicro"
				(at 25.4 -20.32 0)
				(effects
					(font
						(size 1.27 1.27)
						(thickness 0.15)
					)
					(justify left bottom)
					(hide yes)
				)
			)
			(property "License" "Apache-2.0"
				(at 25.4 -22.86 0)
				(effects
					(font
						(size 1.27 1.27)
						(thickness 0.15)
					)
					(justify left bottom)
					(hide yes)
				)
			)
			(property "ki_keywords" "SMT, TRANSISTOR, SEMICONDUCTOR, BIPOLAR, NPN"
				(at 0 0 0)
				(effects
					(font
						(size 1.27 1.27)
					)
					(hide yes)
				)
			)
			(symbol "DTC014T_SOT-416_0_1"
				(polyline
					(pts
						(xy 2.54 0) (xy 3.175 0)
					)
					(stroke
						(width 0.254)
						(type default)
					)
					(fill
						(type none)
					)
				)
				(polyline
					(pts
						(xy 5.08 0) (xy 5.588 0)
					)
					(stroke
						(width 0.254)
						(type default)
					)
					(fill
						(type none)
					)
				)
				(circle
					(center 5.588 0)
					(radius 3.2528)
					(stroke
						(width 0.254)
						(type default)
					)
					(fill
						(type background)
					)
				)
				(polyline
					(pts
						(xy 5.715 1.905) (xy 5.715 -1.905) (xy 5.715 -1.905)
					)
					(stroke
						(width 0.508)
						(type default)
					)
					(fill
						(type none)
					)
				)
				(polyline
					(pts
						(xy 5.715 0.635) (xy 7.62 2.54)
					)
					(stroke
						(width 0.254)
						(type default)
					)
					(fill
						(type none)
					)
				)
				(polyline
					(pts
						(xy 5.715 -0.635) (xy 7.62 -2.54) (xy 7.62 -2.54)
					)
					(stroke
						(width 0.254)
						(type default)
					)
					(fill
						(type none)
					)
				)
				(polyline
					(pts
						(xy 6.35 -1.778) (xy 6.858 -1.27) (xy 7.366 -2.286) (xy 6.35 -1.778) (xy 6.35 -1.778)
					)
					(stroke
						(width 0)
						(type default)
					)
					(fill
						(type outline)
					)
				)
			)
			(symbol "DTC014T_SOT-416_1_1"
				(rectangle
					(start 3.302 0.381)
					(end 4.953 -0.381)
					(stroke
						(width 0.254)
						(type default)
					)
					(fill
						(type none)
					)
				)
				(text "10k"
					(at 3.302 0.508 0)
					(effects
						(font
							(size 0.635 0.635)
							(thickness 0.15)
						)
						(justify left bottom)
					)
				)
				(pin input line
					(at 0 0 0)
					(length 2.54)
					(name "B"
						(effects
							(font
								(size 1.27 1.27)
							)
						)
					)
					(number "1"
						(effects
							(font
								(size 1.27 1.27)
							)
						)
					)
				)
				(pin passive line
					(at 7.62 5.08 270)
					(length 2.54)
					(name "C"
						(effects
							(font
								(size 1.27 1.27)
							)
						)
					)
					(number "3"
						(effects
							(font
								(size 1.27 1.27)
							)
						)
					)
				)
				(pin passive line
					(at 7.62 -5.08 90)
					(length 2.54)
					(name "E"
						(effects
							(font
								(size 1.27 1.27)
							)
						)
					)
					(number "2"
						(effects
							(font
								(size 1.27 1.27)
							)
						)
					)
				)
			)
		)
	(symbol "antmicroTransistorsFETsMOSFETsSingle:2N7002_SOT-23-3"
			(pin_names
				(offset 0)
			)
			(exclude_from_sim no)
			(in_bom yes)
			(on_board yes)
			(property "Reference" "Q"
				(at 22.86 -5.08 0)
				(effects
					(font
						(size 1.27 1.27)
						(thickness 0.15)
					)
					(justify left bottom)
				)
			)
			(property "Value" "2N7002_SOT-23-3"
				(at 22.86 -7.62 0)
				(effects
					(font
						(size 1.27 1.27)
						(thickness 0.15)
					)
					(justify left bottom)
					(hide yes)
				)
			)
			(property "Footprint" "antmicro-footprints:SOT-23-3"
				(at 22.86 -10.16 0)
				(effects
					(font
						(size 1.27 1.27)
						(thickness 0.15)
					)
					(justify left bottom)
					(hide yes)
				)
			)
			(property "Datasheet" "https://www.onsemi.com/pub/Collateral/NDS7002A-D.PDF"
				(at 22.86 -12.7 0)
				(effects
					(font
						(size 1.27 1.27)
						(thickness 0.15)
					)
					(justify left bottom)
					(hide yes)
				)
			)
			(property "Description" "Power MOSFET, N Channel, 60 V, 115 mA, 1.2 ohm, SOT-23, Surface Mount"
				(at 22.86 -25.4 0)
				(effects
					(font
						(size 1.27 1.27)
					)
					(justify left bottom)
					(hide yes)
				)
			)
			(property "MPN" "2N7002"
				(at 22.86 -15.24 0)
				(effects
					(font
						(size 1.27 1.27)
						(thickness 0.15)
					)
					(justify left bottom)
				)
			)
			(property "Manufacturer" "ON Semiconductor"
				(at 22.86 -17.78 0)
				(effects
					(font
						(size 1.27 1.27)
						(thickness 0.15)
					)
					(justify left bottom)
					(hide yes)
				)
			)
			(property "Author" "Antmicro"
				(at 22.86 -20.32 0)
				(effects
					(font
						(size 1.27 1.27)
						(thickness 0.15)
					)
					(justify left bottom)
					(hide yes)
				)
			)
			(property "License" "Apache-2.0"
				(at 22.86 -22.86 0)
				(effects
					(font
						(size 1.27 1.27)
						(thickness 0.15)
					)
					(justify left bottom)
					(hide yes)
				)
			)
			(property "ki_keywords" "SMT, TRANSISTOR, SEMICONDUCTOR, NMOS"
				(at 0 0 0)
				(effects
					(font
						(size 1.27 1.27)
					)
					(hide yes)
				)
			)
			(symbol "2N7002_SOT-23-3_1_1"
				(polyline
					(pts
						(xy 2.54 0) (xy 4.572 0) (xy 4.572 3.937)
					)
					(stroke
						(width 0.254)
						(type default)
					)
					(fill
						(type none)
					)
				)
				(polyline
					(pts
						(xy 5.08 4.445) (xy 5.08 3.429)
					)
					(stroke
						(width 0.254)
						(type default)
					)
					(fill
						(type background)
					)
				)
				(polyline
					(pts
						(xy 5.08 2.54) (xy 5.08 3.048)
					)
					(stroke
						(width 0.254)
						(type default)
					)
					(fill
						(type background)
					)
				)
				(polyline
					(pts
						(xy 5.08 2.54) (xy 5.08 2.032)
					)
					(stroke
						(width 0.254)
						(type default)
					)
					(fill
						(type background)
					)
				)
				(polyline
					(pts
						(xy 5.08 2.54) (xy 5.842 3.048) (xy 5.842 2.032) (xy 5.08 2.54)
					)
					(stroke
						(width 0.254)
						(type default)
					)
					(fill
						(type outline)
					)
				)
				(polyline
					(pts
						(xy 5.08 1.143) (xy 5.08 1.651)
					)
					(stroke
						(width 0.254)
						(type default)
					)
					(fill
						(type background)
					)
				)
				(polyline
					(pts
						(xy 5.08 1.143) (xy 5.08 0.635)
					)
					(stroke
						(width 0.254)
						(type default)
					)
					(fill
						(type background)
					)
				)
				(circle
					(center 6.35 2.54)
					(radius 3.302)
					(stroke
						(width 0.254)
						(type default)
					)
					(fill
						(type background)
					)
				)
				(polyline
					(pts
						(xy 7.493 0.635) (xy 8.636 0.635) (xy 8.636 3.937) (xy 8.636 4.445) (xy 7.493 4.445)
					)
					(stroke
						(width 0.254)
						(type default)
					)
					(fill
						(type background)
					)
				)
				(polyline
					(pts
						(xy 7.62 6.35) (xy 7.62 3.937) (xy 5.08 3.937)
					)
					(stroke
						(width 0.254)
						(type default)
					)
					(fill
						(type none)
					)
				)
				(circle
					(center 7.62 4.445)
					(radius 0.127)
					(stroke
						(width 0.254)
						(type default)
					)
					(fill
						(type background)
					)
				)
				(polyline
					(pts
						(xy 7.62 1.143) (xy 5.08 1.143)
					)
					(stroke
						(width 0.254)
						(type default)
					)
					(fill
						(type background)
					)
				)
				(circle
					(center 7.62 1.143)
					(radius 0.127)
					(stroke
						(width 0.254)
						(type default)
					)
					(fill
						(type background)
					)
				)
				(circle
					(center 7.62 0.635)
					(radius 0.127)
					(stroke
						(width 0.254)
						(type default)
					)
					(fill
						(type background)
					)
				)
				(polyline
					(pts
						(xy 7.62 -1.27) (xy 7.62 2.54) (xy 5.08 2.54)
					)
					(stroke
						(width 0.254)
						(type default)
					)
					(fill
						(type none)
					)
				)
				(polyline
					(pts
						(xy 8.636 3.048) (xy 8.128 2.286) (xy 9.144 2.286) (xy 8.636 3.048)
					)
					(stroke
						(width 0.254)
						(type default)
					)
					(fill
						(type outline)
					)
				)
				(polyline
					(pts
						(xy 9.144 3.048) (xy 8.128 3.048)
					)
					(stroke
						(width 0.254)
						(type default)
					)
					(fill
						(type background)
					)
				)
				(pin input line
					(at 0 0 0)
					(length 2.54)
					(name "G"
						(effects
							(font
								(size 1.27 1.27)
							)
						)
					)
					(number "1"
						(effects
							(font
								(size 1.27 1.27)
							)
						)
					)
				)
				(pin passive line
					(at 7.62 8.89 270)
					(length 2.54)
					(name "D"
						(effects
							(font
								(size 1.27 1.27)
							)
						)
					)
					(number "3"
						(effects
							(font
								(size 1.27 1.27)
							)
						)
					)
				)
				(pin passive line
					(at 7.62 -3.81 90)
					(length 2.54)
					(name "S"
						(effects
							(font
								(size 1.27 1.27)
							)
						)
					)
					(number "2"
						(effects
							(font
								(size 1.27 1.27)
							)
						)
					)
				)
			)
		)
	(symbol "antmicroTransistorsFETsMOSFETsSingle:SQS401EN-T1_BE3"
			(pin_names
				(offset 0)
			)
			(exclude_from_sim no)
			(in_bom yes)
			(on_board yes)
			(property "Reference" "Q"
				(at 15.24 -5.08 0)
				(effects
					(font
						(size 1.27 1.27)
						(thickness 0.15)
					)
					(justify left bottom)
				)
			)
			(property "Value" "SQS401EN-T1_BE3"
				(at 15.24 -10.16 0)
				(effects
					(font
						(size 1.27 1.27)
						(thickness 0.15)
					)
					(justify left bottom)
					(hide yes)
				)
			)
			(property "Footprint" "antmicro-footprints:Vishay_PowerPAK_1212-8_Single"
				(at 15.24 -12.7 0)
				(effects
					(font
						(size 1.27 1.27)
						(thickness 0.15)
					)
					(justify left bottom)
					(hide yes)
				)
			)
			(property "Datasheet" "https://www.vishay.com/docs/65529/sqs401en.pdf"
				(at 15.24 -15.24 0)
				(effects
					(font
						(size 1.27 1.27)
						(thickness 0.15)
					)
					(justify left bottom)
					(hide yes)
				)
			)
			(property "Description" "MOSFET, P Channel, 40 V, 16A, 0.047 ohm, PowerPAK 1212-8, Surface Mount"
				(at 15.24 -25.4 0)
				(effects
					(font
						(size 1.27 1.27)
					)
					(justify left bottom)
					(hide yes)
				)
			)
			(property "MPN" "SQS401EN-T1_BE3"
				(at 15.24 -7.62 0)
				(effects
					(font
						(size 1.27 1.27)
						(thickness 0.15)
					)
					(justify left bottom)
				)
			)
			(property "Manufacturer" "Vishay"
				(at 15.24 -17.78 0)
				(effects
					(font
						(size 1.27 1.27)
						(thickness 0.15)
					)
					(justify left bottom)
					(hide yes)
				)
			)
			(property "Author" "Antmicro"
				(at 15.24 -20.32 0)
				(effects
					(font
						(size 1.27 1.27)
						(thickness 0.15)
					)
					(justify left bottom)
					(hide yes)
				)
			)
			(property "License" "Apache-2.0"
				(at 15.24 -22.86 0)
				(effects
					(font
						(size 1.27 1.27)
						(thickness 0.15)
					)
					(justify left bottom)
					(hide yes)
				)
			)
			(property "ki_keywords" "SMT, TRANSISTOR, SEMICONDUCTOR, MOSFET, PMOS"
				(at 0 0 0)
				(effects
					(font
						(size 1.27 1.27)
					)
					(hide yes)
				)
			)
			(symbol "SQS401EN-T1_BE3_1_1"
				(polyline
					(pts
						(xy 1.27 0) (xy 3.302 0) (xy 3.302 3.937)
					)
					(stroke
						(width 0.254)
						(type default)
					)
					(fill
						(type none)
					)
				)
				(polyline
					(pts
						(xy 3.81 4.445) (xy 3.81 3.429)
					)
					(stroke
						(width 0.254)
						(type default)
					)
					(fill
						(type background)
					)
				)
				(polyline
					(pts
						(xy 3.81 2.54) (xy 3.81 3.048)
					)
					(stroke
						(width 0.254)
						(type default)
					)
					(fill
						(type background)
					)
				)
				(polyline
					(pts
						(xy 3.81 2.54) (xy 3.81 2.032)
					)
					(stroke
						(width 0.254)
						(type default)
					)
					(fill
						(type background)
					)
				)
				(polyline
					(pts
						(xy 3.81 1.143) (xy 3.81 1.651)
					)
					(stroke
						(width 0.254)
						(type default)
					)
					(fill
						(type background)
					)
				)
				(polyline
					(pts
						(xy 3.81 1.143) (xy 3.81 0.635)
					)
					(stroke
						(width 0.254)
						(type default)
					)
					(fill
						(type background)
					)
				)
				(circle
					(center 5.08 2.54)
					(radius 3.302)
					(stroke
						(width 0.254)
						(type default)
					)
					(fill
						(type background)
					)
				)
				(polyline
					(pts
						(xy 6.096 2.54) (xy 5.334 2.032) (xy 5.334 3.048) (xy 6.096 2.54)
					)
					(stroke
						(width 0.254)
						(type default)
					)
					(fill
						(type outline)
					)
				)
				(polyline
					(pts
						(xy 6.223 0.635) (xy 7.366 0.635) (xy 7.366 3.937) (xy 7.366 4.445) (xy 6.223 4.445)
					)
					(stroke
						(width 0.254)
						(type default)
					)
					(fill
						(type none)
					)
				)
				(polyline
					(pts
						(xy 6.35 6.35) (xy 6.35 3.937) (xy 3.81 3.937)
					)
					(stroke
						(width 0.254)
						(type default)
					)
					(fill
						(type none)
					)
				)
				(circle
					(center 6.35 4.445)
					(radius 0.127)
					(stroke
						(width 0.254)
						(type default)
					)
					(fill
						(type background)
					)
				)
				(polyline
					(pts
						(xy 6.35 1.143) (xy 3.81 1.143)
					)
					(stroke
						(width 0.254)
						(type default)
					)
					(fill
						(type background)
					)
				)
				(circle
					(center 6.35 1.143)
					(radius 0.127)
					(stroke
						(width 0.254)
						(type default)
					)
					(fill
						(type background)
					)
				)
				(circle
					(center 6.35 0.635)
					(radius 0.127)
					(stroke
						(width 0.254)
						(type default)
					)
					(fill
						(type background)
					)
				)
				(polyline
					(pts
						(xy 6.35 -1.27) (xy 6.35 2.54) (xy 3.81 2.54)
					)
					(stroke
						(width 0.254)
						(type default)
					)
					(fill
						(type none)
					)
				)
				(polyline
					(pts
						(xy 7.366 2.286) (xy 7.874 3.048) (xy 6.858 3.048) (xy 7.366 2.286)
					)
					(stroke
						(width 0.254)
						(type default)
					)
					(fill
						(type outline)
					)
				)
				(polyline
					(pts
						(xy 7.874 2.286) (xy 6.858 2.286)
					)
					(stroke
						(width 0.254)
						(type default)
					)
					(fill
						(type background)
					)
				)
				(pin passive line
					(at 0 0 0)
					(length 2.54)
					(name "G"
						(effects
							(font
								(size 1.27 1.27)
							)
						)
					)
					(number "4"
						(effects
							(font
								(size 1.27 1.27)
							)
						)
					)
				)
				(pin passive line
					(at 6.35 7.62 270)
					(length 2.54)
					(name "D"
						(effects
							(font
								(size 1.27 1.27)
							)
						)
					)
					(number "5"
						(effects
							(font
								(size 1.27 1.27)
							)
						)
					)
				)
				(pin passive line
					(at 6.35 -2.54 90)
					(length 2.54)
					(name "S"
						(effects
							(font
								(size 1.27 1.27)
							)
						)
					)
					(number "1"
						(effects
							(font
								(size 1.27 1.27)
							)
						)
					)
				)
				(pin passive line
					(at 6.35 -2.54 90)
					(length 2.54)
					(hide yes)
					(name "S"
						(effects
							(font
								(size 1.27 1.27)
							)
						)
					)
					(number "2"
						(effects
							(font
								(size 1.27 1.27)
							)
						)
					)
				)
				(pin passive line
					(at 6.35 -2.54 90)
					(length 2.54)
					(hide yes)
					(name "S"
						(effects
							(font
								(size 1.27 1.27)
							)
						)
					)
					(number "3"
						(effects
							(font
								(size 1.27 1.27)
							)
						)
					)
				)
			)
		)
	(symbol "antmicroUSBConnectors:USB-C_JAE_DX07S024JJ2"
			(exclude_from_sim no)
			(in_bom yes)
			(on_board yes)
			(property "Reference" "J"
				(at 36.83 2.54 0)
				(effects
					(font
						(size 1.27 1.27)
						(thickness 0.15)
					)
					(justify left bottom)
				)
			)
			(property "Value" "USB-C_JAE_DX07S024JJ2"
				(at 36.83 0 0)
				(effects
					(font
						(size 1.27 1.27)
						(thickness 0.15)
					)
					(justify left bottom)
					(hide yes)
				)
			)
			(property "Footprint" "antmicro-footprints:USB-C_Receptacle_JAE_DX07S024JJ2"
				(at 36.83 -2.54 0)
				(effects
					(font
						(size 1.27 1.27)
						(thickness 0.15)
					)
					(justify left bottom)
					(hide yes)
				)
			)
			(property "Datasheet" "https://www.jae.com/en/connectors/series/detail/product/id=66508"
				(at 36.83 -5.08 0)
				(effects
					(font
						(size 1.27 1.27)
						(thickness 0.15)
					)
					(justify left bottom)
					(hide yes)
				)
			)
			(property "Description" "USB-C (USB TYPE-C) USB 3.2 Gen 2 (USB 3.1 Gen 2, Superspeed + (USB 3.1)) Receptacle Connector 24 Position Surface Mount, Right Angle"
				(at 36.83 -17.78 0)
				(effects
					(font
						(size 1.27 1.27)
					)
					(justify left bottom)
					(hide yes)
				)
			)
			(property "MPN" "DX07S024JJ2"
				(at 36.83 -7.62 0)
				(effects
					(font
						(size 1.27 1.27)
						(thickness 0.15)
					)
					(justify left bottom)
				)
			)
			(property "Manufacturer" "JAE Electronics"
				(at 36.83 -10.16 0)
				(effects
					(font
						(size 1.27 1.27)
						(thickness 0.15)
					)
					(justify left bottom)
					(hide yes)
				)
			)
			(property "Author" "Antmicro"
				(at 36.83 -12.7 0)
				(effects
					(font
						(size 1.27 1.27)
						(thickness 0.15)
					)
					(justify left bottom)
					(hide yes)
				)
			)
			(property "License" "Apache-2.0"
				(at 36.83 -15.24 0)
				(effects
					(font
						(size 1.27 1.27)
						(thickness 0.15)
					)
					(justify left bottom)
					(hide yes)
				)
			)
			(property "ki_keywords" "USB, CONNECTOR, SMT, HORIZONTAL"
				(at 0 0 0)
				(effects
					(font
						(size 1.27 1.27)
					)
					(hide yes)
				)
			)
			(symbol "USB-C_JAE_DX07S024JJ2_1_1"
				(rectangle
					(start -22.86 -68.58)
					(end -3.81 2.54)
					(stroke
						(width 0.254)
						(type default)
					)
					(fill
						(type background)
					)
				)
				(circle
					(center -20.066 -33.274)
					(radius 0.284)
					(stroke
						(width 0.254)
						(type default)
					)
					(fill
						(type outline)
					)
				)
				(polyline
					(pts
						(xy -19.812 -31.623) (xy -19.177 -30.48) (xy -18.542 -31.623) (xy -19.812 -31.623)
					)
					(stroke
						(width 0.254)
						(type default)
					)
					(fill
						(type outline)
					)
				)
				(polyline
					(pts
						(xy -19.177 -34.798) (xy -18.288 -33.909) (xy -18.288 -33.274)
					)
					(stroke
						(width 0.254)
						(type default)
					)
					(fill
						(type background)
					)
				)
				(polyline
					(pts
						(xy -19.177 -35.179) (xy -20.066 -34.29) (xy -20.066 -33.655)
					)
					(stroke
						(width 0.254)
						(type default)
					)
					(fill
						(type background)
					)
				)
				(polyline
					(pts
						(xy -19.177 -35.941) (xy -19.177 -31.623)
					)
					(stroke
						(width 0.254)
						(type default)
					)
					(fill
						(type background)
					)
				)
				(circle
					(center -19.177 -36.068)
					(radius 0.5236)
					(stroke
						(width 0.254)
						(type default)
					)
					(fill
						(type outline)
					)
				)
				(rectangle
					(start -18.669 -33.274)
					(end -17.907 -32.512)
					(stroke
						(width 0.254)
						(type default)
					)
					(fill
						(type outline)
					)
				)
				(polyline
					(pts
						(xy -16.51 -36.83) (xy -16.51 -29.21)
					)
					(stroke
						(width 0.254)
						(type default)
					)
					(fill
						(type background)
					)
				)
				(rectangle
					(start -15.24 -36.83)
					(end -13.97 -29.21)
					(stroke
						(width 0.254)
						(type default)
					)
					(fill
						(type outline)
					)
				)
				(arc
					(start -15.24 -29.21)
					(mid -14.605 -28.5777)
					(end -13.97 -29.21)
					(stroke
						(width 0.254)
						(type default)
					)
					(fill
						(type outline)
					)
				)
				(arc
					(start -15.24 -29.21)
					(mid -14.605 -28.5777)
					(end -13.97 -29.21)
					(stroke
						(width 0.254)
						(type default)
					)
					(fill
						(type background)
					)
				)
				(arc
					(start -16.51 -29.21)
					(mid -14.605 -27.3133)
					(end -12.7 -29.21)
					(stroke
						(width 0.254)
						(type default)
					)
					(fill
						(type background)
					)
				)
				(arc
					(start -12.7 -36.83)
					(mid -14.605 -38.7267)
					(end -16.51 -36.83)
					(stroke
						(width 0.254)
						(type default)
					)
					(fill
						(type background)
					)
				)
				(arc
					(start -13.97 -36.83)
					(mid -14.605 -37.4623)
					(end -15.24 -36.83)
					(stroke
						(width 0.254)
						(type default)
					)
					(fill
						(type outline)
					)
				)
				(arc
					(start -13.97 -36.83)
					(mid -14.605 -37.4623)
					(end -15.24 -36.83)
					(stroke
						(width 0.254)
						(type default)
					)
					(fill
						(type background)
					)
				)
				(polyline
					(pts
						(xy -12.7 -29.21) (xy -12.7 -36.83)
					)
					(stroke
						(width 0.254)
						(type default)
					)
					(fill
						(type background)
					)
				)
				(pin power_in line
					(at 0 0 180)
					(length 3.81)
					(name "VBUS"
						(effects
							(font
								(size 1.27 1.27)
							)
						)
					)
					(number "A4"
						(effects
							(font
								(size 1.27 1.27)
							)
						)
					)
				)
				(pin passive line
					(at 0 0 180)
					(length 3.81)
					(name "VBUS"
						(effects
							(font
								(size 1.27 1.27)
							)
						)
					)
					(number "A9"
						(effects
							(font
								(size 1.27 1.27)
							)
						)
					)
				)
				(pin passive line
					(at 0 0 180)
					(length 3.81)
					(name "VBUS"
						(effects
							(font
								(size 1.27 1.27)
							)
						)
					)
					(number "B4"
						(effects
							(font
								(size 1.27 1.27)
							)
						)
					)
				)
				(pin passive line
					(at 0 0 180)
					(length 3.81)
					(name "VBUS"
						(effects
							(font
								(size 1.27 1.27)
							)
						)
					)
					(number "B9"
						(effects
							(font
								(size 1.27 1.27)
							)
						)
					)
				)
				(pin bidirectional line
					(at 0 -5.08 180)
					(length 3.81)
					(name "CC_{1}"
						(effects
							(font
								(size 1.27 1.27)
							)
						)
					)
					(number "A5"
						(effects
							(font
								(size 1.27 1.27)
							)
						)
					)
				)
				(pin bidirectional line
					(at 0 -7.62 180)
					(length 3.81)
					(name "CC_{2}"
						(effects
							(font
								(size 1.27 1.27)
							)
						)
					)
					(number "B5"
						(effects
							(font
								(size 1.27 1.27)
							)
						)
					)
				)
				(pin bidirectional line
					(at 0 -12.7 180)
					(length 3.81)
					(name "D_{A}+"
						(effects
							(font
								(size 1.27 1.27)
							)
						)
					)
					(number "A6"
						(effects
							(font
								(size 1.27 1.27)
							)
						)
					)
				)
				(pin bidirectional line
					(at 0 -15.24 180)
					(length 3.81)
					(name "D_{A}-"
						(effects
							(font
								(size 1.27 1.27)
							)
						)
					)
					(number "A7"
						(effects
							(font
								(size 1.27 1.27)
							)
						)
					)
				)
				(pin bidirectional line
					(at 0 -17.78 180)
					(length 3.81)
					(name "D_{B}+"
						(effects
							(font
								(size 1.27 1.27)
							)
						)
					)
					(number "B6"
						(effects
							(font
								(size 1.27 1.27)
							)
						)
					)
				)
				(pin bidirectional line
					(at 0 -20.32 180)
					(length 3.81)
					(name "D_{B}-"
						(effects
							(font
								(size 1.27 1.27)
							)
						)
					)
					(number "B7"
						(effects
							(font
								(size 1.27 1.27)
							)
						)
					)
				)
				(pin bidirectional line
					(at 0 -25.4 180)
					(length 3.81)
					(name "RX_{1}+"
						(effects
							(font
								(size 1.27 1.27)
							)
						)
					)
					(number "B11"
						(effects
							(font
								(size 1.27 1.27)
							)
						)
					)
				)
				(pin bidirectional line
					(at 0 -27.94 180)
					(length 3.81)
					(name "RX_{1}-"
						(effects
							(font
								(size 1.27 1.27)
							)
						)
					)
					(number "B10"
						(effects
							(font
								(size 1.27 1.27)
							)
						)
					)
				)
				(pin bidirectional line
					(at 0 -33.02 180)
					(length 3.81)
					(name "TX_{1}+"
						(effects
							(font
								(size 1.27 1.27)
							)
						)
					)
					(number "A2"
						(effects
							(font
								(size 1.27 1.27)
							)
						)
					)
				)
				(pin bidirectional line
					(at 0 -35.56 180)
					(length 3.81)
					(name "TX_{1}-"
						(effects
							(font
								(size 1.27 1.27)
							)
						)
					)
					(number "A3"
						(effects
							(font
								(size 1.27 1.27)
							)
						)
					)
				)
				(pin bidirectional line
					(at 0 -40.64 180)
					(length 3.81)
					(name "RX_{2}+"
						(effects
							(font
								(size 1.27 1.27)
							)
						)
					)
					(number "A11"
						(effects
							(font
								(size 1.27 1.27)
							)
						)
					)
				)
				(pin bidirectional line
					(at 0 -43.18 180)
					(length 3.81)
					(name "RX_{2}-"
						(effects
							(font
								(size 1.27 1.27)
							)
						)
					)
					(number "A10"
						(effects
							(font
								(size 1.27 1.27)
							)
						)
					)
				)
				(pin bidirectional line
					(at 0 -48.26 180)
					(length 3.81)
					(name "TX_{2}+"
						(effects
							(font
								(size 1.27 1.27)
							)
						)
					)
					(number "B2"
						(effects
							(font
								(size 1.27 1.27)
							)
						)
					)
				)
				(pin bidirectional line
					(at 0 -50.8 180)
					(length 3.81)
					(name "TX_{2}-"
						(effects
							(font
								(size 1.27 1.27)
							)
						)
					)
					(number "B3"
						(effects
							(font
								(size 1.27 1.27)
							)
						)
					)
				)
				(pin bidirectional line
					(at 0 -55.88 180)
					(length 3.81)
					(name "SBU_{1}"
						(effects
							(font
								(size 1.27 1.27)
							)
						)
					)
					(number "A8"
						(effects
							(font
								(size 1.27 1.27)
							)
						)
					)
				)
				(pin bidirectional line
					(at 0 -58.42 180)
					(length 3.81)
					(name "SBU_{2}"
						(effects
							(font
								(size 1.27 1.27)
							)
						)
					)
					(number "B8"
						(effects
							(font
								(size 1.27 1.27)
							)
						)
					)
				)
				(pin power_in line
					(at 0 -63.5 180)
					(length 3.81)
					(name "GND"
						(effects
							(font
								(size 1.27 1.27)
							)
						)
					)
					(number "A1"
						(effects
							(font
								(size 1.27 1.27)
							)
						)
					)
				)
				(pin passive line
					(at 0 -63.5 180)
					(length 3.81)
					(name "GND"
						(effects
							(font
								(size 1.27 1.27)
							)
						)
					)
					(number "A12"
						(effects
							(font
								(size 1.27 1.27)
							)
						)
					)
				)
				(pin passive line
					(at 0 -63.5 180)
					(length 3.81)
					(name "GND"
						(effects
							(font
								(size 1.27 1.27)
							)
						)
					)
					(number "B1"
						(effects
							(font
								(size 1.27 1.27)
							)
						)
					)
				)
				(pin passive line
					(at 0 -63.5 180)
					(length 3.81)
					(name "GND"
						(effects
							(font
								(size 1.27 1.27)
							)
						)
					)
					(number "B12"
						(effects
							(font
								(size 1.27 1.27)
							)
						)
					)
				)
				(pin passive line
					(at 0 -66.04 180)
					(length 3.81)
					(name "SH"
						(effects
							(font
								(size 1.27 1.27)
							)
						)
					)
					(number "SH"
						(effects
							(font
								(size 1.27 1.27)
							)
						)
					)
				)
			)
		)
	(symbol "antmicroWire2BoardConnectors:Molex_KK_1x4_0470531000"
			(exclude_from_sim no)
			(in_bom yes)
			(on_board yes)
			(property "Reference" "J"
				(at 20.32 -5.08 0)
				(effects
					(font
						(size 1.27 1.27)
						(thickness 0.15)
					)
					(justify left bottom)
				)
			)
			(property "Value" "Molex_KK_1x4_0470531000"
				(at 20.32 -10.16 0)
				(effects
					(font
						(size 1.27 1.27)
						(thickness 0.15)
					)
					(justify left bottom)
					(hide yes)
				)
			)
			(property "Footprint" "antmicro-footprints:Conn_Molex_KK_1x4_0470531000"
				(at 20.32 -12.7 0)
				(effects
					(font
						(size 1.27 1.27)
						(thickness 0.15)
					)
					(justify left bottom)
					(hide yes)
				)
			)
			(property "Datasheet" "https://tools.molex.com/pdm_docs/sd/470531000_sd.pdf"
				(at 20.32 -15.24 0)
				(effects
					(font
						(size 1.27 1.27)
						(thickness 0.15)
					)
					(justify left bottom)
					(hide yes)
				)
			)
			(property "Description" "Connector Header, THT,  4x1"
				(at 20.32 -25.4 0)
				(effects
					(font
						(size 1.27 1.27)
					)
					(justify left bottom)
					(hide yes)
				)
			)
			(property "MPN" "0470531000"
				(at 20.32 -7.62 0)
				(effects
					(font
						(size 1.27 1.27)
						(thickness 0.15)
					)
					(justify left bottom)
				)
			)
			(property "Manufacturer" "Molex"
				(at 20.32 -17.78 0)
				(effects
					(font
						(size 1.27 1.27)
						(thickness 0.15)
					)
					(justify left bottom)
					(hide yes)
				)
			)
			(property "Author" "Antmicro"
				(at 20.32 -20.32 0)
				(effects
					(font
						(size 1.27 1.27)
						(thickness 0.15)
					)
					(justify left bottom)
					(hide yes)
				)
			)
			(property "License" "Apache-2.0"
				(at 20.32 -22.86 0)
				(effects
					(font
						(size 1.27 1.27)
						(thickness 0.15)
					)
					(justify left bottom)
					(hide yes)
				)
			)
			(property "ki_keywords" "CONNECTOR, HEADER, WIRE-BOARD, THT"
				(at 0 0 0)
				(effects
					(font
						(size 1.27 1.27)
					)
					(hide yes)
				)
			)
			(symbol "Molex_KK_1x4_0470531000_1_1"
				(rectangle
					(start 2.54 0.127)
					(end 3.81 -0.127)
					(stroke
						(width 0.254)
						(type default)
					)
					(fill
						(type background)
					)
				)
				(rectangle
					(start 2.54 -2.413)
					(end 3.81 -2.667)
					(stroke
						(width 0.254)
						(type default)
					)
					(fill
						(type background)
					)
				)
				(rectangle
					(start 2.54 -4.953)
					(end 3.81 -5.207)
					(stroke
						(width 0.254)
						(type default)
					)
					(fill
						(type background)
					)
				)
				(rectangle
					(start 2.54 -7.493)
					(end 3.81 -7.747)
					(stroke
						(width 0.254)
						(type default)
					)
					(fill
						(type background)
					)
				)
				(rectangle
					(start 5.08 -8.89)
					(end 2.54 1.27)
					(stroke
						(width 0.254)
						(type default)
					)
					(fill
						(type background)
					)
				)
				(pin passive line
					(at 0 0 0)
					(length 2.54)
					(name "~"
						(effects
							(font
								(size 1.27 1.27)
							)
						)
					)
					(number "1"
						(effects
							(font
								(size 1.27 1.27)
							)
						)
					)
				)
				(pin passive line
					(at 0 -2.54 0)
					(length 2.54)
					(name "~"
						(effects
							(font
								(size 1.27 1.27)
							)
						)
					)
					(number "2"
						(effects
							(font
								(size 1.27 1.27)
							)
						)
					)
				)
				(pin passive line
					(at 0 -5.08 0)
					(length 2.54)
					(name "~"
						(effects
							(font
								(size 1.27 1.27)
							)
						)
					)
					(number "3"
						(effects
							(font
								(size 1.27 1.27)
							)
						)
					)
				)
				(pin passive line
					(at 0 -7.62 0)
					(length 2.54)
					(name "~"
						(effects
							(font
								(size 1.27 1.27)
							)
						)
					)
					(number "4"
						(effects
							(font
								(size 1.27 1.27)
							)
						)
					)
				)
			)
		)
	(symbol "antmicroWire2BoardConnectors:Molex_Nano-Fit_1x2_105313-2202_Horizontal"
			(exclude_from_sim no)
			(in_bom yes)
			(on_board yes)
			(property "Reference" "J"
				(at 20.32 -2.54 0)
				(effects
					(font
						(size 1.27 1.27)
						(thickness 0.15)
					)
					(justify left bottom)
				)
			)
			(property "Value" "Molex_Nano-Fit_1x2_105313-2202_Horizontal"
				(at 20.32 -7.62 0)
				(effects
					(font
						(size 1.27 1.27)
						(thickness 0.15)
					)
					(justify left bottom)
					(hide yes)
				)
			)
			(property "Footprint" "antmicro-footprints:Conn_Molex_Nano-Fit_1x2_105313-2202_Horizontal"
				(at 20.32 -10.16 0)
				(effects
					(font
						(size 1.27 1.27)
						(thickness 0.15)
					)
					(justify left bottom)
					(hide yes)
				)
			)
			(property "Datasheet" "https://tools.molex.com/pdm_docs/sd/1053132202_sd.pdf"
				(at 20.32 -12.7 0)
				(effects
					(font
						(size 1.27 1.27)
						(thickness 0.15)
					)
					(justify left bottom)
					(hide yes)
				)
			)
			(property "Description" "Pin Header, Power, 2.5 mm, 1 Rows, 2 Contacts, Through Hole Horizontal, Nano-Fit"
				(at 20.32 -22.86 0)
				(effects
					(font
						(size 1.27 1.27)
					)
					(justify left bottom)
					(hide yes)
				)
			)
			(property "MPN" "105313-2202"
				(at 20.32 -5.08 0)
				(effects
					(font
						(size 1.27 1.27)
						(thickness 0.15)
					)
					(justify left bottom)
				)
			)
			(property "Manufacturer" "Molex"
				(at 20.32 -15.24 0)
				(effects
					(font
						(size 1.27 1.27)
						(thickness 0.15)
					)
					(justify left bottom)
					(hide yes)
				)
			)
			(property "Author" "Antmicro"
				(at 20.32 -17.78 0)
				(effects
					(font
						(size 1.27 1.27)
						(thickness 0.15)
					)
					(justify left bottom)
					(hide yes)
				)
			)
			(property "License" "Apache-2.0"
				(at 20.32 -20.32 0)
				(effects
					(font
						(size 1.27 1.27)
						(thickness 0.15)
					)
					(justify left bottom)
					(hide yes)
				)
			)
			(property "ki_keywords" "CONNECTOR, HEADER, THT, WIRE-BOARD"
				(at 0 0 0)
				(effects
					(font
						(size 1.27 1.27)
					)
					(hide yes)
				)
			)
			(symbol "Molex_Nano-Fit_1x2_105313-2202_Horizontal_1_1"
				(rectangle
					(start 2.54 2.54)
					(end 6.35 -5.08)
					(stroke
						(width 0.254)
						(type default)
					)
					(fill
						(type background)
					)
				)
				(rectangle
					(start 3.81 -0.635)
					(end 5.08 0.635)
					(stroke
						(width 0.254)
						(type default)
					)
					(fill
						(type background)
					)
				)
				(rectangle
					(start 3.81 -3.175)
					(end 5.08 -1.905)
					(stroke
						(width 0.254)
						(type default)
					)
					(fill
						(type background)
					)
				)
				(pin input line
					(at 0 0 0)
					(length 2.54)
					(name "~"
						(effects
							(font
								(size 1.27 1.27)
							)
						)
					)
					(number "1"
						(effects
							(font
								(size 1.27 1.27)
							)
						)
					)
				)
				(pin input line
					(at 0 -2.54 0)
					(length 2.54)
					(name "~"
						(effects
							(font
								(size 1.27 1.27)
							)
						)
					)
					(number "2"
						(effects
							(font
								(size 1.27 1.27)
							)
						)
					)
				)
			)
		)
	(symbol "antmicropower:+1V0"
			(power)
			(pin_names
				(offset 0)
			)
			(exclude_from_sim no)
			(in_bom yes)
			(on_board yes)
			(property "Reference" "#PWR"
				(at 0 -3.81 0)
				(effects
					(font
						(size 1.27 1.27)
					)
					(hide yes)
				)
			)
			(property "Value" "+1V0"
				(at 0 3.556 0)
				(effects
					(font
						(size 1.27 1.27)
					)
				)
			)
			(property "Footprint" ""
				(at 0 0 0)
				(effects
					(font
						(size 1.27 1.27)
					)
					(hide yes)
				)
			)
			(property "Datasheet" ""
				(at 0 0 0)
				(effects
					(font
						(size 1.27 1.27)
					)
					(hide yes)
				)
			)
			(property "Description" ""
				(at 0 -6.35 0)
				(effects
					(font
						(size 1.27 1.27)
					)
					(justify left bottom)
					(hide yes)
				)
			)
			(symbol "+1V0_0_1"
				(polyline
					(pts
						(xy -0.762 1.27) (xy 0 2.54)
					)
					(stroke
						(width 0)
						(type default)
					)
					(fill
						(type none)
					)
				)
				(polyline
					(pts
						(xy 0 2.54) (xy 0.762 1.27)
					)
					(stroke
						(width 0)
						(type default)
					)
					(fill
						(type none)
					)
				)
				(polyline
					(pts
						(xy 0 0) (xy 0 2.54)
					)
					(stroke
						(width 0)
						(type default)
					)
					(fill
						(type none)
					)
				)
			)
			(symbol "+1V0_1_1"
				(pin power_in line
					(at 0 0 90)
					(length 0)
					(hide yes)
					(name "+1V0"
						(effects
							(font
								(size 1.27 1.27)
							)
						)
					)
					(number "1"
						(effects
							(font
								(size 1.27 1.27)
							)
						)
					)
				)
			)
		)
	(symbol "antmicropower:+1V8"
			(power)
			(pin_numbers
				(hide yes)
			)
			(pin_names
				(hide yes)
			)
			(exclude_from_sim no)
			(in_bom yes)
			(on_board yes)
			(property "Reference" "#PWR"
				(at 15.24 -2.54 0)
				(effects
					(font
						(size 1.27 1.27)
						(thickness 0.15)
					)
					(justify left bottom)
					(hide yes)
				)
			)
			(property "Value" "+1V8"
				(at -3.175 2.54 0)
				(effects
					(font
						(size 1.27 1.27)
						(thickness 0.15)
					)
					(justify left bottom)
				)
			)
			(property "Footprint" ""
				(at 15.24 -7.62 0)
				(effects
					(font
						(size 1.27 1.27)
						(thickness 0.15)
					)
					(justify left bottom)
					(hide yes)
				)
			)
			(property "Datasheet" ""
				(at 15.24 -10.16 0)
				(effects
					(font
						(size 1.27 1.27)
						(thickness 0.15)
					)
					(justify left bottom)
					(hide yes)
				)
			)
			(property "Description" ""
				(at 15.24 -12.7 0)
				(effects
					(font
						(size 1.27 1.27)
					)
					(justify left bottom)
					(hide yes)
				)
			)
			(property "Author" "Antmicro"
				(at 15.24 -5.08 0)
				(effects
					(font
						(size 1.27 1.27)
						(thickness 0.15)
					)
					(justify left bottom)
					(hide yes)
				)
			)
			(property "License" "Apache-2.0"
				(at 15.24 -7.62 0)
				(effects
					(font
						(size 1.27 1.27)
						(thickness 0.15)
					)
					(justify left bottom)
					(hide yes)
				)
			)
			(symbol "+1V8_1_1"
				(polyline
					(pts
						(xy -0.762 1.27) (xy 0 2.54)
					)
					(stroke
						(width 0)
						(type default)
					)
					(fill
						(type background)
					)
				)
				(polyline
					(pts
						(xy 0 2.54) (xy 0.762 1.27)
					)
					(stroke
						(width 0)
						(type default)
					)
					(fill
						(type background)
					)
				)
				(polyline
					(pts
						(xy 0 0) (xy 0 2.54)
					)
					(stroke
						(width 0)
						(type default)
					)
					(fill
						(type background)
					)
				)
				(pin power_in line
					(at 0 0 90)
					(length 0)
					(hide yes)
					(name "+1V8"
						(effects
							(font
								(size 1.27 1.27)
							)
						)
					)
					(number "1"
						(effects
							(font
								(size 1.27 1.27)
							)
						)
					)
				)
			)
		)
	(symbol "antmicropower:+3V3"
			(power)
			(pin_numbers
				(hide yes)
			)
			(pin_names
				(hide yes)
			)
			(exclude_from_sim no)
			(in_bom yes)
			(on_board yes)
			(property "Reference" "#PWR"
				(at 15.24 0 0)
				(effects
					(font
						(size 1.27 1.27)
						(thickness 0.15)
					)
					(justify left bottom)
					(hide yes)
				)
			)
			(property "Value" "+3V3"
				(at -3.175 2.54 0)
				(effects
					(font
						(size 1.27 1.27)
						(thickness 0.15)
					)
					(justify left bottom)
				)
			)
			(property "Footprint" ""
				(at 15.24 -7.62 0)
				(effects
					(font
						(size 1.27 1.27)
						(thickness 0.15)
					)
					(justify left bottom)
					(hide yes)
				)
			)
			(property "Datasheet" ""
				(at 15.24 -10.16 0)
				(effects
					(font
						(size 1.27 1.27)
						(thickness 0.15)
					)
					(justify left bottom)
					(hide yes)
				)
			)
			(property "Description" ""
				(at 15.24 -12.7 0)
				(effects
					(font
						(size 1.27 1.27)
					)
					(justify left bottom)
					(hide yes)
				)
			)
			(property "Author" "Antmicro"
				(at 15.24 -2.54 0)
				(effects
					(font
						(size 1.27 1.27)
						(thickness 0.15)
					)
					(justify left bottom)
					(hide yes)
				)
			)
			(property "License" "Apache-2.0"
				(at 15.24 -5.08 0)
				(effects
					(font
						(size 1.27 1.27)
						(thickness 0.15)
					)
					(justify left bottom)
					(hide yes)
				)
			)
			(symbol "+3V3_0_1"
				(polyline
					(pts
						(xy 0 2.54) (xy -0.762 1.27)
					)
					(stroke
						(width 0)
						(type default)
					)
					(fill
						(type none)
					)
				)
				(polyline
					(pts
						(xy 0 2.54) (xy 0.762 1.27)
					)
					(stroke
						(width 0)
						(type default)
					)
					(fill
						(type none)
					)
				)
				(polyline
					(pts
						(xy 0 0) (xy 0 2.54)
					)
					(stroke
						(width 0)
						(type default)
					)
					(fill
						(type none)
					)
				)
			)
			(symbol "+3V3_1_1"
				(pin power_in line
					(at 0 0 90)
					(length 0)
					(hide yes)
					(name "+3V3"
						(effects
							(font
								(size 1.27 1.27)
							)
						)
					)
					(number "1"
						(effects
							(font
								(size 1.27 1.27)
							)
						)
					)
				)
			)
		)
	(symbol "antmicropower:+5V"
			(power)
			(pin_numbers
				(hide yes)
			)
			(pin_names
				(hide yes)
			)
			(exclude_from_sim no)
			(in_bom yes)
			(on_board yes)
			(property "Reference" "#PWR"
				(at 15.24 -2.54 0)
				(effects
					(font
						(size 1.27 1.27)
						(thickness 0.15)
					)
					(justify left bottom)
					(hide yes)
				)
			)
			(property "Value" "+5V"
				(at 15.24 -5.08 0)
				(effects
					(font
						(size 1.27 1.27)
						(thickness 0.15)
					)
					(justify left bottom)
				)
			)
			(property "Footprint" ""
				(at 15.24 -7.62 0)
				(effects
					(font
						(size 1.27 1.27)
						(thickness 0.15)
					)
					(justify left bottom)
					(hide yes)
				)
			)
			(property "Datasheet" ""
				(at 15.24 -10.16 0)
				(effects
					(font
						(size 1.27 1.27)
						(thickness 0.15)
					)
					(justify left bottom)
					(hide yes)
				)
			)
			(property "Description" ""
				(at 15.24 -12.7 0)
				(effects
					(font
						(size 1.27 1.27)
					)
					(justify left bottom)
					(hide yes)
				)
			)
			(property "Author" "Antmicro"
				(at 15.24 -7.62 0)
				(effects
					(font
						(size 1.27 1.27)
						(thickness 0.15)
					)
					(justify left bottom)
					(hide yes)
				)
			)
			(property "License" "Apache-2.0"
				(at 15.24 -10.16 0)
				(effects
					(font
						(size 1.27 1.27)
						(thickness 0.15)
					)
					(justify left bottom)
					(hide yes)
				)
			)
			(symbol "+5V_1_1"
				(polyline
					(pts
						(xy -0.762 1.27) (xy 0 2.54)
					)
					(stroke
						(width 0)
						(type default)
					)
					(fill
						(type background)
					)
				)
				(polyline
					(pts
						(xy 0 2.54) (xy 0.762 1.27)
					)
					(stroke
						(width 0)
						(type default)
					)
					(fill
						(type background)
					)
				)
				(polyline
					(pts
						(xy 0 0) (xy 0 2.54)
					)
					(stroke
						(width 0)
						(type default)
					)
					(fill
						(type background)
					)
				)
				(pin power_in line
					(at 0 0 90)
					(length 0)
					(name "+5V"
						(effects
							(font
								(size 1.27 1.27)
							)
						)
					)
					(number "1"
						(effects
							(font
								(size 1.27 1.27)
							)
						)
					)
				)
			)
		)
	(symbol "antmicropower:GND"
			(power)
			(pin_numbers
				(hide yes)
			)
			(pin_names
				(hide yes)
			)
			(exclude_from_sim no)
			(in_bom yes)
			(on_board yes)
			(property "Reference" "#PWR"
				(at 8.89 -2.54 0)
				(effects
					(font
						(size 1.27 1.27)
						(thickness 0.15)
					)
					(justify left bottom)
					(hide yes)
				)
			)
			(property "Value" "GND"
				(at 8.89 -5.08 0)
				(effects
					(font
						(size 1.27 1.27)
						(thickness 0.15)
					)
					(justify left bottom)
				)
			)
			(property "Footprint" ""
				(at 8.89 -7.62 0)
				(effects
					(font
						(size 1.27 1.27)
						(thickness 0.15)
					)
					(justify left bottom)
					(hide yes)
				)
			)
			(property "Datasheet" ""
				(at 8.89 -12.7 0)
				(effects
					(font
						(size 1.27 1.27)
						(thickness 0.15)
					)
					(justify left bottom)
					(hide yes)
				)
			)
			(property "Description" ""
				(at 8.89 -15.24 0)
				(effects
					(font
						(size 1.27 1.27)
					)
					(justify left bottom)
					(hide yes)
				)
			)
			(property "Author" "Antmicro"
				(at 8.89 -7.62 0)
				(effects
					(font
						(size 1.27 1.27)
						(thickness 0.15)
					)
					(justify left bottom)
					(hide yes)
				)
			)
			(property "License" "Apache-2.0"
				(at 8.89 -10.16 0)
				(effects
					(font
						(size 1.27 1.27)
						(thickness 0.15)
					)
					(justify left bottom)
					(hide yes)
				)
			)
			(symbol "GND_1_1"
				(polyline
					(pts
						(xy 0 0) (xy 0 -1.27) (xy 1.27 -1.27) (xy 0 -2.54) (xy -1.27 -1.27) (xy 0 -1.27)
					)
					(stroke
						(width 0)
						(type default)
					)
					(fill
						(type none)
					)
				)
				(pin power_in line
					(at 0 0 270)
					(length 0)
					(name "GND"
						(effects
							(font
								(size 1.27 1.27)
							)
						)
					)
					(number "1"
						(effects
							(font
								(size 1.27 1.27)
							)
						)
					)
				)
			)
		)
	(symbol "antmicropower:PWR_FLAG"
			(power)
			(pin_numbers
				(hide yes)
			)
			(pin_names
				(offset 0)
				(hide yes)
			)
			(exclude_from_sim no)
			(in_bom yes)
			(on_board yes)
			(property "Reference" "#FLG"
				(at 0 1.905 0)
				(effects
					(font
						(size 1.27 1.27)
					)
					(hide yes)
				)
			)
			(property "Value" "PWR_FLAG"
				(at 0 3.81 0)
				(effects
					(font
						(size 1.27 1.27)
					)
				)
			)
			(property "Footprint" ""
				(at 0 0 0)
				(effects
					(font
						(size 1.27 1.27)
					)
					(hide yes)
				)
			)
			(property "Datasheet" ""
				(at 0 0 0)
				(effects
					(font
						(size 1.27 1.27)
					)
					(hide yes)
				)
			)
			(property "Description" ""
				(at 0 -2.54 0)
				(effects
					(font
						(size 1.27 1.27)
					)
					(justify left bottom)
					(hide yes)
				)
			)
			(symbol "PWR_FLAG_0_0"
				(pin power_out line
					(at 0 0 90)
					(length 0)
					(name "pwr"
						(effects
							(font
								(size 1.27 1.27)
							)
						)
					)
					(number "1"
						(effects
							(font
								(size 1.27 1.27)
							)
						)
					)
				)
			)
			(symbol "PWR_FLAG_0_1"
				(polyline
					(pts
						(xy 0 0) (xy 0 1.27) (xy -1.016 1.905) (xy 0 2.54) (xy 1.016 1.905) (xy 0 1.27)
					)
					(stroke
						(width 0)
						(type default)
					)
					(fill
						(type none)
					)
				)
			)
		)
	(symbol "antmicropower:VCC"
			(power)
			(pin_names
				(offset 0)
			)
			(exclude_from_sim no)
			(in_bom yes)
			(on_board yes)
			(property "Reference" "#PWR"
				(at 0 -3.81 0)
				(effects
					(font
						(size 1.27 1.27)
					)
					(hide yes)
				)
			)
			(property "Value" "VCC"
				(at 0 3.81 0)
				(effects
					(font
						(size 1.27 1.27)
					)
				)
			)
			(property "Footprint" ""
				(at 0 0 0)
				(effects
					(font
						(size 1.27 1.27)
					)
					(hide yes)
				)
			)
			(property "Datasheet" ""
				(at 0 0 0)
				(effects
					(font
						(size 1.27 1.27)
					)
					(hide yes)
				)
			)
			(property "Description" ""
				(at 0 -6.35 0)
				(effects
					(font
						(size 1.27 1.27)
					)
					(justify left bottom)
					(hide yes)
				)
			)
			(symbol "VCC_0_1"
				(polyline
					(pts
						(xy -0.762 1.27) (xy 0 2.54)
					)
					(stroke
						(width 0)
						(type default)
					)
					(fill
						(type none)
					)
				)
				(polyline
					(pts
						(xy 0 2.54) (xy 0.762 1.27)
					)
					(stroke
						(width 0)
						(type default)
					)
					(fill
						(type none)
					)
				)
				(polyline
					(pts
						(xy 0 0) (xy 0 2.54)
					)
					(stroke
						(width 0)
						(type default)
					)
					(fill
						(type none)
					)
				)
			)
			(symbol "VCC_1_1"
				(pin power_in line
					(at 0 0 90)
					(length 0)
					(hide yes)
					(name "VCC"
						(effects
							(font
								(size 1.27 1.27)
							)
						)
					)
					(number "1"
						(effects
							(font
								(size 1.27 1.27)
							)
						)
					)
				)
			)
		)
	(symbol "antmicropower:VDD"
			(power)
			(pin_names
				(offset 0)
			)
			(exclude_from_sim no)
			(in_bom yes)
			(on_board yes)
			(property "Reference" "#PWR"
				(at 0 -3.81 0)
				(effects
					(font
						(size 1.27 1.27)
					)
					(hide yes)
				)
			)
			(property "Value" "VDD"
				(at 0 3.81 0)
				(effects
					(font
						(size 1.27 1.27)
					)
				)
			)
			(property "Footprint" ""
				(at 0 0 0)
				(effects
					(font
						(size 1.27 1.27)
					)
					(hide yes)
				)
			)
			(property "Datasheet" ""
				(at 0 0 0)
				(effects
					(font
						(size 1.27 1.27)
					)
					(hide yes)
				)
			)
			(property "Description" ""
				(at 0 -6.35 0)
				(effects
					(font
						(size 1.27 1.27)
					)
					(justify left bottom)
					(hide yes)
				)
			)
			(symbol "VDD_0_1"
				(polyline
					(pts
						(xy -0.762 1.27) (xy 0 2.54)
					)
					(stroke
						(width 0)
						(type default)
					)
					(fill
						(type none)
					)
				)
				(polyline
					(pts
						(xy 0 2.54) (xy 0.762 1.27)
					)
					(stroke
						(width 0)
						(type default)
					)
					(fill
						(type none)
					)
				)
				(polyline
					(pts
						(xy 0 0) (xy 0 2.54)
					)
					(stroke
						(width 0)
						(type default)
					)
					(fill
						(type none)
					)
				)
			)
			(symbol "VDD_1_1"
				(pin power_in line
					(at 0 0 90)
					(length 0)
					(hide yes)
					(name "VDD"
						(effects
							(font
								(size 1.27 1.27)
							)
						)
					)
					(number "1"
						(effects
							(font
								(size 1.27 1.27)
							)
						)
					)
				)
			)
		)
	(symbol "thunderbolt-gpu-adapter:C_1u_0402_10"
			(pin_numbers
				(hide yes)
			)
			(pin_names
				(hide yes)
			)
			(exclude_from_sim no)
			(in_bom yes)
			(on_board yes)
			(property "Reference" "C"
				(at 20.32 -5.08 0)
				(effects
					(font
						(size 1.27 1.27)
						(thickness 0.15)
					)
					(justify left bottom)
				)
			)
			(property "Value" "C_1u_0402_10"
				(at 20.32 -10.16 0)
				(effects
					(font
						(size 1.27 1.27)
						(thickness 0.15)
					)
					(justify left bottom)
					(hide yes)
				)
			)
			(property "Footprint" "thunderbolt-gpu-adapter-footprints:C_0402_1005Metric"
				(at 20.32 -12.7 0)
				(effects
					(font
						(size 1.27 1.27)
						(thickness 0.15)
					)
					(justify left bottom)
					(hide yes)
				)
			)
			(property "Datasheet" ""
				(at 20.32 -15.24 0)
				(effects
					(font
						(size 1.27 1.27)
						(thickness 0.15)
					)
					(justify left bottom)
					(hide yes)
				)
			)
			(property "Description" ""
				(at 0 0 0)
				(effects
					(font
						(size 1.27 1.27)
					)
					(hide yes)
				)
			)
			(property "MPN" "C1005X6S1A105K050BC"
				(at 20.32 -17.78 0)
				(effects
					(font
						(size 1.27 1.27)
						(thickness 0.15)
					)
					(justify left bottom)
					(hide yes)
				)
			)
			(property "Manufacturer" "TDK"
				(at 20.32 -20.32 0)
				(effects
					(font
						(size 1.27 1.27)
						(thickness 0.15)
					)
					(justify left bottom)
					(hide yes)
				)
			)
			(property "License" "Apache-2.0"
				(at 20.32 -22.86 0)
				(effects
					(font
						(size 1.27 1.27)
						(thickness 0.15)
					)
					(justify left bottom)
					(hide yes)
				)
			)
			(property "Author" "Antmicro"
				(at 20.32 -25.4 0)
				(effects
					(font
						(size 1.27 1.27)
						(thickness 0.15)
					)
					(justify left bottom)
					(hide yes)
				)
			)
			(property "Val" "1u"
				(at 20.32 -7.62 0)
				(effects
					(font
						(size 1.27 1.27)
						(thickness 0.15)
					)
					(justify left bottom)
				)
			)
			(property "Voltage" ""
				(at 20.32 -27.94 0)
				(effects
					(font
						(size 1.27 1.27)
					)
					(justify left bottom)
					(hide yes)
				)
			)
			(property "Dielectric" ""
				(at 20.32 -30.48 0)
				(effects
					(font
						(size 1.27 1.27)
					)
					(justify left bottom)
					(hide yes)
				)
			)
			(symbol "C_1u_0402_10_0_1"
				(polyline
					(pts
						(xy 2.032 -1.524) (xy 2.032 1.524)
					)
					(stroke
						(width 0.3048)
						(type default)
					)
					(fill
						(type none)
					)
				)
				(polyline
					(pts
						(xy 3.048 -1.524) (xy 3.048 1.524)
					)
					(stroke
						(width 0.3302)
						(type default)
					)
					(fill
						(type none)
					)
				)
			)
			(symbol "C_1u_0402_10_1_1"
				(pin passive line
					(at 0 0 0)
					(length 2.032)
					(name "~"
						(effects
							(font
								(size 1.27 1.27)
							)
						)
					)
					(number "1"
						(effects
							(font
								(size 1.27 1.27)
							)
						)
					)
				)
				(pin passive line
					(at 5.08 0 180)
					(length 2.032)
					(name "~"
						(effects
							(font
								(size 1.27 1.27)
							)
						)
					)
					(number "2"
						(effects
							(font
								(size 1.27 1.27)
							)
						)
					)
				)
			)
		)
	(symbol "thunderbolt-gpu-adapter:C_1u_0402_11"
			(pin_numbers
				(hide yes)
			)
			(pin_names
				(hide yes)
			)
			(exclude_from_sim no)
			(in_bom yes)
			(on_board yes)
			(property "Reference" "C"
				(at 20.32 -5.08 0)
				(effects
					(font
						(size 1.27 1.27)
						(thickness 0.15)
					)
					(justify left bottom)
				)
			)
			(property "Value" "C_1u_0402_11"
				(at 20.32 -10.16 0)
				(effects
					(font
						(size 1.27 1.27)
						(thickness 0.15)
					)
					(justify left bottom)
					(hide yes)
				)
			)
			(property "Footprint" "thunderbolt-gpu-adapter-footprints:C_0402_1005Metric"
				(at 20.32 -12.7 0)
				(effects
					(font
						(size 1.27 1.27)
						(thickness 0.15)
					)
					(justify left bottom)
					(hide yes)
				)
			)
			(property "Datasheet" ""
				(at 20.32 -15.24 0)
				(effects
					(font
						(size 1.27 1.27)
						(thickness 0.15)
					)
					(justify left bottom)
					(hide yes)
				)
			)
			(property "Description" ""
				(at 0 0 0)
				(effects
					(font
						(size 1.27 1.27)
					)
					(hide yes)
				)
			)
			(property "MPN" "C1005X6S1A105K050BC"
				(at 20.32 -17.78 0)
				(effects
					(font
						(size 1.27 1.27)
						(thickness 0.15)
					)
					(justify left bottom)
					(hide yes)
				)
			)
			(property "Manufacturer" "TDK"
				(at 20.32 -20.32 0)
				(effects
					(font
						(size 1.27 1.27)
						(thickness 0.15)
					)
					(justify left bottom)
					(hide yes)
				)
			)
			(property "License" "Apache-2.0"
				(at 20.32 -22.86 0)
				(effects
					(font
						(size 1.27 1.27)
						(thickness 0.15)
					)
					(justify left bottom)
					(hide yes)
				)
			)
			(property "Author" "Antmicro"
				(at 20.32 -25.4 0)
				(effects
					(font
						(size 1.27 1.27)
						(thickness 0.15)
					)
					(justify left bottom)
					(hide yes)
				)
			)
			(property "Val" "1u"
				(at 20.32 -7.62 0)
				(effects
					(font
						(size 1.27 1.27)
						(thickness 0.15)
					)
					(justify left bottom)
				)
			)
			(property "Voltage" ""
				(at 20.32 -27.94 0)
				(effects
					(font
						(size 1.27 1.27)
					)
					(justify left bottom)
					(hide yes)
				)
			)
			(property "Dielectric" ""
				(at 20.32 -30.48 0)
				(effects
					(font
						(size 1.27 1.27)
					)
					(justify left bottom)
					(hide yes)
				)
			)
			(symbol "C_1u_0402_11_0_1"
				(polyline
					(pts
						(xy 2.032 -1.524) (xy 2.032 1.524)
					)
					(stroke
						(width 0.3048)
						(type default)
					)
					(fill
						(type none)
					)
				)
				(polyline
					(pts
						(xy 3.048 -1.524) (xy 3.048 1.524)
					)
					(stroke
						(width 0.3302)
						(type default)
					)
					(fill
						(type none)
					)
				)
			)
			(symbol "C_1u_0402_11_1_1"
				(pin passive line
					(at 0 0 0)
					(length 2.032)
					(name "~"
						(effects
							(font
								(size 1.27 1.27)
							)
						)
					)
					(number "1"
						(effects
							(font
								(size 1.27 1.27)
							)
						)
					)
				)
				(pin passive line
					(at 5.08 0 180)
					(length 2.032)
					(name "~"
						(effects
							(font
								(size 1.27 1.27)
							)
						)
					)
					(number "2"
						(effects
							(font
								(size 1.27 1.27)
							)
						)
					)
				)
			)
		)
	(symbol "thunderbolt-gpu-adapter:C_1u_0402_12"
			(pin_numbers
				(hide yes)
			)
			(pin_names
				(hide yes)
			)
			(exclude_from_sim no)
			(in_bom yes)
			(on_board yes)
			(property "Reference" "C"
				(at 20.32 -5.08 0)
				(effects
					(font
						(size 1.27 1.27)
						(thickness 0.15)
					)
					(justify left bottom)
				)
			)
			(property "Value" "C_1u_0402_12"
				(at 20.32 -10.16 0)
				(effects
					(font
						(size 1.27 1.27)
						(thickness 0.15)
					)
					(justify left bottom)
					(hide yes)
				)
			)
			(property "Footprint" "thunderbolt-gpu-adapter-footprints:C_0402_1005Metric"
				(at 20.32 -12.7 0)
				(effects
					(font
						(size 1.27 1.27)
						(thickness 0.15)
					)
					(justify left bottom)
					(hide yes)
				)
			)
			(property "Datasheet" ""
				(at 20.32 -15.24 0)
				(effects
					(font
						(size 1.27 1.27)
						(thickness 0.15)
					)
					(justify left bottom)
					(hide yes)
				)
			)
			(property "Description" ""
				(at 0 0 0)
				(effects
					(font
						(size 1.27 1.27)
					)
					(hide yes)
				)
			)
			(property "MPN" "C1005X6S1A105K050BC"
				(at 20.32 -17.78 0)
				(effects
					(font
						(size 1.27 1.27)
						(thickness 0.15)
					)
					(justify left bottom)
					(hide yes)
				)
			)
			(property "Manufacturer" "TDK"
				(at 20.32 -20.32 0)
				(effects
					(font
						(size 1.27 1.27)
						(thickness 0.15)
					)
					(justify left bottom)
					(hide yes)
				)
			)
			(property "License" "Apache-2.0"
				(at 20.32 -22.86 0)
				(effects
					(font
						(size 1.27 1.27)
						(thickness 0.15)
					)
					(justify left bottom)
					(hide yes)
				)
			)
			(property "Author" "Antmicro"
				(at 20.32 -25.4 0)
				(effects
					(font
						(size 1.27 1.27)
						(thickness 0.15)
					)
					(justify left bottom)
					(hide yes)
				)
			)
			(property "Val" "1u"
				(at 20.32 -7.62 0)
				(effects
					(font
						(size 1.27 1.27)
						(thickness 0.15)
					)
					(justify left bottom)
				)
			)
			(property "Voltage" ""
				(at 20.32 -27.94 0)
				(effects
					(font
						(size 1.27 1.27)
					)
					(justify left bottom)
					(hide yes)
				)
			)
			(property "Dielectric" ""
				(at 20.32 -30.48 0)
				(effects
					(font
						(size 1.27 1.27)
					)
					(justify left bottom)
					(hide yes)
				)
			)
			(symbol "C_1u_0402_12_0_1"
				(polyline
					(pts
						(xy 2.032 -1.524) (xy 2.032 1.524)
					)
					(stroke
						(width 0.3048)
						(type default)
					)
					(fill
						(type none)
					)
				)
				(polyline
					(pts
						(xy 3.048 -1.524) (xy 3.048 1.524)
					)
					(stroke
						(width 0.3302)
						(type default)
					)
					(fill
						(type none)
					)
				)
			)
			(symbol "C_1u_0402_12_1_1"
				(pin passive line
					(at 0 0 0)
					(length 2.032)
					(name "~"
						(effects
							(font
								(size 1.27 1.27)
							)
						)
					)
					(number "1"
						(effects
							(font
								(size 1.27 1.27)
							)
						)
					)
				)
				(pin passive line
					(at 5.08 0 180)
					(length 2.032)
					(name "~"
						(effects
							(font
								(size 1.27 1.27)
							)
						)
					)
					(number "2"
						(effects
							(font
								(size 1.27 1.27)
							)
						)
					)
				)
			)
		)
	(symbol "thunderbolt-gpu-adapter:C_1u_0402_13"
			(pin_numbers
				(hide yes)
			)
			(pin_names
				(hide yes)
			)
			(exclude_from_sim no)
			(in_bom yes)
			(on_board yes)
			(property "Reference" "C"
				(at 20.32 -5.08 0)
				(effects
					(font
						(size 1.27 1.27)
						(thickness 0.15)
					)
					(justify left bottom)
				)
			)
			(property "Value" "C_1u_0402_13"
				(at 20.32 -10.16 0)
				(effects
					(font
						(size 1.27 1.27)
						(thickness 0.15)
					)
					(justify left bottom)
					(hide yes)
				)
			)
			(property "Footprint" "thunderbolt-gpu-adapter-footprints:C_0402_1005Metric"
				(at 20.32 -12.7 0)
				(effects
					(font
						(size 1.27 1.27)
						(thickness 0.15)
					)
					(justify left bottom)
					(hide yes)
				)
			)
			(property "Datasheet" ""
				(at 20.32 -15.24 0)
				(effects
					(font
						(size 1.27 1.27)
						(thickness 0.15)
					)
					(justify left bottom)
					(hide yes)
				)
			)
			(property "Description" ""
				(at 0 0 0)
				(effects
					(font
						(size 1.27 1.27)
					)
					(hide yes)
				)
			)
			(property "MPN" "C1005X6S1A105K050BC"
				(at 20.32 -17.78 0)
				(effects
					(font
						(size 1.27 1.27)
						(thickness 0.15)
					)
					(justify left bottom)
					(hide yes)
				)
			)
			(property "Manufacturer" "TDK"
				(at 20.32 -20.32 0)
				(effects
					(font
						(size 1.27 1.27)
						(thickness 0.15)
					)
					(justify left bottom)
					(hide yes)
				)
			)
			(property "License" "Apache-2.0"
				(at 20.32 -22.86 0)
				(effects
					(font
						(size 1.27 1.27)
						(thickness 0.15)
					)
					(justify left bottom)
					(hide yes)
				)
			)
			(property "Author" "Antmicro"
				(at 20.32 -25.4 0)
				(effects
					(font
						(size 1.27 1.27)
						(thickness 0.15)
					)
					(justify left bottom)
					(hide yes)
				)
			)
			(property "Val" "1u"
				(at 20.32 -7.62 0)
				(effects
					(font
						(size 1.27 1.27)
						(thickness 0.15)
					)
					(justify left bottom)
				)
			)
			(property "Voltage" ""
				(at 20.32 -27.94 0)
				(effects
					(font
						(size 1.27 1.27)
					)
					(justify left bottom)
					(hide yes)
				)
			)
			(property "Dielectric" ""
				(at 20.32 -30.48 0)
				(effects
					(font
						(size 1.27 1.27)
					)
					(justify left bottom)
					(hide yes)
				)
			)
			(symbol "C_1u_0402_13_0_1"
				(polyline
					(pts
						(xy 2.032 -1.524) (xy 2.032 1.524)
					)
					(stroke
						(width 0.3048)
						(type default)
					)
					(fill
						(type none)
					)
				)
				(polyline
					(pts
						(xy 3.048 -1.524) (xy 3.048 1.524)
					)
					(stroke
						(width 0.3302)
						(type default)
					)
					(fill
						(type none)
					)
				)
			)
			(symbol "C_1u_0402_13_1_1"
				(pin passive line
					(at 0 0 0)
					(length 2.032)
					(name "~"
						(effects
							(font
								(size 1.27 1.27)
							)
						)
					)
					(number "1"
						(effects
							(font
								(size 1.27 1.27)
							)
						)
					)
				)
				(pin passive line
					(at 5.08 0 180)
					(length 2.032)
					(name "~"
						(effects
							(font
								(size 1.27 1.27)
							)
						)
					)
					(number "2"
						(effects
							(font
								(size 1.27 1.27)
							)
						)
					)
				)
			)
		)
	(symbol "thunderbolt-gpu-adapter:C_1u_0402_14"
			(pin_numbers
				(hide yes)
			)
			(pin_names
				(hide yes)
			)
			(exclude_from_sim no)
			(in_bom yes)
			(on_board yes)
			(property "Reference" "C"
				(at 20.32 -5.08 0)
				(effects
					(font
						(size 1.27 1.27)
						(thickness 0.15)
					)
					(justify left bottom)
				)
			)
			(property "Value" "C_1u_0402_14"
				(at 20.32 -10.16 0)
				(effects
					(font
						(size 1.27 1.27)
						(thickness 0.15)
					)
					(justify left bottom)
					(hide yes)
				)
			)
			(property "Footprint" "thunderbolt-gpu-adapter-footprints:C_0402_1005Metric"
				(at 20.32 -12.7 0)
				(effects
					(font
						(size 1.27 1.27)
						(thickness 0.15)
					)
					(justify left bottom)
					(hide yes)
				)
			)
			(property "Datasheet" ""
				(at 20.32 -15.24 0)
				(effects
					(font
						(size 1.27 1.27)
						(thickness 0.15)
					)
					(justify left bottom)
					(hide yes)
				)
			)
			(property "Description" ""
				(at 0 0 0)
				(effects
					(font
						(size 1.27 1.27)
					)
					(hide yes)
				)
			)
			(property "MPN" "C1005X6S1A105K050BC"
				(at 20.32 -17.78 0)
				(effects
					(font
						(size 1.27 1.27)
						(thickness 0.15)
					)
					(justify left bottom)
					(hide yes)
				)
			)
			(property "Manufacturer" "TDK"
				(at 20.32 -20.32 0)
				(effects
					(font
						(size 1.27 1.27)
						(thickness 0.15)
					)
					(justify left bottom)
					(hide yes)
				)
			)
			(property "License" "Apache-2.0"
				(at 20.32 -22.86 0)
				(effects
					(font
						(size 1.27 1.27)
						(thickness 0.15)
					)
					(justify left bottom)
					(hide yes)
				)
			)
			(property "Author" "Antmicro"
				(at 20.32 -25.4 0)
				(effects
					(font
						(size 1.27 1.27)
						(thickness 0.15)
					)
					(justify left bottom)
					(hide yes)
				)
			)
			(property "Val" "1u"
				(at 20.32 -7.62 0)
				(effects
					(font
						(size 1.27 1.27)
						(thickness 0.15)
					)
					(justify left bottom)
				)
			)
			(property "Voltage" ""
				(at 20.32 -27.94 0)
				(effects
					(font
						(size 1.27 1.27)
					)
					(justify left bottom)
					(hide yes)
				)
			)
			(property "Dielectric" ""
				(at 20.32 -30.48 0)
				(effects
					(font
						(size 1.27 1.27)
					)
					(justify left bottom)
					(hide yes)
				)
			)
			(symbol "C_1u_0402_14_0_1"
				(polyline
					(pts
						(xy 2.032 -1.524) (xy 2.032 1.524)
					)
					(stroke
						(width 0.3048)
						(type default)
					)
					(fill
						(type none)
					)
				)
				(polyline
					(pts
						(xy 3.048 -1.524) (xy 3.048 1.524)
					)
					(stroke
						(width 0.3302)
						(type default)
					)
					(fill
						(type none)
					)
				)
			)
			(symbol "C_1u_0402_14_1_1"
				(pin passive line
					(at 0 0 0)
					(length 2.032)
					(name "~"
						(effects
							(font
								(size 1.27 1.27)
							)
						)
					)
					(number "1"
						(effects
							(font
								(size 1.27 1.27)
							)
						)
					)
				)
				(pin passive line
					(at 5.08 0 180)
					(length 2.032)
					(name "~"
						(effects
							(font
								(size 1.27 1.27)
							)
						)
					)
					(number "2"
						(effects
							(font
								(size 1.27 1.27)
							)
						)
					)
				)
			)
		)
	(symbol "thunderbolt-gpu-adapter:C_1u_0402_15"
			(pin_numbers
				(hide yes)
			)
			(pin_names
				(hide yes)
			)
			(exclude_from_sim no)
			(in_bom yes)
			(on_board yes)
			(property "Reference" "C"
				(at 20.32 -5.08 0)
				(effects
					(font
						(size 1.27 1.27)
						(thickness 0.15)
					)
					(justify left bottom)
				)
			)
			(property "Value" "C_1u_0402_15"
				(at 20.32 -10.16 0)
				(effects
					(font
						(size 1.27 1.27)
						(thickness 0.15)
					)
					(justify left bottom)
					(hide yes)
				)
			)
			(property "Footprint" "thunderbolt-gpu-adapter-footprints:C_0402_1005Metric"
				(at 20.32 -12.7 0)
				(effects
					(font
						(size 1.27 1.27)
						(thickness 0.15)
					)
					(justify left bottom)
					(hide yes)
				)
			)
			(property "Datasheet" ""
				(at 20.32 -15.24 0)
				(effects
					(font
						(size 1.27 1.27)
						(thickness 0.15)
					)
					(justify left bottom)
					(hide yes)
				)
			)
			(property "Description" ""
				(at 0 0 0)
				(effects
					(font
						(size 1.27 1.27)
					)
					(hide yes)
				)
			)
			(property "MPN" "C1005X6S1A105K050BC"
				(at 20.32 -17.78 0)
				(effects
					(font
						(size 1.27 1.27)
						(thickness 0.15)
					)
					(justify left bottom)
					(hide yes)
				)
			)
			(property "Manufacturer" "TDK"
				(at 20.32 -20.32 0)
				(effects
					(font
						(size 1.27 1.27)
						(thickness 0.15)
					)
					(justify left bottom)
					(hide yes)
				)
			)
			(property "License" "Apache-2.0"
				(at 20.32 -22.86 0)
				(effects
					(font
						(size 1.27 1.27)
						(thickness 0.15)
					)
					(justify left bottom)
					(hide yes)
				)
			)
			(property "Author" "Antmicro"
				(at 20.32 -25.4 0)
				(effects
					(font
						(size 1.27 1.27)
						(thickness 0.15)
					)
					(justify left bottom)
					(hide yes)
				)
			)
			(property "Val" "1u"
				(at 20.32 -7.62 0)
				(effects
					(font
						(size 1.27 1.27)
						(thickness 0.15)
					)
					(justify left bottom)
				)
			)
			(property "Voltage" ""
				(at 20.32 -27.94 0)
				(effects
					(font
						(size 1.27 1.27)
					)
					(justify left bottom)
					(hide yes)
				)
			)
			(property "Dielectric" ""
				(at 20.32 -30.48 0)
				(effects
					(font
						(size 1.27 1.27)
					)
					(justify left bottom)
					(hide yes)
				)
			)
			(symbol "C_1u_0402_15_0_1"
				(polyline
					(pts
						(xy 2.032 -1.524) (xy 2.032 1.524)
					)
					(stroke
						(width 0.3048)
						(type default)
					)
					(fill
						(type none)
					)
				)
				(polyline
					(pts
						(xy 3.048 -1.524) (xy 3.048 1.524)
					)
					(stroke
						(width 0.3302)
						(type default)
					)
					(fill
						(type none)
					)
				)
			)
			(symbol "C_1u_0402_15_1_1"
				(pin passive line
					(at 0 0 0)
					(length 2.032)
					(name "~"
						(effects
							(font
								(size 1.27 1.27)
							)
						)
					)
					(number "1"
						(effects
							(font
								(size 1.27 1.27)
							)
						)
					)
				)
				(pin passive line
					(at 5.08 0 180)
					(length 2.032)
					(name "~"
						(effects
							(font
								(size 1.27 1.27)
							)
						)
					)
					(number "2"
						(effects
							(font
								(size 1.27 1.27)
							)
						)
					)
				)
			)
		)
	(symbol "thunderbolt-gpu-adapter:C_1u_0402_16"
			(pin_numbers
				(hide yes)
			)
			(pin_names
				(hide yes)
			)
			(exclude_from_sim no)
			(in_bom yes)
			(on_board yes)
			(property "Reference" "C"
				(at 20.32 -5.08 0)
				(effects
					(font
						(size 1.27 1.27)
						(thickness 0.15)
					)
					(justify left bottom)
				)
			)
			(property "Value" "C_1u_0402_16"
				(at 20.32 -10.16 0)
				(effects
					(font
						(size 1.27 1.27)
						(thickness 0.15)
					)
					(justify left bottom)
					(hide yes)
				)
			)
			(property "Footprint" "thunderbolt-gpu-adapter-footprints:C_0402_1005Metric"
				(at 20.32 -12.7 0)
				(effects
					(font
						(size 1.27 1.27)
						(thickness 0.15)
					)
					(justify left bottom)
					(hide yes)
				)
			)
			(property "Datasheet" ""
				(at 20.32 -15.24 0)
				(effects
					(font
						(size 1.27 1.27)
						(thickness 0.15)
					)
					(justify left bottom)
					(hide yes)
				)
			)
			(property "Description" ""
				(at 0 0 0)
				(effects
					(font
						(size 1.27 1.27)
					)
					(hide yes)
				)
			)
			(property "MPN" "C1005X6S1A105K050BC"
				(at 20.32 -17.78 0)
				(effects
					(font
						(size 1.27 1.27)
						(thickness 0.15)
					)
					(justify left bottom)
					(hide yes)
				)
			)
			(property "Manufacturer" "TDK"
				(at 20.32 -20.32 0)
				(effects
					(font
						(size 1.27 1.27)
						(thickness 0.15)
					)
					(justify left bottom)
					(hide yes)
				)
			)
			(property "License" "Apache-2.0"
				(at 20.32 -22.86 0)
				(effects
					(font
						(size 1.27 1.27)
						(thickness 0.15)
					)
					(justify left bottom)
					(hide yes)
				)
			)
			(property "Author" "Antmicro"
				(at 20.32 -25.4 0)
				(effects
					(font
						(size 1.27 1.27)
						(thickness 0.15)
					)
					(justify left bottom)
					(hide yes)
				)
			)
			(property "Val" "1u"
				(at 20.32 -7.62 0)
				(effects
					(font
						(size 1.27 1.27)
						(thickness 0.15)
					)
					(justify left bottom)
				)
			)
			(property "Voltage" ""
				(at 20.32 -27.94 0)
				(effects
					(font
						(size 1.27 1.27)
					)
					(justify left bottom)
					(hide yes)
				)
			)
			(property "Dielectric" ""
				(at 20.32 -30.48 0)
				(effects
					(font
						(size 1.27 1.27)
					)
					(justify left bottom)
					(hide yes)
				)
			)
			(symbol "C_1u_0402_16_0_1"
				(polyline
					(pts
						(xy 2.032 -1.524) (xy 2.032 1.524)
					)
					(stroke
						(width 0.3048)
						(type default)
					)
					(fill
						(type none)
					)
				)
				(polyline
					(pts
						(xy 3.048 -1.524) (xy 3.048 1.524)
					)
					(stroke
						(width 0.3302)
						(type default)
					)
					(fill
						(type none)
					)
				)
			)
			(symbol "C_1u_0402_16_1_1"
				(pin passive line
					(at 0 0 0)
					(length 2.032)
					(name "~"
						(effects
							(font
								(size 1.27 1.27)
							)
						)
					)
					(number "1"
						(effects
							(font
								(size 1.27 1.27)
							)
						)
					)
				)
				(pin passive line
					(at 5.08 0 180)
					(length 2.032)
					(name "~"
						(effects
							(font
								(size 1.27 1.27)
							)
						)
					)
					(number "2"
						(effects
							(font
								(size 1.27 1.27)
							)
						)
					)
				)
			)
		)
	(symbol "thunderbolt-gpu-adapter:C_1u_0402_17"
			(pin_numbers
				(hide yes)
			)
			(pin_names
				(hide yes)
			)
			(exclude_from_sim no)
			(in_bom yes)
			(on_board yes)
			(property "Reference" "C"
				(at 20.32 -5.08 0)
				(effects
					(font
						(size 1.27 1.27)
						(thickness 0.15)
					)
					(justify left bottom)
				)
			)
			(property "Value" "C_1u_0402_17"
				(at 20.32 -10.16 0)
				(effects
					(font
						(size 1.27 1.27)
						(thickness 0.15)
					)
					(justify left bottom)
					(hide yes)
				)
			)
			(property "Footprint" "thunderbolt-gpu-adapter-footprints:C_0402_1005Metric"
				(at 20.32 -12.7 0)
				(effects
					(font
						(size 1.27 1.27)
						(thickness 0.15)
					)
					(justify left bottom)
					(hide yes)
				)
			)
			(property "Datasheet" ""
				(at 20.32 -15.24 0)
				(effects
					(font
						(size 1.27 1.27)
						(thickness 0.15)
					)
					(justify left bottom)
					(hide yes)
				)
			)
			(property "Description" ""
				(at 0 0 0)
				(effects
					(font
						(size 1.27 1.27)
					)
					(hide yes)
				)
			)
			(property "MPN" "C1005X6S1A105K050BC"
				(at 20.32 -17.78 0)
				(effects
					(font
						(size 1.27 1.27)
						(thickness 0.15)
					)
					(justify left bottom)
					(hide yes)
				)
			)
			(property "Manufacturer" "TDK"
				(at 20.32 -20.32 0)
				(effects
					(font
						(size 1.27 1.27)
						(thickness 0.15)
					)
					(justify left bottom)
					(hide yes)
				)
			)
			(property "License" "Apache-2.0"
				(at 20.32 -22.86 0)
				(effects
					(font
						(size 1.27 1.27)
						(thickness 0.15)
					)
					(justify left bottom)
					(hide yes)
				)
			)
			(property "Author" "Antmicro"
				(at 20.32 -25.4 0)
				(effects
					(font
						(size 1.27 1.27)
						(thickness 0.15)
					)
					(justify left bottom)
					(hide yes)
				)
			)
			(property "Val" "1u"
				(at 20.32 -7.62 0)
				(effects
					(font
						(size 1.27 1.27)
						(thickness 0.15)
					)
					(justify left bottom)
				)
			)
			(property "Voltage" ""
				(at 20.32 -27.94 0)
				(effects
					(font
						(size 1.27 1.27)
					)
					(justify left bottom)
					(hide yes)
				)
			)
			(property "Dielectric" ""
				(at 20.32 -30.48 0)
				(effects
					(font
						(size 1.27 1.27)
					)
					(justify left bottom)
					(hide yes)
				)
			)
			(symbol "C_1u_0402_17_0_1"
				(polyline
					(pts
						(xy 2.032 -1.524) (xy 2.032 1.524)
					)
					(stroke
						(width 0.3048)
						(type default)
					)
					(fill
						(type none)
					)
				)
				(polyline
					(pts
						(xy 3.048 -1.524) (xy 3.048 1.524)
					)
					(stroke
						(width 0.3302)
						(type default)
					)
					(fill
						(type none)
					)
				)
			)
			(symbol "C_1u_0402_17_1_1"
				(pin passive line
					(at 0 0 0)
					(length 2.032)
					(name "~"
						(effects
							(font
								(size 1.27 1.27)
							)
						)
					)
					(number "1"
						(effects
							(font
								(size 1.27 1.27)
							)
						)
					)
				)
				(pin passive line
					(at 5.08 0 180)
					(length 2.032)
					(name "~"
						(effects
							(font
								(size 1.27 1.27)
							)
						)
					)
					(number "2"
						(effects
							(font
								(size 1.27 1.27)
							)
						)
					)
				)
			)
		)
	(symbol "thunderbolt-gpu-adapter:C_1u_0402_18"
			(pin_numbers
				(hide yes)
			)
			(pin_names
				(hide yes)
			)
			(exclude_from_sim no)
			(in_bom yes)
			(on_board yes)
			(property "Reference" "C"
				(at 20.32 -5.08 0)
				(effects
					(font
						(size 1.27 1.27)
						(thickness 0.15)
					)
					(justify left bottom)
				)
			)
			(property "Value" "C_1u_0402_18"
				(at 20.32 -10.16 0)
				(effects
					(font
						(size 1.27 1.27)
						(thickness 0.15)
					)
					(justify left bottom)
					(hide yes)
				)
			)
			(property "Footprint" "thunderbolt-gpu-adapter-footprints:C_0402_1005Metric"
				(at 20.32 -12.7 0)
				(effects
					(font
						(size 1.27 1.27)
						(thickness 0.15)
					)
					(justify left bottom)
					(hide yes)
				)
			)
			(property "Datasheet" ""
				(at 20.32 -15.24 0)
				(effects
					(font
						(size 1.27 1.27)
						(thickness 0.15)
					)
					(justify left bottom)
					(hide yes)
				)
			)
			(property "Description" ""
				(at 0 0 0)
				(effects
					(font
						(size 1.27 1.27)
					)
					(hide yes)
				)
			)
			(property "MPN" "C1005X6S1A105K050BC"
				(at 20.32 -17.78 0)
				(effects
					(font
						(size 1.27 1.27)
						(thickness 0.15)
					)
					(justify left bottom)
					(hide yes)
				)
			)
			(property "Manufacturer" "TDK"
				(at 20.32 -20.32 0)
				(effects
					(font
						(size 1.27 1.27)
						(thickness 0.15)
					)
					(justify left bottom)
					(hide yes)
				)
			)
			(property "License" "Apache-2.0"
				(at 20.32 -22.86 0)
				(effects
					(font
						(size 1.27 1.27)
						(thickness 0.15)
					)
					(justify left bottom)
					(hide yes)
				)
			)
			(property "Author" "Antmicro"
				(at 20.32 -25.4 0)
				(effects
					(font
						(size 1.27 1.27)
						(thickness 0.15)
					)
					(justify left bottom)
					(hide yes)
				)
			)
			(property "Val" "1u"
				(at 20.32 -7.62 0)
				(effects
					(font
						(size 1.27 1.27)
						(thickness 0.15)
					)
					(justify left bottom)
				)
			)
			(property "Voltage" ""
				(at 20.32 -27.94 0)
				(effects
					(font
						(size 1.27 1.27)
					)
					(justify left bottom)
					(hide yes)
				)
			)
			(property "Dielectric" ""
				(at 20.32 -30.48 0)
				(effects
					(font
						(size 1.27 1.27)
					)
					(justify left bottom)
					(hide yes)
				)
			)
			(symbol "C_1u_0402_18_0_1"
				(polyline
					(pts
						(xy 2.032 -1.524) (xy 2.032 1.524)
					)
					(stroke
						(width 0.3048)
						(type default)
					)
					(fill
						(type none)
					)
				)
				(polyline
					(pts
						(xy 3.048 -1.524) (xy 3.048 1.524)
					)
					(stroke
						(width 0.3302)
						(type default)
					)
					(fill
						(type none)
					)
				)
			)
			(symbol "C_1u_0402_18_1_1"
				(pin passive line
					(at 0 0 0)
					(length 2.032)
					(name "~"
						(effects
							(font
								(size 1.27 1.27)
							)
						)
					)
					(number "1"
						(effects
							(font
								(size 1.27 1.27)
							)
						)
					)
				)
				(pin passive line
					(at 5.08 0 180)
					(length 2.032)
					(name "~"
						(effects
							(font
								(size 1.27 1.27)
							)
						)
					)
					(number "2"
						(effects
							(font
								(size 1.27 1.27)
							)
						)
					)
				)
			)
		)
	(symbol "thunderbolt-gpu-adapter:C_1u_0402_19"
			(pin_numbers
				(hide yes)
			)
			(pin_names
				(hide yes)
			)
			(exclude_from_sim no)
			(in_bom yes)
			(on_board yes)
			(property "Reference" "C"
				(at 20.32 -5.08 0)
				(effects
					(font
						(size 1.27 1.27)
						(thickness 0.15)
					)
					(justify left bottom)
				)
			)
			(property "Value" "C_1u_0402_19"
				(at 20.32 -10.16 0)
				(effects
					(font
						(size 1.27 1.27)
						(thickness 0.15)
					)
					(justify left bottom)
					(hide yes)
				)
			)
			(property "Footprint" "thunderbolt-gpu-adapter-footprints:C_0402_1005Metric"
				(at 20.32 -12.7 0)
				(effects
					(font
						(size 1.27 1.27)
						(thickness 0.15)
					)
					(justify left bottom)
					(hide yes)
				)
			)
			(property "Datasheet" ""
				(at 20.32 -15.24 0)
				(effects
					(font
						(size 1.27 1.27)
						(thickness 0.15)
					)
					(justify left bottom)
					(hide yes)
				)
			)
			(property "Description" ""
				(at 0 0 0)
				(effects
					(font
						(size 1.27 1.27)
					)
					(hide yes)
				)
			)
			(property "MPN" "C1005X6S1A105K050BC"
				(at 20.32 -17.78 0)
				(effects
					(font
						(size 1.27 1.27)
						(thickness 0.15)
					)
					(justify left bottom)
					(hide yes)
				)
			)
			(property "Manufacturer" "TDK"
				(at 20.32 -20.32 0)
				(effects
					(font
						(size 1.27 1.27)
						(thickness 0.15)
					)
					(justify left bottom)
					(hide yes)
				)
			)
			(property "License" "Apache-2.0"
				(at 20.32 -22.86 0)
				(effects
					(font
						(size 1.27 1.27)
						(thickness 0.15)
					)
					(justify left bottom)
					(hide yes)
				)
			)
			(property "Author" "Antmicro"
				(at 20.32 -25.4 0)
				(effects
					(font
						(size 1.27 1.27)
						(thickness 0.15)
					)
					(justify left bottom)
					(hide yes)
				)
			)
			(property "Val" "1u"
				(at 20.32 -7.62 0)
				(effects
					(font
						(size 1.27 1.27)
						(thickness 0.15)
					)
					(justify left bottom)
				)
			)
			(property "Voltage" ""
				(at 20.32 -27.94 0)
				(effects
					(font
						(size 1.27 1.27)
					)
					(justify left bottom)
					(hide yes)
				)
			)
			(property "Dielectric" ""
				(at 20.32 -30.48 0)
				(effects
					(font
						(size 1.27 1.27)
					)
					(justify left bottom)
					(hide yes)
				)
			)
			(symbol "C_1u_0402_19_0_1"
				(polyline
					(pts
						(xy 2.032 -1.524) (xy 2.032 1.524)
					)
					(stroke
						(width 0.3048)
						(type default)
					)
					(fill
						(type none)
					)
				)
				(polyline
					(pts
						(xy 3.048 -1.524) (xy 3.048 1.524)
					)
					(stroke
						(width 0.3302)
						(type default)
					)
					(fill
						(type none)
					)
				)
			)
			(symbol "C_1u_0402_19_1_1"
				(pin passive line
					(at 0 0 0)
					(length 2.032)
					(name "~"
						(effects
							(font
								(size 1.27 1.27)
							)
						)
					)
					(number "1"
						(effects
							(font
								(size 1.27 1.27)
							)
						)
					)
				)
				(pin passive line
					(at 5.08 0 180)
					(length 2.032)
					(name "~"
						(effects
							(font
								(size 1.27 1.27)
							)
						)
					)
					(number "2"
						(effects
							(font
								(size 1.27 1.27)
							)
						)
					)
				)
			)
		)
	(symbol "thunderbolt-gpu-adapter:C_1u_0402_20"
			(pin_numbers
				(hide yes)
			)
			(pin_names
				(hide yes)
			)
			(exclude_from_sim no)
			(in_bom yes)
			(on_board yes)
			(property "Reference" "C"
				(at 20.32 -5.08 0)
				(effects
					(font
						(size 1.27 1.27)
						(thickness 0.15)
					)
					(justify left bottom)
				)
			)
			(property "Value" "C_1u_0402_20"
				(at 20.32 -10.16 0)
				(effects
					(font
						(size 1.27 1.27)
						(thickness 0.15)
					)
					(justify left bottom)
					(hide yes)
				)
			)
			(property "Footprint" "thunderbolt-gpu-adapter-footprints:C_0402_1005Metric"
				(at 20.32 -12.7 0)
				(effects
					(font
						(size 1.27 1.27)
						(thickness 0.15)
					)
					(justify left bottom)
					(hide yes)
				)
			)
			(property "Datasheet" ""
				(at 20.32 -15.24 0)
				(effects
					(font
						(size 1.27 1.27)
						(thickness 0.15)
					)
					(justify left bottom)
					(hide yes)
				)
			)
			(property "Description" ""
				(at 0 0 0)
				(effects
					(font
						(size 1.27 1.27)
					)
					(hide yes)
				)
			)
			(property "MPN" "C1005X6S1A105K050BC"
				(at 20.32 -17.78 0)
				(effects
					(font
						(size 1.27 1.27)
						(thickness 0.15)
					)
					(justify left bottom)
					(hide yes)
				)
			)
			(property "Manufacturer" "TDK"
				(at 20.32 -20.32 0)
				(effects
					(font
						(size 1.27 1.27)
						(thickness 0.15)
					)
					(justify left bottom)
					(hide yes)
				)
			)
			(property "License" "Apache-2.0"
				(at 20.32 -22.86 0)
				(effects
					(font
						(size 1.27 1.27)
						(thickness 0.15)
					)
					(justify left bottom)
					(hide yes)
				)
			)
			(property "Author" "Antmicro"
				(at 20.32 -25.4 0)
				(effects
					(font
						(size 1.27 1.27)
						(thickness 0.15)
					)
					(justify left bottom)
					(hide yes)
				)
			)
			(property "Val" "1u"
				(at 20.32 -7.62 0)
				(effects
					(font
						(size 1.27 1.27)
						(thickness 0.15)
					)
					(justify left bottom)
				)
			)
			(property "Voltage" ""
				(at 20.32 -27.94 0)
				(effects
					(font
						(size 1.27 1.27)
					)
					(justify left bottom)
					(hide yes)
				)
			)
			(property "Dielectric" ""
				(at 20.32 -30.48 0)
				(effects
					(font
						(size 1.27 1.27)
					)
					(justify left bottom)
					(hide yes)
				)
			)
			(symbol "C_1u_0402_20_0_1"
				(polyline
					(pts
						(xy 2.032 -1.524) (xy 2.032 1.524)
					)
					(stroke
						(width 0.3048)
						(type default)
					)
					(fill
						(type none)
					)
				)
				(polyline
					(pts
						(xy 3.048 -1.524) (xy 3.048 1.524)
					)
					(stroke
						(width 0.3302)
						(type default)
					)
					(fill
						(type none)
					)
				)
			)
			(symbol "C_1u_0402_20_1_1"
				(pin passive line
					(at 0 0 0)
					(length 2.032)
					(name "~"
						(effects
							(font
								(size 1.27 1.27)
							)
						)
					)
					(number "1"
						(effects
							(font
								(size 1.27 1.27)
							)
						)
					)
				)
				(pin passive line
					(at 5.08 0 180)
					(length 2.032)
					(name "~"
						(effects
							(font
								(size 1.27 1.27)
							)
						)
					)
					(number "2"
						(effects
							(font
								(size 1.27 1.27)
							)
						)
					)
				)
			)
		)
	(symbol "thunderbolt-gpu-adapter:C_1u_0402_21"
			(pin_numbers
				(hide yes)
			)
			(pin_names
				(hide yes)
			)
			(exclude_from_sim no)
			(in_bom yes)
			(on_board yes)
			(property "Reference" "C"
				(at 20.32 -5.08 0)
				(effects
					(font
						(size 1.27 1.27)
						(thickness 0.15)
					)
					(justify left bottom)
				)
			)
			(property "Value" "C_1u_0402_21"
				(at 20.32 -10.16 0)
				(effects
					(font
						(size 1.27 1.27)
						(thickness 0.15)
					)
					(justify left bottom)
					(hide yes)
				)
			)
			(property "Footprint" "thunderbolt-gpu-adapter-footprints:C_0402_1005Metric"
				(at 20.32 -12.7 0)
				(effects
					(font
						(size 1.27 1.27)
						(thickness 0.15)
					)
					(justify left bottom)
					(hide yes)
				)
			)
			(property "Datasheet" ""
				(at 20.32 -15.24 0)
				(effects
					(font
						(size 1.27 1.27)
						(thickness 0.15)
					)
					(justify left bottom)
					(hide yes)
				)
			)
			(property "Description" ""
				(at 0 0 0)
				(effects
					(font
						(size 1.27 1.27)
					)
					(hide yes)
				)
			)
			(property "MPN" "C1005X6S1A105K050BC"
				(at 20.32 -17.78 0)
				(effects
					(font
						(size 1.27 1.27)
						(thickness 0.15)
					)
					(justify left bottom)
					(hide yes)
				)
			)
			(property "Manufacturer" "TDK"
				(at 20.32 -20.32 0)
				(effects
					(font
						(size 1.27 1.27)
						(thickness 0.15)
					)
					(justify left bottom)
					(hide yes)
				)
			)
			(property "License" "Apache-2.0"
				(at 20.32 -22.86 0)
				(effects
					(font
						(size 1.27 1.27)
						(thickness 0.15)
					)
					(justify left bottom)
					(hide yes)
				)
			)
			(property "Author" "Antmicro"
				(at 20.32 -25.4 0)
				(effects
					(font
						(size 1.27 1.27)
						(thickness 0.15)
					)
					(justify left bottom)
					(hide yes)
				)
			)
			(property "Val" "1u"
				(at 20.32 -7.62 0)
				(effects
					(font
						(size 1.27 1.27)
						(thickness 0.15)
					)
					(justify left bottom)
				)
			)
			(property "Voltage" ""
				(at 20.32 -27.94 0)
				(effects
					(font
						(size 1.27 1.27)
					)
					(justify left bottom)
					(hide yes)
				)
			)
			(property "Dielectric" ""
				(at 20.32 -30.48 0)
				(effects
					(font
						(size 1.27 1.27)
					)
					(justify left bottom)
					(hide yes)
				)
			)
			(symbol "C_1u_0402_21_0_1"
				(polyline
					(pts
						(xy 2.032 -1.524) (xy 2.032 1.524)
					)
					(stroke
						(width 0.3048)
						(type default)
					)
					(fill
						(type none)
					)
				)
				(polyline
					(pts
						(xy 3.048 -1.524) (xy 3.048 1.524)
					)
					(stroke
						(width 0.3302)
						(type default)
					)
					(fill
						(type none)
					)
				)
			)
			(symbol "C_1u_0402_21_1_1"
				(pin passive line
					(at 0 0 0)
					(length 2.032)
					(name "~"
						(effects
							(font
								(size 1.27 1.27)
							)
						)
					)
					(number "1"
						(effects
							(font
								(size 1.27 1.27)
							)
						)
					)
				)
				(pin passive line
					(at 5.08 0 180)
					(length 2.032)
					(name "~"
						(effects
							(font
								(size 1.27 1.27)
							)
						)
					)
					(number "2"
						(effects
							(font
								(size 1.27 1.27)
							)
						)
					)
				)
			)
		)
	(symbol "thunderbolt-gpu-adapter:C_1u_0402_22"
			(pin_numbers
				(hide yes)
			)
			(pin_names
				(hide yes)
			)
			(exclude_from_sim no)
			(in_bom yes)
			(on_board yes)
			(property "Reference" "C"
				(at 20.32 -5.08 0)
				(effects
					(font
						(size 1.27 1.27)
						(thickness 0.15)
					)
					(justify left bottom)
				)
			)
			(property "Value" "C_1u_0402_22"
				(at 20.32 -10.16 0)
				(effects
					(font
						(size 1.27 1.27)
						(thickness 0.15)
					)
					(justify left bottom)
					(hide yes)
				)
			)
			(property "Footprint" "thunderbolt-gpu-adapter-footprints:C_0402_1005Metric"
				(at 20.32 -12.7 0)
				(effects
					(font
						(size 1.27 1.27)
						(thickness 0.15)
					)
					(justify left bottom)
					(hide yes)
				)
			)
			(property "Datasheet" ""
				(at 20.32 -15.24 0)
				(effects
					(font
						(size 1.27 1.27)
						(thickness 0.15)
					)
					(justify left bottom)
					(hide yes)
				)
			)
			(property "Description" ""
				(at 0 0 0)
				(effects
					(font
						(size 1.27 1.27)
					)
					(hide yes)
				)
			)
			(property "MPN" "C1005X6S1A105K050BC"
				(at 20.32 -17.78 0)
				(effects
					(font
						(size 1.27 1.27)
						(thickness 0.15)
					)
					(justify left bottom)
					(hide yes)
				)
			)
			(property "Manufacturer" "TDK"
				(at 20.32 -20.32 0)
				(effects
					(font
						(size 1.27 1.27)
						(thickness 0.15)
					)
					(justify left bottom)
					(hide yes)
				)
			)
			(property "License" "Apache-2.0"
				(at 20.32 -22.86 0)
				(effects
					(font
						(size 1.27 1.27)
						(thickness 0.15)
					)
					(justify left bottom)
					(hide yes)
				)
			)
			(property "Author" "Antmicro"
				(at 20.32 -25.4 0)
				(effects
					(font
						(size 1.27 1.27)
						(thickness 0.15)
					)
					(justify left bottom)
					(hide yes)
				)
			)
			(property "Val" "1u"
				(at 20.32 -7.62 0)
				(effects
					(font
						(size 1.27 1.27)
						(thickness 0.15)
					)
					(justify left bottom)
				)
			)
			(property "Voltage" ""
				(at 20.32 -27.94 0)
				(effects
					(font
						(size 1.27 1.27)
					)
					(justify left bottom)
					(hide yes)
				)
			)
			(property "Dielectric" ""
				(at 20.32 -30.48 0)
				(effects
					(font
						(size 1.27 1.27)
					)
					(justify left bottom)
					(hide yes)
				)
			)
			(symbol "C_1u_0402_22_0_1"
				(polyline
					(pts
						(xy 2.032 -1.524) (xy 2.032 1.524)
					)
					(stroke
						(width 0.3048)
						(type default)
					)
					(fill
						(type none)
					)
				)
				(polyline
					(pts
						(xy 3.048 -1.524) (xy 3.048 1.524)
					)
					(stroke
						(width 0.3302)
						(type default)
					)
					(fill
						(type none)
					)
				)
			)
			(symbol "C_1u_0402_22_1_1"
				(pin passive line
					(at 0 0 0)
					(length 2.032)
					(name "~"
						(effects
							(font
								(size 1.27 1.27)
							)
						)
					)
					(number "1"
						(effects
							(font
								(size 1.27 1.27)
							)
						)
					)
				)
				(pin passive line
					(at 5.08 0 180)
					(length 2.032)
					(name "~"
						(effects
							(font
								(size 1.27 1.27)
							)
						)
					)
					(number "2"
						(effects
							(font
								(size 1.27 1.27)
							)
						)
					)
				)
			)
		)
	(symbol "thunderbolt-gpu-adapter:C_1u_0402_23"
			(pin_numbers
				(hide yes)
			)
			(pin_names
				(hide yes)
			)
			(exclude_from_sim no)
			(in_bom yes)
			(on_board yes)
			(property "Reference" "C"
				(at 20.32 -5.08 0)
				(effects
					(font
						(size 1.27 1.27)
						(thickness 0.15)
					)
					(justify left bottom)
				)
			)
			(property "Value" "C_1u_0402_23"
				(at 20.32 -10.16 0)
				(effects
					(font
						(size 1.27 1.27)
						(thickness 0.15)
					)
					(justify left bottom)
					(hide yes)
				)
			)
			(property "Footprint" "thunderbolt-gpu-adapter-footprints:C_0402_1005Metric"
				(at 20.32 -12.7 0)
				(effects
					(font
						(size 1.27 1.27)
						(thickness 0.15)
					)
					(justify left bottom)
					(hide yes)
				)
			)
			(property "Datasheet" ""
				(at 20.32 -15.24 0)
				(effects
					(font
						(size 1.27 1.27)
						(thickness 0.15)
					)
					(justify left bottom)
					(hide yes)
				)
			)
			(property "Description" ""
				(at 0 0 0)
				(effects
					(font
						(size 1.27 1.27)
					)
					(hide yes)
				)
			)
			(property "MPN" "C1005X6S1A105K050BC"
				(at 20.32 -17.78 0)
				(effects
					(font
						(size 1.27 1.27)
						(thickness 0.15)
					)
					(justify left bottom)
					(hide yes)
				)
			)
			(property "Manufacturer" "TDK"
				(at 20.32 -20.32 0)
				(effects
					(font
						(size 1.27 1.27)
						(thickness 0.15)
					)
					(justify left bottom)
					(hide yes)
				)
			)
			(property "License" "Apache-2.0"
				(at 20.32 -22.86 0)
				(effects
					(font
						(size 1.27 1.27)
						(thickness 0.15)
					)
					(justify left bottom)
					(hide yes)
				)
			)
			(property "Author" "Antmicro"
				(at 20.32 -25.4 0)
				(effects
					(font
						(size 1.27 1.27)
						(thickness 0.15)
					)
					(justify left bottom)
					(hide yes)
				)
			)
			(property "Val" "1u"
				(at 20.32 -7.62 0)
				(effects
					(font
						(size 1.27 1.27)
						(thickness 0.15)
					)
					(justify left bottom)
				)
			)
			(property "Voltage" ""
				(at 20.32 -27.94 0)
				(effects
					(font
						(size 1.27 1.27)
					)
					(justify left bottom)
					(hide yes)
				)
			)
			(property "Dielectric" ""
				(at 20.32 -30.48 0)
				(effects
					(font
						(size 1.27 1.27)
					)
					(justify left bottom)
					(hide yes)
				)
			)
			(symbol "C_1u_0402_23_0_1"
				(polyline
					(pts
						(xy 2.032 -1.524) (xy 2.032 1.524)
					)
					(stroke
						(width 0.3048)
						(type default)
					)
					(fill
						(type none)
					)
				)
				(polyline
					(pts
						(xy 3.048 -1.524) (xy 3.048 1.524)
					)
					(stroke
						(width 0.3302)
						(type default)
					)
					(fill
						(type none)
					)
				)
			)
			(symbol "C_1u_0402_23_1_1"
				(pin passive line
					(at 0 0 0)
					(length 2.032)
					(name "~"
						(effects
							(font
								(size 1.27 1.27)
							)
						)
					)
					(number "1"
						(effects
							(font
								(size 1.27 1.27)
							)
						)
					)
				)
				(pin passive line
					(at 5.08 0 180)
					(length 2.032)
					(name "~"
						(effects
							(font
								(size 1.27 1.27)
							)
						)
					)
					(number "2"
						(effects
							(font
								(size 1.27 1.27)
							)
						)
					)
				)
			)
		)
	(symbol "thunderbolt-gpu-adapter:C_1u_0402_24"
			(pin_numbers
				(hide yes)
			)
			(pin_names
				(hide yes)
			)
			(exclude_from_sim no)
			(in_bom yes)
			(on_board yes)
			(property "Reference" "C"
				(at 20.32 -5.08 0)
				(effects
					(font
						(size 1.27 1.27)
						(thickness 0.15)
					)
					(justify left bottom)
				)
			)
			(property "Value" "C_1u_0402_24"
				(at 20.32 -10.16 0)
				(effects
					(font
						(size 1.27 1.27)
						(thickness 0.15)
					)
					(justify left bottom)
					(hide yes)
				)
			)
			(property "Footprint" "thunderbolt-gpu-adapter-footprints:C_0402_1005Metric"
				(at 20.32 -12.7 0)
				(effects
					(font
						(size 1.27 1.27)
						(thickness 0.15)
					)
					(justify left bottom)
					(hide yes)
				)
			)
			(property "Datasheet" ""
				(at 20.32 -15.24 0)
				(effects
					(font
						(size 1.27 1.27)
						(thickness 0.15)
					)
					(justify left bottom)
					(hide yes)
				)
			)
			(property "Description" ""
				(at 0 0 0)
				(effects
					(font
						(size 1.27 1.27)
					)
					(hide yes)
				)
			)
			(property "MPN" "C1005X6S1A105K050BC"
				(at 20.32 -17.78 0)
				(effects
					(font
						(size 1.27 1.27)
						(thickness 0.15)
					)
					(justify left bottom)
					(hide yes)
				)
			)
			(property "Manufacturer" "TDK"
				(at 20.32 -20.32 0)
				(effects
					(font
						(size 1.27 1.27)
						(thickness 0.15)
					)
					(justify left bottom)
					(hide yes)
				)
			)
			(property "License" "Apache-2.0"
				(at 20.32 -22.86 0)
				(effects
					(font
						(size 1.27 1.27)
						(thickness 0.15)
					)
					(justify left bottom)
					(hide yes)
				)
			)
			(property "Author" "Antmicro"
				(at 20.32 -25.4 0)
				(effects
					(font
						(size 1.27 1.27)
						(thickness 0.15)
					)
					(justify left bottom)
					(hide yes)
				)
			)
			(property "Val" "1u"
				(at 20.32 -7.62 0)
				(effects
					(font
						(size 1.27 1.27)
						(thickness 0.15)
					)
					(justify left bottom)
				)
			)
			(property "Voltage" ""
				(at 20.32 -27.94 0)
				(effects
					(font
						(size 1.27 1.27)
					)
					(justify left bottom)
					(hide yes)
				)
			)
			(property "Dielectric" ""
				(at 20.32 -30.48 0)
				(effects
					(font
						(size 1.27 1.27)
					)
					(justify left bottom)
					(hide yes)
				)
			)
			(symbol "C_1u_0402_24_0_1"
				(polyline
					(pts
						(xy 2.032 -1.524) (xy 2.032 1.524)
					)
					(stroke
						(width 0.3048)
						(type default)
					)
					(fill
						(type none)
					)
				)
				(polyline
					(pts
						(xy 3.048 -1.524) (xy 3.048 1.524)
					)
					(stroke
						(width 0.3302)
						(type default)
					)
					(fill
						(type none)
					)
				)
			)
			(symbol "C_1u_0402_24_1_1"
				(pin passive line
					(at 0 0 0)
					(length 2.032)
					(name "~"
						(effects
							(font
								(size 1.27 1.27)
							)
						)
					)
					(number "1"
						(effects
							(font
								(size 1.27 1.27)
							)
						)
					)
				)
				(pin passive line
					(at 5.08 0 180)
					(length 2.032)
					(name "~"
						(effects
							(font
								(size 1.27 1.27)
							)
						)
					)
					(number "2"
						(effects
							(font
								(size 1.27 1.27)
							)
						)
					)
				)
			)
		)
	(symbol "thunderbolt-gpu-adapter:C_1u_0402_25"
			(pin_numbers
				(hide yes)
			)
			(pin_names
				(hide yes)
			)
			(exclude_from_sim no)
			(in_bom yes)
			(on_board yes)
			(property "Reference" "C"
				(at 20.32 -5.08 0)
				(effects
					(font
						(size 1.27 1.27)
						(thickness 0.15)
					)
					(justify left bottom)
				)
			)
			(property "Value" "C_1u_0402_25"
				(at 20.32 -10.16 0)
				(effects
					(font
						(size 1.27 1.27)
						(thickness 0.15)
					)
					(justify left bottom)
					(hide yes)
				)
			)
			(property "Footprint" "thunderbolt-gpu-adapter-footprints:C_0402_1005Metric"
				(at 20.32 -12.7 0)
				(effects
					(font
						(size 1.27 1.27)
						(thickness 0.15)
					)
					(justify left bottom)
					(hide yes)
				)
			)
			(property "Datasheet" ""
				(at 20.32 -15.24 0)
				(effects
					(font
						(size 1.27 1.27)
						(thickness 0.15)
					)
					(justify left bottom)
					(hide yes)
				)
			)
			(property "Description" ""
				(at 0 0 0)
				(effects
					(font
						(size 1.27 1.27)
					)
					(hide yes)
				)
			)
			(property "MPN" "C1005X6S1A105K050BC"
				(at 20.32 -17.78 0)
				(effects
					(font
						(size 1.27 1.27)
						(thickness 0.15)
					)
					(justify left bottom)
					(hide yes)
				)
			)
			(property "Manufacturer" "TDK"
				(at 20.32 -20.32 0)
				(effects
					(font
						(size 1.27 1.27)
						(thickness 0.15)
					)
					(justify left bottom)
					(hide yes)
				)
			)
			(property "License" "Apache-2.0"
				(at 20.32 -22.86 0)
				(effects
					(font
						(size 1.27 1.27)
						(thickness 0.15)
					)
					(justify left bottom)
					(hide yes)
				)
			)
			(property "Author" "Antmicro"
				(at 20.32 -25.4 0)
				(effects
					(font
						(size 1.27 1.27)
						(thickness 0.15)
					)
					(justify left bottom)
					(hide yes)
				)
			)
			(property "Val" "1u"
				(at 20.32 -7.62 0)
				(effects
					(font
						(size 1.27 1.27)
						(thickness 0.15)
					)
					(justify left bottom)
				)
			)
			(property "Voltage" ""
				(at 20.32 -27.94 0)
				(effects
					(font
						(size 1.27 1.27)
					)
					(justify left bottom)
					(hide yes)
				)
			)
			(property "Dielectric" ""
				(at 20.32 -30.48 0)
				(effects
					(font
						(size 1.27 1.27)
					)
					(justify left bottom)
					(hide yes)
				)
			)
			(symbol "C_1u_0402_25_0_1"
				(polyline
					(pts
						(xy 2.032 -1.524) (xy 2.032 1.524)
					)
					(stroke
						(width 0.3048)
						(type default)
					)
					(fill
						(type none)
					)
				)
				(polyline
					(pts
						(xy 3.048 -1.524) (xy 3.048 1.524)
					)
					(stroke
						(width 0.3302)
						(type default)
					)
					(fill
						(type none)
					)
				)
			)
			(symbol "C_1u_0402_25_1_1"
				(pin passive line
					(at 0 0 0)
					(length 2.032)
					(name "~"
						(effects
							(font
								(size 1.27 1.27)
							)
						)
					)
					(number "1"
						(effects
							(font
								(size 1.27 1.27)
							)
						)
					)
				)
				(pin passive line
					(at 5.08 0 180)
					(length 2.032)
					(name "~"
						(effects
							(font
								(size 1.27 1.27)
							)
						)
					)
					(number "2"
						(effects
							(font
								(size 1.27 1.27)
							)
						)
					)
				)
			)
		)
	(symbol "thunderbolt-gpu-adapter:C_1u_0402_26"
			(pin_numbers
				(hide yes)
			)
			(pin_names
				(hide yes)
			)
			(exclude_from_sim no)
			(in_bom yes)
			(on_board yes)
			(property "Reference" "C"
				(at 20.32 -5.08 0)
				(effects
					(font
						(size 1.27 1.27)
						(thickness 0.15)
					)
					(justify left bottom)
				)
			)
			(property "Value" "C_1u_0402_26"
				(at 20.32 -10.16 0)
				(effects
					(font
						(size 1.27 1.27)
						(thickness 0.15)
					)
					(justify left bottom)
					(hide yes)
				)
			)
			(property "Footprint" "thunderbolt-gpu-adapter-footprints:C_0402_1005Metric"
				(at 20.32 -12.7 0)
				(effects
					(font
						(size 1.27 1.27)
						(thickness 0.15)
					)
					(justify left bottom)
					(hide yes)
				)
			)
			(property "Datasheet" ""
				(at 20.32 -15.24 0)
				(effects
					(font
						(size 1.27 1.27)
						(thickness 0.15)
					)
					(justify left bottom)
					(hide yes)
				)
			)
			(property "Description" ""
				(at 0 0 0)
				(effects
					(font
						(size 1.27 1.27)
					)
					(hide yes)
				)
			)
			(property "MPN" "C1005X6S1A105K050BC"
				(at 20.32 -17.78 0)
				(effects
					(font
						(size 1.27 1.27)
						(thickness 0.15)
					)
					(justify left bottom)
					(hide yes)
				)
			)
			(property "Manufacturer" "TDK"
				(at 20.32 -20.32 0)
				(effects
					(font
						(size 1.27 1.27)
						(thickness 0.15)
					)
					(justify left bottom)
					(hide yes)
				)
			)
			(property "License" "Apache-2.0"
				(at 20.32 -22.86 0)
				(effects
					(font
						(size 1.27 1.27)
						(thickness 0.15)
					)
					(justify left bottom)
					(hide yes)
				)
			)
			(property "Author" "Antmicro"
				(at 20.32 -25.4 0)
				(effects
					(font
						(size 1.27 1.27)
						(thickness 0.15)
					)
					(justify left bottom)
					(hide yes)
				)
			)
			(property "Val" "1u"
				(at 20.32 -7.62 0)
				(effects
					(font
						(size 1.27 1.27)
						(thickness 0.15)
					)
					(justify left bottom)
				)
			)
			(property "Voltage" ""
				(at 20.32 -27.94 0)
				(effects
					(font
						(size 1.27 1.27)
					)
					(justify left bottom)
					(hide yes)
				)
			)
			(property "Dielectric" ""
				(at 20.32 -30.48 0)
				(effects
					(font
						(size 1.27 1.27)
					)
					(justify left bottom)
					(hide yes)
				)
			)
			(symbol "C_1u_0402_26_0_1"
				(polyline
					(pts
						(xy 2.032 -1.524) (xy 2.032 1.524)
					)
					(stroke
						(width 0.3048)
						(type default)
					)
					(fill
						(type none)
					)
				)
				(polyline
					(pts
						(xy 3.048 -1.524) (xy 3.048 1.524)
					)
					(stroke
						(width 0.3302)
						(type default)
					)
					(fill
						(type none)
					)
				)
			)
			(symbol "C_1u_0402_26_1_1"
				(pin passive line
					(at 0 0 0)
					(length 2.032)
					(name "~"
						(effects
							(font
								(size 1.27 1.27)
							)
						)
					)
					(number "1"
						(effects
							(font
								(size 1.27 1.27)
							)
						)
					)
				)
				(pin passive line
					(at 5.08 0 180)
					(length 2.032)
					(name "~"
						(effects
							(font
								(size 1.27 1.27)
							)
						)
					)
					(number "2"
						(effects
							(font
								(size 1.27 1.27)
							)
						)
					)
				)
			)
		)
	(symbol "thunderbolt-gpu-adapter:C_1u_0402_27"
			(pin_numbers
				(hide yes)
			)
			(pin_names
				(hide yes)
			)
			(exclude_from_sim no)
			(in_bom yes)
			(on_board yes)
			(property "Reference" "C"
				(at 20.32 -5.08 0)
				(effects
					(font
						(size 1.27 1.27)
						(thickness 0.15)
					)
					(justify left bottom)
				)
			)
			(property "Value" "C_1u_0402_27"
				(at 20.32 -10.16 0)
				(effects
					(font
						(size 1.27 1.27)
						(thickness 0.15)
					)
					(justify left bottom)
					(hide yes)
				)
			)
			(property "Footprint" "thunderbolt-gpu-adapter-footprints:C_0402_1005Metric"
				(at 20.32 -12.7 0)
				(effects
					(font
						(size 1.27 1.27)
						(thickness 0.15)
					)
					(justify left bottom)
					(hide yes)
				)
			)
			(property "Datasheet" ""
				(at 20.32 -15.24 0)
				(effects
					(font
						(size 1.27 1.27)
						(thickness 0.15)
					)
					(justify left bottom)
					(hide yes)
				)
			)
			(property "Description" ""
				(at 0 0 0)
				(effects
					(font
						(size 1.27 1.27)
					)
					(hide yes)
				)
			)
			(property "MPN" "C1005X6S1A105K050BC"
				(at 20.32 -17.78 0)
				(effects
					(font
						(size 1.27 1.27)
						(thickness 0.15)
					)
					(justify left bottom)
					(hide yes)
				)
			)
			(property "Manufacturer" "TDK"
				(at 20.32 -20.32 0)
				(effects
					(font
						(size 1.27 1.27)
						(thickness 0.15)
					)
					(justify left bottom)
					(hide yes)
				)
			)
			(property "License" "Apache-2.0"
				(at 20.32 -22.86 0)
				(effects
					(font
						(size 1.27 1.27)
						(thickness 0.15)
					)
					(justify left bottom)
					(hide yes)
				)
			)
			(property "Author" "Antmicro"
				(at 20.32 -25.4 0)
				(effects
					(font
						(size 1.27 1.27)
						(thickness 0.15)
					)
					(justify left bottom)
					(hide yes)
				)
			)
			(property "Val" "1u"
				(at 20.32 -7.62 0)
				(effects
					(font
						(size 1.27 1.27)
						(thickness 0.15)
					)
					(justify left bottom)
				)
			)
			(property "Voltage" ""
				(at 20.32 -27.94 0)
				(effects
					(font
						(size 1.27 1.27)
					)
					(justify left bottom)
					(hide yes)
				)
			)
			(property "Dielectric" ""
				(at 20.32 -30.48 0)
				(effects
					(font
						(size 1.27 1.27)
					)
					(justify left bottom)
					(hide yes)
				)
			)
			(symbol "C_1u_0402_27_0_1"
				(polyline
					(pts
						(xy 2.032 -1.524) (xy 2.032 1.524)
					)
					(stroke
						(width 0.3048)
						(type default)
					)
					(fill
						(type none)
					)
				)
				(polyline
					(pts
						(xy 3.048 -1.524) (xy 3.048 1.524)
					)
					(stroke
						(width 0.3302)
						(type default)
					)
					(fill
						(type none)
					)
				)
			)
			(symbol "C_1u_0402_27_1_1"
				(pin passive line
					(at 0 0 0)
					(length 2.032)
					(name "~"
						(effects
							(font
								(size 1.27 1.27)
							)
						)
					)
					(number "1"
						(effects
							(font
								(size 1.27 1.27)
							)
						)
					)
				)
				(pin passive line
					(at 5.08 0 180)
					(length 2.032)
					(name "~"
						(effects
							(font
								(size 1.27 1.27)
							)
						)
					)
					(number "2"
						(effects
							(font
								(size 1.27 1.27)
							)
						)
					)
				)
			)
		)
	(symbol "thunderbolt-gpu-adapter:C_1u_0402_28"
			(pin_numbers
				(hide yes)
			)
			(pin_names
				(hide yes)
			)
			(exclude_from_sim no)
			(in_bom yes)
			(on_board yes)
			(property "Reference" "C"
				(at 20.32 -5.08 0)
				(effects
					(font
						(size 1.27 1.27)
						(thickness 0.15)
					)
					(justify left bottom)
				)
			)
			(property "Value" "C_1u_0402_28"
				(at 20.32 -10.16 0)
				(effects
					(font
						(size 1.27 1.27)
						(thickness 0.15)
					)
					(justify left bottom)
					(hide yes)
				)
			)
			(property "Footprint" "thunderbolt-gpu-adapter-footprints:C_0402_1005Metric"
				(at 20.32 -12.7 0)
				(effects
					(font
						(size 1.27 1.27)
						(thickness 0.15)
					)
					(justify left bottom)
					(hide yes)
				)
			)
			(property "Datasheet" ""
				(at 20.32 -15.24 0)
				(effects
					(font
						(size 1.27 1.27)
						(thickness 0.15)
					)
					(justify left bottom)
					(hide yes)
				)
			)
			(property "Description" ""
				(at 0 0 0)
				(effects
					(font
						(size 1.27 1.27)
					)
					(hide yes)
				)
			)
			(property "MPN" "C1005X6S1A105K050BC"
				(at 20.32 -17.78 0)
				(effects
					(font
						(size 1.27 1.27)
						(thickness 0.15)
					)
					(justify left bottom)
					(hide yes)
				)
			)
			(property "Manufacturer" "TDK"
				(at 20.32 -20.32 0)
				(effects
					(font
						(size 1.27 1.27)
						(thickness 0.15)
					)
					(justify left bottom)
					(hide yes)
				)
			)
			(property "License" "Apache-2.0"
				(at 20.32 -22.86 0)
				(effects
					(font
						(size 1.27 1.27)
						(thickness 0.15)
					)
					(justify left bottom)
					(hide yes)
				)
			)
			(property "Author" "Antmicro"
				(at 20.32 -25.4 0)
				(effects
					(font
						(size 1.27 1.27)
						(thickness 0.15)
					)
					(justify left bottom)
					(hide yes)
				)
			)
			(property "Val" "1u"
				(at 20.32 -7.62 0)
				(effects
					(font
						(size 1.27 1.27)
						(thickness 0.15)
					)
					(justify left bottom)
				)
			)
			(property "Voltage" ""
				(at 20.32 -27.94 0)
				(effects
					(font
						(size 1.27 1.27)
					)
					(justify left bottom)
					(hide yes)
				)
			)
			(property "Dielectric" ""
				(at 20.32 -30.48 0)
				(effects
					(font
						(size 1.27 1.27)
					)
					(justify left bottom)
					(hide yes)
				)
			)
			(symbol "C_1u_0402_28_0_1"
				(polyline
					(pts
						(xy 2.032 -1.524) (xy 2.032 1.524)
					)
					(stroke
						(width 0.3048)
						(type default)
					)
					(fill
						(type none)
					)
				)
				(polyline
					(pts
						(xy 3.048 -1.524) (xy 3.048 1.524)
					)
					(stroke
						(width 0.3302)
						(type default)
					)
					(fill
						(type none)
					)
				)
			)
			(symbol "C_1u_0402_28_1_1"
				(pin passive line
					(at 0 0 0)
					(length 2.032)
					(name "~"
						(effects
							(font
								(size 1.27 1.27)
							)
						)
					)
					(number "1"
						(effects
							(font
								(size 1.27 1.27)
							)
						)
					)
				)
				(pin passive line
					(at 5.08 0 180)
					(length 2.032)
					(name "~"
						(effects
							(font
								(size 1.27 1.27)
							)
						)
					)
					(number "2"
						(effects
							(font
								(size 1.27 1.27)
							)
						)
					)
				)
			)
		)
	(symbol "thunderbolt-gpu-adapter:C_1u_0402_29"
			(pin_numbers
				(hide yes)
			)
			(pin_names
				(hide yes)
			)
			(exclude_from_sim no)
			(in_bom yes)
			(on_board yes)
			(property "Reference" "C"
				(at 20.32 -5.08 0)
				(effects
					(font
						(size 1.27 1.27)
						(thickness 0.15)
					)
					(justify left bottom)
				)
			)
			(property "Value" "C_1u_0402_29"
				(at 20.32 -10.16 0)
				(effects
					(font
						(size 1.27 1.27)
						(thickness 0.15)
					)
					(justify left bottom)
					(hide yes)
				)
			)
			(property "Footprint" "thunderbolt-gpu-adapter-footprints:C_0402_1005Metric"
				(at 20.32 -12.7 0)
				(effects
					(font
						(size 1.27 1.27)
						(thickness 0.15)
					)
					(justify left bottom)
					(hide yes)
				)
			)
			(property "Datasheet" ""
				(at 20.32 -15.24 0)
				(effects
					(font
						(size 1.27 1.27)
						(thickness 0.15)
					)
					(justify left bottom)
					(hide yes)
				)
			)
			(property "Description" ""
				(at 0 0 0)
				(effects
					(font
						(size 1.27 1.27)
					)
					(hide yes)
				)
			)
			(property "MPN" "C1005X6S1A105K050BC"
				(at 20.32 -17.78 0)
				(effects
					(font
						(size 1.27 1.27)
						(thickness 0.15)
					)
					(justify left bottom)
					(hide yes)
				)
			)
			(property "Manufacturer" "TDK"
				(at 20.32 -20.32 0)
				(effects
					(font
						(size 1.27 1.27)
						(thickness 0.15)
					)
					(justify left bottom)
					(hide yes)
				)
			)
			(property "License" "Apache-2.0"
				(at 20.32 -22.86 0)
				(effects
					(font
						(size 1.27 1.27)
						(thickness 0.15)
					)
					(justify left bottom)
					(hide yes)
				)
			)
			(property "Author" "Antmicro"
				(at 20.32 -25.4 0)
				(effects
					(font
						(size 1.27 1.27)
						(thickness 0.15)
					)
					(justify left bottom)
					(hide yes)
				)
			)
			(property "Val" "1u"
				(at 20.32 -7.62 0)
				(effects
					(font
						(size 1.27 1.27)
						(thickness 0.15)
					)
					(justify left bottom)
				)
			)
			(property "Voltage" ""
				(at 20.32 -27.94 0)
				(effects
					(font
						(size 1.27 1.27)
					)
					(justify left bottom)
					(hide yes)
				)
			)
			(property "Dielectric" ""
				(at 20.32 -30.48 0)
				(effects
					(font
						(size 1.27 1.27)
					)
					(justify left bottom)
					(hide yes)
				)
			)
			(symbol "C_1u_0402_29_0_1"
				(polyline
					(pts
						(xy 2.032 -1.524) (xy 2.032 1.524)
					)
					(stroke
						(width 0.3048)
						(type default)
					)
					(fill
						(type none)
					)
				)
				(polyline
					(pts
						(xy 3.048 -1.524) (xy 3.048 1.524)
					)
					(stroke
						(width 0.3302)
						(type default)
					)
					(fill
						(type none)
					)
				)
			)
			(symbol "C_1u_0402_29_1_1"
				(pin passive line
					(at 0 0 0)
					(length 2.032)
					(name "~"
						(effects
							(font
								(size 1.27 1.27)
							)
						)
					)
					(number "1"
						(effects
							(font
								(size 1.27 1.27)
							)
						)
					)
				)
				(pin passive line
					(at 5.08 0 180)
					(length 2.032)
					(name "~"
						(effects
							(font
								(size 1.27 1.27)
							)
						)
					)
					(number "2"
						(effects
							(font
								(size 1.27 1.27)
							)
						)
					)
				)
			)
		)
	(symbol "thunderbolt-gpu-adapter:C_220n_0402_10"
			(pin_numbers
				(hide yes)
			)
			(pin_names
				(hide yes)
			)
			(exclude_from_sim no)
			(in_bom yes)
			(on_board yes)
			(property "Reference" "C"
				(at 20.32 -5.08 0)
				(effects
					(font
						(size 1.27 1.27)
						(thickness 0.15)
					)
					(justify left bottom)
				)
			)
			(property "Value" "C_220n_0402_10"
				(at 20.32 -10.16 0)
				(effects
					(font
						(size 1.27 1.27)
						(thickness 0.15)
					)
					(justify left bottom)
					(hide yes)
				)
			)
			(property "Footprint" "thunderbolt-gpu-adapter-footprints:C_0402_1005Metric"
				(at 20.32 -12.7 0)
				(effects
					(font
						(size 1.27 1.27)
						(thickness 0.15)
					)
					(justify left bottom)
					(hide yes)
				)
			)
			(property "Datasheet" ""
				(at 20.32 -15.24 0)
				(effects
					(font
						(size 1.27 1.27)
						(thickness 0.15)
					)
					(justify left bottom)
					(hide yes)
				)
			)
			(property "Description" ""
				(at 0 0 0)
				(effects
					(font
						(size 1.27 1.27)
					)
					(hide yes)
				)
			)
			(property "MPN" "CC0402KRX5R6BB224"
				(at 20.32 -17.78 0)
				(effects
					(font
						(size 1.27 1.27)
						(thickness 0.15)
					)
					(justify left bottom)
					(hide yes)
				)
			)
			(property "Manufacturer" "Yaego"
				(at 20.32 -20.32 0)
				(effects
					(font
						(size 1.27 1.27)
						(thickness 0.15)
					)
					(justify left bottom)
					(hide yes)
				)
			)
			(property "License" "Apache-2.0"
				(at 20.32 -22.86 0)
				(effects
					(font
						(size 1.27 1.27)
						(thickness 0.15)
					)
					(justify left bottom)
					(hide yes)
				)
			)
			(property "Author" "Antmicro"
				(at 20.32 -25.4 0)
				(effects
					(font
						(size 1.27 1.27)
						(thickness 0.15)
					)
					(justify left bottom)
					(hide yes)
				)
			)
			(property "Val" "220n"
				(at 20.32 -7.62 0)
				(effects
					(font
						(size 1.27 1.27)
						(thickness 0.15)
					)
					(justify left bottom)
				)
			)
			(property "Voltage" ""
				(at 20.32 -27.94 0)
				(effects
					(font
						(size 1.27 1.27)
					)
					(justify left bottom)
					(hide yes)
				)
			)
			(property "Dielectric" ""
				(at 20.32 -30.48 0)
				(effects
					(font
						(size 1.27 1.27)
					)
					(justify left bottom)
					(hide yes)
				)
			)
			(symbol "C_220n_0402_10_0_1"
				(polyline
					(pts
						(xy 2.032 -1.524) (xy 2.032 1.524)
					)
					(stroke
						(width 0.3048)
						(type default)
					)
					(fill
						(type none)
					)
				)
				(polyline
					(pts
						(xy 3.048 -1.524) (xy 3.048 1.524)
					)
					(stroke
						(width 0.3302)
						(type default)
					)
					(fill
						(type none)
					)
				)
			)
			(symbol "C_220n_0402_10_1_1"
				(pin passive line
					(at 0 0 0)
					(length 2.032)
					(name "~"
						(effects
							(font
								(size 1.27 1.27)
							)
						)
					)
					(number "1"
						(effects
							(font
								(size 1.27 1.27)
							)
						)
					)
				)
				(pin passive line
					(at 5.08 0 180)
					(length 2.032)
					(name "~"
						(effects
							(font
								(size 1.27 1.27)
							)
						)
					)
					(number "2"
						(effects
							(font
								(size 1.27 1.27)
							)
						)
					)
				)
			)
		)
	(symbol "thunderbolt-gpu-adapter:C_220n_0402_11"
			(pin_numbers
				(hide yes)
			)
			(pin_names
				(hide yes)
			)
			(exclude_from_sim no)
			(in_bom yes)
			(on_board yes)
			(property "Reference" "C"
				(at 20.32 -5.08 0)
				(effects
					(font
						(size 1.27 1.27)
						(thickness 0.15)
					)
					(justify left bottom)
				)
			)
			(property "Value" "C_220n_0402_11"
				(at 20.32 -10.16 0)
				(effects
					(font
						(size 1.27 1.27)
						(thickness 0.15)
					)
					(justify left bottom)
					(hide yes)
				)
			)
			(property "Footprint" "thunderbolt-gpu-adapter-footprints:C_0402_1005Metric"
				(at 20.32 -12.7 0)
				(effects
					(font
						(size 1.27 1.27)
						(thickness 0.15)
					)
					(justify left bottom)
					(hide yes)
				)
			)
			(property "Datasheet" ""
				(at 20.32 -15.24 0)
				(effects
					(font
						(size 1.27 1.27)
						(thickness 0.15)
					)
					(justify left bottom)
					(hide yes)
				)
			)
			(property "Description" ""
				(at 0 0 0)
				(effects
					(font
						(size 1.27 1.27)
					)
					(hide yes)
				)
			)
			(property "MPN" "CC0402KRX5R6BB224"
				(at 20.32 -17.78 0)
				(effects
					(font
						(size 1.27 1.27)
						(thickness 0.15)
					)
					(justify left bottom)
					(hide yes)
				)
			)
			(property "Manufacturer" "Yaego"
				(at 20.32 -20.32 0)
				(effects
					(font
						(size 1.27 1.27)
						(thickness 0.15)
					)
					(justify left bottom)
					(hide yes)
				)
			)
			(property "License" "Apache-2.0"
				(at 20.32 -22.86 0)
				(effects
					(font
						(size 1.27 1.27)
						(thickness 0.15)
					)
					(justify left bottom)
					(hide yes)
				)
			)
			(property "Author" "Antmicro"
				(at 20.32 -25.4 0)
				(effects
					(font
						(size 1.27 1.27)
						(thickness 0.15)
					)
					(justify left bottom)
					(hide yes)
				)
			)
			(property "Val" "220n"
				(at 20.32 -7.62 0)
				(effects
					(font
						(size 1.27 1.27)
						(thickness 0.15)
					)
					(justify left bottom)
				)
			)
			(property "Voltage" ""
				(at 20.32 -27.94 0)
				(effects
					(font
						(size 1.27 1.27)
					)
					(justify left bottom)
					(hide yes)
				)
			)
			(property "Dielectric" ""
				(at 20.32 -30.48 0)
				(effects
					(font
						(size 1.27 1.27)
					)
					(justify left bottom)
					(hide yes)
				)
			)
			(symbol "C_220n_0402_11_0_1"
				(polyline
					(pts
						(xy 2.032 -1.524) (xy 2.032 1.524)
					)
					(stroke
						(width 0.3048)
						(type default)
					)
					(fill
						(type none)
					)
				)
				(polyline
					(pts
						(xy 3.048 -1.524) (xy 3.048 1.524)
					)
					(stroke
						(width 0.3302)
						(type default)
					)
					(fill
						(type none)
					)
				)
			)
			(symbol "C_220n_0402_11_1_1"
				(pin passive line
					(at 0 0 0)
					(length 2.032)
					(name "~"
						(effects
							(font
								(size 1.27 1.27)
							)
						)
					)
					(number "1"
						(effects
							(font
								(size 1.27 1.27)
							)
						)
					)
				)
				(pin passive line
					(at 5.08 0 180)
					(length 2.032)
					(name "~"
						(effects
							(font
								(size 1.27 1.27)
							)
						)
					)
					(number "2"
						(effects
							(font
								(size 1.27 1.27)
							)
						)
					)
				)
			)
		)
	(symbol "thunderbolt-gpu-adapter:R_100k_0402_10"
			(pin_numbers
				(hide yes)
			)
			(pin_names
				(hide yes)
			)
			(exclude_from_sim no)
			(in_bom yes)
			(on_board yes)
			(property "Reference" "R"
				(at 20.32 -5.08 0)
				(effects
					(font
						(size 1.27 1.27)
						(thickness 0.15)
					)
					(justify left bottom)
				)
			)
			(property "Value" "R_100k_0402_10"
				(at 20.32 -12.7 0)
				(effects
					(font
						(size 1.27 1.27)
						(thickness 0.15)
					)
					(justify left bottom)
					(hide yes)
				)
			)
			(property "Footprint" "thunderbolt-gpu-adapter-footprints:R_0402_1005Metric"
				(at 20.32 -15.24 0)
				(effects
					(font
						(size 1.27 1.27)
						(thickness 0.15)
					)
					(justify left bottom)
					(hide yes)
				)
			)
			(property "Datasheet" "https://www.bourns.com/docs/product-datasheets/cr.pdf"
				(at 20.32 -17.78 0)
				(effects
					(font
						(size 1.27 1.27)
						(thickness 0.15)
					)
					(justify left bottom)
					(hide yes)
				)
			)
			(property "Description" "100k resistor in 0402 package with 1% tolerance"
				(at 0 0 0)
				(effects
					(font
						(size 1.27 1.27)
					)
					(hide yes)
				)
			)
			(property "MPN" "CR0402-FX-1003GLF"
				(at 20.32 -20.32 0)
				(effects
					(font
						(size 1.27 1.27)
						(thickness 0.15)
					)
					(justify left bottom)
					(hide yes)
				)
			)
			(property "Manufacturer" "Bourns"
				(at 20.32 -22.86 0)
				(effects
					(font
						(size 1.27 1.27)
						(thickness 0.15)
					)
					(justify left bottom)
					(hide yes)
				)
			)
			(property "License" "Apache-2.0"
				(at 20.32 -25.4 0)
				(effects
					(font
						(size 1.27 1.27)
						(thickness 0.15)
					)
					(justify left bottom)
					(hide yes)
				)
			)
			(property "Author" "Antmicro"
				(at 20.32 -27.94 0)
				(effects
					(font
						(size 1.27 1.27)
						(thickness 0.15)
					)
					(justify left bottom)
					(hide yes)
				)
			)
			(property "Val" "100k"
				(at 20.32 -7.62 0)
				(effects
					(font
						(size 1.27 1.27)
						(thickness 0.15)
					)
					(justify left bottom)
				)
			)
			(property "Tolerance" "1%"
				(at 20.32 -10.16 0)
				(effects
					(font
						(size 1.27 1.27)
					)
					(justify left bottom)
					(hide yes)
				)
			)
			(symbol "R_100k_0402_10_0_1"
				(rectangle
					(start 0.635 0.889)
					(end 4.445 -0.889)
					(stroke
						(width 0.254)
						(type default)
					)
					(fill
						(type none)
					)
				)
			)
			(symbol "R_100k_0402_10_1_1"
				(pin passive line
					(at 0 0 0)
					(length 0.635)
					(name "~"
						(effects
							(font
								(size 1.27 1.27)
							)
						)
					)
					(number "1"
						(effects
							(font
								(size 1.27 1.27)
							)
						)
					)
				)
				(pin passive line
					(at 5.08 0 180)
					(length 0.635)
					(name "~"
						(effects
							(font
								(size 1.27 1.27)
							)
						)
					)
					(number "2"
						(effects
							(font
								(size 1.27 1.27)
							)
						)
					)
				)
			)
		)
	(symbol "thunderbolt-gpu-adapter:R_100k_0402_11"
			(pin_numbers
				(hide yes)
			)
			(pin_names
				(hide yes)
			)
			(exclude_from_sim no)
			(in_bom yes)
			(on_board yes)
			(property "Reference" "R"
				(at 20.32 -5.08 0)
				(effects
					(font
						(size 1.27 1.27)
						(thickness 0.15)
					)
					(justify left bottom)
				)
			)
			(property "Value" "R_100k_0402_11"
				(at 20.32 -12.7 0)
				(effects
					(font
						(size 1.27 1.27)
						(thickness 0.15)
					)
					(justify left bottom)
					(hide yes)
				)
			)
			(property "Footprint" "thunderbolt-gpu-adapter-footprints:R_0402_1005Metric"
				(at 20.32 -15.24 0)
				(effects
					(font
						(size 1.27 1.27)
						(thickness 0.15)
					)
					(justify left bottom)
					(hide yes)
				)
			)
			(property "Datasheet" "https://www.bourns.com/docs/product-datasheets/cr.pdf"
				(at 20.32 -17.78 0)
				(effects
					(font
						(size 1.27 1.27)
						(thickness 0.15)
					)
					(justify left bottom)
					(hide yes)
				)
			)
			(property "Description" "100k resistor in 0402 package with 1% tolerance"
				(at 0 0 0)
				(effects
					(font
						(size 1.27 1.27)
					)
					(hide yes)
				)
			)
			(property "MPN" "CR0402-FX-1003GLF"
				(at 20.32 -20.32 0)
				(effects
					(font
						(size 1.27 1.27)
						(thickness 0.15)
					)
					(justify left bottom)
					(hide yes)
				)
			)
			(property "Manufacturer" "Bourns"
				(at 20.32 -22.86 0)
				(effects
					(font
						(size 1.27 1.27)
						(thickness 0.15)
					)
					(justify left bottom)
					(hide yes)
				)
			)
			(property "License" "Apache-2.0"
				(at 20.32 -25.4 0)
				(effects
					(font
						(size 1.27 1.27)
						(thickness 0.15)
					)
					(justify left bottom)
					(hide yes)
				)
			)
			(property "Author" "Antmicro"
				(at 20.32 -27.94 0)
				(effects
					(font
						(size 1.27 1.27)
						(thickness 0.15)
					)
					(justify left bottom)
					(hide yes)
				)
			)
			(property "Val" "100k"
				(at 20.32 -7.62 0)
				(effects
					(font
						(size 1.27 1.27)
						(thickness 0.15)
					)
					(justify left bottom)
				)
			)
			(property "Tolerance" "1%"
				(at 20.32 -10.16 0)
				(effects
					(font
						(size 1.27 1.27)
					)
					(justify left bottom)
					(hide yes)
				)
			)
			(symbol "R_100k_0402_11_0_1"
				(rectangle
					(start 0.635 0.889)
					(end 4.445 -0.889)
					(stroke
						(width 0.254)
						(type default)
					)
					(fill
						(type none)
					)
				)
			)
			(symbol "R_100k_0402_11_1_1"
				(pin passive line
					(at 0 0 0)
					(length 0.635)
					(name "~"
						(effects
							(font
								(size 1.27 1.27)
							)
						)
					)
					(number "1"
						(effects
							(font
								(size 1.27 1.27)
							)
						)
					)
				)
				(pin passive line
					(at 5.08 0 180)
					(length 0.635)
					(name "~"
						(effects
							(font
								(size 1.27 1.27)
							)
						)
					)
					(number "2"
						(effects
							(font
								(size 1.27 1.27)
							)
						)
					)
				)
			)
		)
	(symbol "thunderbolt-gpu-adapter:R_100k_0402_12"
			(pin_numbers
				(hide yes)
			)
			(pin_names
				(hide yes)
			)
			(exclude_from_sim no)
			(in_bom yes)
			(on_board yes)
			(property "Reference" "R"
				(at 20.32 -5.08 0)
				(effects
					(font
						(size 1.27 1.27)
						(thickness 0.15)
					)
					(justify left bottom)
				)
			)
			(property "Value" "R_100k_0402_12"
				(at 20.32 -12.7 0)
				(effects
					(font
						(size 1.27 1.27)
						(thickness 0.15)
					)
					(justify left bottom)
					(hide yes)
				)
			)
			(property "Footprint" "thunderbolt-gpu-adapter-footprints:R_0402_1005Metric"
				(at 20.32 -15.24 0)
				(effects
					(font
						(size 1.27 1.27)
						(thickness 0.15)
					)
					(justify left bottom)
					(hide yes)
				)
			)
			(property "Datasheet" "https://www.bourns.com/docs/product-datasheets/cr.pdf"
				(at 20.32 -17.78 0)
				(effects
					(font
						(size 1.27 1.27)
						(thickness 0.15)
					)
					(justify left bottom)
					(hide yes)
				)
			)
			(property "Description" "100k resistor in 0402 package with 1% tolerance"
				(at 0 0 0)
				(effects
					(font
						(size 1.27 1.27)
					)
					(hide yes)
				)
			)
			(property "MPN" "CR0402-FX-1003GLF"
				(at 20.32 -20.32 0)
				(effects
					(font
						(size 1.27 1.27)
						(thickness 0.15)
					)
					(justify left bottom)
					(hide yes)
				)
			)
			(property "Manufacturer" "Bourns"
				(at 20.32 -22.86 0)
				(effects
					(font
						(size 1.27 1.27)
						(thickness 0.15)
					)
					(justify left bottom)
					(hide yes)
				)
			)
			(property "License" "Apache-2.0"
				(at 20.32 -25.4 0)
				(effects
					(font
						(size 1.27 1.27)
						(thickness 0.15)
					)
					(justify left bottom)
					(hide yes)
				)
			)
			(property "Author" "Antmicro"
				(at 20.32 -27.94 0)
				(effects
					(font
						(size 1.27 1.27)
						(thickness 0.15)
					)
					(justify left bottom)
					(hide yes)
				)
			)
			(property "Val" "100k"
				(at 20.32 -7.62 0)
				(effects
					(font
						(size 1.27 1.27)
						(thickness 0.15)
					)
					(justify left bottom)
				)
			)
			(property "Tolerance" "1%"
				(at 20.32 -10.16 0)
				(effects
					(font
						(size 1.27 1.27)
					)
					(justify left bottom)
					(hide yes)
				)
			)
			(symbol "R_100k_0402_12_0_1"
				(rectangle
					(start 0.635 0.889)
					(end 4.445 -0.889)
					(stroke
						(width 0.254)
						(type default)
					)
					(fill
						(type none)
					)
				)
			)
			(symbol "R_100k_0402_12_1_1"
				(pin passive line
					(at 0 0 0)
					(length 0.635)
					(name "~"
						(effects
							(font
								(size 1.27 1.27)
							)
						)
					)
					(number "1"
						(effects
							(font
								(size 1.27 1.27)
							)
						)
					)
				)
				(pin passive line
					(at 5.08 0 180)
					(length 0.635)
					(name "~"
						(effects
							(font
								(size 1.27 1.27)
							)
						)
					)
					(number "2"
						(effects
							(font
								(size 1.27 1.27)
							)
						)
					)
				)
			)
		)
	(symbol "thunderbolt-gpu-adapter:R_10k_0402_10"
			(pin_numbers
				(hide yes)
			)
			(pin_names
				(hide yes)
			)
			(exclude_from_sim no)
			(in_bom yes)
			(on_board yes)
			(property "Reference" "R"
				(at 20.32 -5.08 0)
				(effects
					(font
						(size 1.27 1.27)
						(thickness 0.15)
					)
					(justify left bottom)
				)
			)
			(property "Value" "R_10k_0402_10"
				(at 20.32 -12.7 0)
				(effects
					(font
						(size 1.27 1.27)
						(thickness 0.15)
					)
					(justify left bottom)
					(hide yes)
				)
			)
			(property "Footprint" "thunderbolt-gpu-adapter-footprints:R_0402_1005Metric"
				(at 20.32 -15.24 0)
				(effects
					(font
						(size 1.27 1.27)
						(thickness 0.15)
					)
					(justify left bottom)
					(hide yes)
				)
			)
			(property "Datasheet" "https://www.bourns.com/docs/product-datasheets/cr.pdf"
				(at 20.32 -17.78 0)
				(effects
					(font
						(size 1.27 1.27)
						(thickness 0.15)
					)
					(justify left bottom)
					(hide yes)
				)
			)
			(property "Description" "10k resistor in 0402 package with 1% tolerance"
				(at 0 0 0)
				(effects
					(font
						(size 1.27 1.27)
					)
					(hide yes)
				)
			)
			(property "MPN" "CR0402-FX-1002GLF"
				(at 20.32 -20.32 0)
				(effects
					(font
						(size 1.27 1.27)
						(thickness 0.15)
					)
					(justify left bottom)
					(hide yes)
				)
			)
			(property "Manufacturer" "Bourns"
				(at 20.32 -22.86 0)
				(effects
					(font
						(size 1.27 1.27)
						(thickness 0.15)
					)
					(justify left bottom)
					(hide yes)
				)
			)
			(property "License" "Apache-2.0"
				(at 20.32 -25.4 0)
				(effects
					(font
						(size 1.27 1.27)
						(thickness 0.15)
					)
					(justify left bottom)
					(hide yes)
				)
			)
			(property "Author" "Antmicro"
				(at 20.32 -27.94 0)
				(effects
					(font
						(size 1.27 1.27)
						(thickness 0.15)
					)
					(justify left bottom)
					(hide yes)
				)
			)
			(property "Val" "10k"
				(at 20.32 -7.62 0)
				(effects
					(font
						(size 1.27 1.27)
						(thickness 0.15)
					)
					(justify left bottom)
				)
			)
			(property "Tolerance" "1%"
				(at 20.32 -10.16 0)
				(effects
					(font
						(size 1.27 1.27)
					)
					(justify left bottom)
					(hide yes)
				)
			)
			(symbol "R_10k_0402_10_0_1"
				(rectangle
					(start 0.635 0.889)
					(end 4.445 -0.889)
					(stroke
						(width 0.254)
						(type default)
					)
					(fill
						(type none)
					)
				)
			)
			(symbol "R_10k_0402_10_1_1"
				(pin passive line
					(at 0 0 0)
					(length 0.635)
					(name "~"
						(effects
							(font
								(size 1.27 1.27)
							)
						)
					)
					(number "1"
						(effects
							(font
								(size 1.27 1.27)
							)
						)
					)
				)
				(pin passive line
					(at 5.08 0 180)
					(length 0.635)
					(name "~"
						(effects
							(font
								(size 1.27 1.27)
							)
						)
					)
					(number "2"
						(effects
							(font
								(size 1.27 1.27)
							)
						)
					)
				)
			)
		)
	(symbol "thunderbolt-gpu-adapter:R_10k_0402_11"
			(pin_numbers
				(hide yes)
			)
			(pin_names
				(hide yes)
			)
			(exclude_from_sim no)
			(in_bom yes)
			(on_board yes)
			(property "Reference" "R"
				(at 20.32 -5.08 0)
				(effects
					(font
						(size 1.27 1.27)
						(thickness 0.15)
					)
					(justify left bottom)
				)
			)
			(property "Value" "R_10k_0402_11"
				(at 20.32 -12.7 0)
				(effects
					(font
						(size 1.27 1.27)
						(thickness 0.15)
					)
					(justify left bottom)
					(hide yes)
				)
			)
			(property "Footprint" "thunderbolt-gpu-adapter-footprints:R_0402_1005Metric"
				(at 20.32 -15.24 0)
				(effects
					(font
						(size 1.27 1.27)
						(thickness 0.15)
					)
					(justify left bottom)
					(hide yes)
				)
			)
			(property "Datasheet" "https://www.bourns.com/docs/product-datasheets/cr.pdf"
				(at 20.32 -17.78 0)
				(effects
					(font
						(size 1.27 1.27)
						(thickness 0.15)
					)
					(justify left bottom)
					(hide yes)
				)
			)
			(property "Description" "10k resistor in 0402 package with 1% tolerance"
				(at 0 0 0)
				(effects
					(font
						(size 1.27 1.27)
					)
					(hide yes)
				)
			)
			(property "MPN" "CR0402-FX-1002GLF"
				(at 20.32 -20.32 0)
				(effects
					(font
						(size 1.27 1.27)
						(thickness 0.15)
					)
					(justify left bottom)
					(hide yes)
				)
			)
			(property "Manufacturer" "Bourns"
				(at 20.32 -22.86 0)
				(effects
					(font
						(size 1.27 1.27)
						(thickness 0.15)
					)
					(justify left bottom)
					(hide yes)
				)
			)
			(property "License" "Apache-2.0"
				(at 20.32 -25.4 0)
				(effects
					(font
						(size 1.27 1.27)
						(thickness 0.15)
					)
					(justify left bottom)
					(hide yes)
				)
			)
			(property "Author" "Antmicro"
				(at 20.32 -27.94 0)
				(effects
					(font
						(size 1.27 1.27)
						(thickness 0.15)
					)
					(justify left bottom)
					(hide yes)
				)
			)
			(property "Val" "10k"
				(at 20.32 -7.62 0)
				(effects
					(font
						(size 1.27 1.27)
						(thickness 0.15)
					)
					(justify left bottom)
				)
			)
			(property "Tolerance" "1%"
				(at 20.32 -10.16 0)
				(effects
					(font
						(size 1.27 1.27)
					)
					(justify left bottom)
					(hide yes)
				)
			)
			(symbol "R_10k_0402_11_0_1"
				(rectangle
					(start 0.635 0.889)
					(end 4.445 -0.889)
					(stroke
						(width 0.254)
						(type default)
					)
					(fill
						(type none)
					)
				)
			)
			(symbol "R_10k_0402_11_1_1"
				(pin passive line
					(at 0 0 0)
					(length 0.635)
					(name "~"
						(effects
							(font
								(size 1.27 1.27)
							)
						)
					)
					(number "1"
						(effects
							(font
								(size 1.27 1.27)
							)
						)
					)
				)
				(pin passive line
					(at 5.08 0 180)
					(length 0.635)
					(name "~"
						(effects
							(font
								(size 1.27 1.27)
							)
						)
					)
					(number "2"
						(effects
							(font
								(size 1.27 1.27)
							)
						)
					)
				)
			)
		)
	(symbol "thunderbolt-gpu-adapter:R_10k_0402_12"
			(pin_numbers
				(hide yes)
			)
			(pin_names
				(hide yes)
			)
			(exclude_from_sim no)
			(in_bom yes)
			(on_board yes)
			(property "Reference" "R"
				(at 20.32 -5.08 0)
				(effects
					(font
						(size 1.27 1.27)
						(thickness 0.15)
					)
					(justify left bottom)
				)
			)
			(property "Value" "R_10k_0402_12"
				(at 20.32 -12.7 0)
				(effects
					(font
						(size 1.27 1.27)
						(thickness 0.15)
					)
					(justify left bottom)
					(hide yes)
				)
			)
			(property "Footprint" "thunderbolt-gpu-adapter-footprints:R_0402_1005Metric"
				(at 20.32 -15.24 0)
				(effects
					(font
						(size 1.27 1.27)
						(thickness 0.15)
					)
					(justify left bottom)
					(hide yes)
				)
			)
			(property "Datasheet" "https://www.bourns.com/docs/product-datasheets/cr.pdf"
				(at 20.32 -17.78 0)
				(effects
					(font
						(size 1.27 1.27)
						(thickness 0.15)
					)
					(justify left bottom)
					(hide yes)
				)
			)
			(property "Description" "10k resistor in 0402 package with 1% tolerance"
				(at 0 0 0)
				(effects
					(font
						(size 1.27 1.27)
					)
					(hide yes)
				)
			)
			(property "MPN" "CR0402-FX-1002GLF"
				(at 20.32 -20.32 0)
				(effects
					(font
						(size 1.27 1.27)
						(thickness 0.15)
					)
					(justify left bottom)
					(hide yes)
				)
			)
			(property "Manufacturer" "Bourns"
				(at 20.32 -22.86 0)
				(effects
					(font
						(size 1.27 1.27)
						(thickness 0.15)
					)
					(justify left bottom)
					(hide yes)
				)
			)
			(property "License" "Apache-2.0"
				(at 20.32 -25.4 0)
				(effects
					(font
						(size 1.27 1.27)
						(thickness 0.15)
					)
					(justify left bottom)
					(hide yes)
				)
			)
			(property "Author" "Antmicro"
				(at 20.32 -27.94 0)
				(effects
					(font
						(size 1.27 1.27)
						(thickness 0.15)
					)
					(justify left bottom)
					(hide yes)
				)
			)
			(property "Val" "10k"
				(at 20.32 -7.62 0)
				(effects
					(font
						(size 1.27 1.27)
						(thickness 0.15)
					)
					(justify left bottom)
				)
			)
			(property "Tolerance" "1%"
				(at 20.32 -10.16 0)
				(effects
					(font
						(size 1.27 1.27)
					)
					(justify left bottom)
					(hide yes)
				)
			)
			(symbol "R_10k_0402_12_0_1"
				(rectangle
					(start 0.635 0.889)
					(end 4.445 -0.889)
					(stroke
						(width 0.254)
						(type default)
					)
					(fill
						(type none)
					)
				)
			)
			(symbol "R_10k_0402_12_1_1"
				(pin passive line
					(at 0 0 0)
					(length 0.635)
					(name "~"
						(effects
							(font
								(size 1.27 1.27)
							)
						)
					)
					(number "1"
						(effects
							(font
								(size 1.27 1.27)
							)
						)
					)
				)
				(pin passive line
					(at 5.08 0 180)
					(length 0.635)
					(name "~"
						(effects
							(font
								(size 1.27 1.27)
							)
						)
					)
					(number "2"
						(effects
							(font
								(size 1.27 1.27)
							)
						)
					)
				)
			)
		)
	(symbol "thunderbolt-gpu-adapter:R_10k_0402_13"
			(pin_numbers
				(hide yes)
			)
			(pin_names
				(hide yes)
			)
			(exclude_from_sim no)
			(in_bom yes)
			(on_board yes)
			(property "Reference" "R"
				(at 20.32 -5.08 0)
				(effects
					(font
						(size 1.27 1.27)
						(thickness 0.15)
					)
					(justify left bottom)
				)
			)
			(property "Value" "R_10k_0402_13"
				(at 20.32 -12.7 0)
				(effects
					(font
						(size 1.27 1.27)
						(thickness 0.15)
					)
					(justify left bottom)
					(hide yes)
				)
			)
			(property "Footprint" "thunderbolt-gpu-adapter-footprints:R_0402_1005Metric"
				(at 20.32 -15.24 0)
				(effects
					(font
						(size 1.27 1.27)
						(thickness 0.15)
					)
					(justify left bottom)
					(hide yes)
				)
			)
			(property "Datasheet" "https://www.bourns.com/docs/product-datasheets/cr.pdf"
				(at 20.32 -17.78 0)
				(effects
					(font
						(size 1.27 1.27)
						(thickness 0.15)
					)
					(justify left bottom)
					(hide yes)
				)
			)
			(property "Description" "10k resistor in 0402 package with 1% tolerance"
				(at 0 0 0)
				(effects
					(font
						(size 1.27 1.27)
					)
					(hide yes)
				)
			)
			(property "MPN" "CR0402-FX-1002GLF"
				(at 20.32 -20.32 0)
				(effects
					(font
						(size 1.27 1.27)
						(thickness 0.15)
					)
					(justify left bottom)
					(hide yes)
				)
			)
			(property "Manufacturer" "Bourns"
				(at 20.32 -22.86 0)
				(effects
					(font
						(size 1.27 1.27)
						(thickness 0.15)
					)
					(justify left bottom)
					(hide yes)
				)
			)
			(property "License" "Apache-2.0"
				(at 20.32 -25.4 0)
				(effects
					(font
						(size 1.27 1.27)
						(thickness 0.15)
					)
					(justify left bottom)
					(hide yes)
				)
			)
			(property "Author" "Antmicro"
				(at 20.32 -27.94 0)
				(effects
					(font
						(size 1.27 1.27)
						(thickness 0.15)
					)
					(justify left bottom)
					(hide yes)
				)
			)
			(property "Val" "10k"
				(at 20.32 -7.62 0)
				(effects
					(font
						(size 1.27 1.27)
						(thickness 0.15)
					)
					(justify left bottom)
				)
			)
			(property "Tolerance" "1%"
				(at 20.32 -10.16 0)
				(effects
					(font
						(size 1.27 1.27)
					)
					(justify left bottom)
					(hide yes)
				)
			)
			(symbol "R_10k_0402_13_0_1"
				(rectangle
					(start 0.635 0.889)
					(end 4.445 -0.889)
					(stroke
						(width 0.254)
						(type default)
					)
					(fill
						(type none)
					)
				)
			)
			(symbol "R_10k_0402_13_1_1"
				(pin passive line
					(at 0 0 0)
					(length 0.635)
					(name "~"
						(effects
							(font
								(size 1.27 1.27)
							)
						)
					)
					(number "1"
						(effects
							(font
								(size 1.27 1.27)
							)
						)
					)
				)
				(pin passive line
					(at 5.08 0 180)
					(length 0.635)
					(name "~"
						(effects
							(font
								(size 1.27 1.27)
							)
						)
					)
					(number "2"
						(effects
							(font
								(size 1.27 1.27)
							)
						)
					)
				)
			)
		)
)
